(kicad_pcb
	(version 20241229)
	(generator "pcbnew")
	(generator_version "9.0")
	(general
		(thickness 1.599998)
		(legacy_teardrops no)
	)
	(paper "A4")
	(title_block
		(title "Artix - Datacenter Secure Control Module (DC-SCM)")
		(date "2024-11-06")
		(rev "1.1.3")
	)
	(layers
		(0 "F.Cu" signal)
		(4 "In1.Cu" signal)
		(6 "In2.Cu" signal)
		(8 "In3.Cu" signal)
		(10 "In4.Cu" signal)
		(12 "In5.Cu" signal)
		(14 "In6.Cu" signal)
		(2 "B.Cu" signal)
		(9 "F.Adhes" user "F.Adhesive")
		(11 "B.Adhes" user "B.Adhesive")
		(13 "F.Paste" user)
		(15 "B.Paste" user)
		(5 "F.SilkS" user "F.Silkscreen")
		(7 "B.SilkS" user "B.Silkscreen")
		(1 "F.Mask" user)
		(3 "B.Mask" user)
		(17 "Dwgs.User" user "User.Drawings")
		(19 "Cmts.User" user "User.Comments")
		(21 "Eco1.User" user "User.Eco1")
		(23 "Eco2.User" user "User.Eco2")
		(25 "Edge.Cuts" user)
		(27 "Margin" user)
		(31 "F.CrtYd" user "F.Courtyard")
		(29 "B.CrtYd" user "B.Courtyard")
		(35 "F.Fab" user)
		(33 "B.Fab" user)
	)
	(setup
		(stackup
			(layer "F.SilkS"
				(type "Top Silk Screen")
			)
			(layer "F.Paste"
				(type "Top Solder Paste")
			)
			(layer "F.Mask"
				(type "Top Solder Mask")
				(thickness 0.01)
			)
			(layer "F.Cu"
				(type "copper")
				(thickness 0.035)
			)
			(layer "dielectric 1"
				(type "core")
				(thickness 0.185714)
				(material "FR4")
				(epsilon_r 4.5)
				(loss_tangent 0.02)
			)
			(layer "In1.Cu"
				(type "copper")
				(thickness 0.035)
			)
			(layer "dielectric 2"
				(type "prepreg")
				(thickness 0.185714)
				(material "FR4")
				(epsilon_r 4.5)
				(loss_tangent 0.02)
			)
			(layer "In2.Cu"
				(type "copper")
				(thickness 0.035)
			)
			(layer "dielectric 3"
				(type "core")
				(thickness 0.185714)
				(material "FR4")
				(epsilon_r 4.5)
				(loss_tangent 0.02)
			)
			(layer "In3.Cu"
				(type "copper")
				(thickness 0.035)
			)
			(layer "dielectric 4"
				(type "prepreg")
				(thickness 0.185714)
				(material "FR4")
				(epsilon_r 4.5)
				(loss_tangent 0.02)
			)
			(layer "In4.Cu"
				(type "copper")
				(thickness 0.035)
			)
			(layer "dielectric 5"
				(type "core")
				(thickness 0.185714)
				(material "FR4")
				(epsilon_r 4.5)
				(loss_tangent 0.02)
			)
			(layer "In5.Cu"
				(type "copper")
				(thickness 0.035)
			)
			(layer "dielectric 6"
				(type "prepreg")
				(thickness 0.185714)
				(material "FR4")
				(epsilon_r 4.5)
				(loss_tangent 0.02)
			)
			(layer "In6.Cu"
				(type "copper")
				(thickness 0.035)
			)
			(layer "dielectric 7"
				(type "core")
				(thickness 0.185714)
				(material "FR4")
				(epsilon_r 4.5)
				(loss_tangent 0.02)
			)
			(layer "B.Cu"
				(type "copper")
				(thickness 0.035)
			)
			(layer "B.Mask"
				(type "Bottom Solder Mask")
				(thickness 0.01)
			)
			(layer "B.Paste"
				(type "Bottom Solder Paste")
			)
			(layer "B.SilkS"
				(type "Bottom Silk Screen")
			)
			(copper_finish "None")
			(dielectric_constraints no)
		)
		(pad_to_mask_clearance 0)
		(allow_soldermask_bridges_in_footprints no)
		(tenting front back)
		(aux_axis_origin 60.1 179.3)
		(pcbplotparams
			(layerselection 0x00000000_00000000_55555555_5755f5ff)
			(plot_on_all_layers_selection 0x00000000_00000000_00000000_00000000)
			(disableapertmacros no)
			(usegerberextensions no)
			(usegerberattributes yes)
			(usegerberadvancedattributes yes)
			(creategerberjobfile yes)
			(dashed_line_dash_ratio 12.000000)
			(dashed_line_gap_ratio 3.000000)
			(svgprecision 6)
			(plotframeref no)
			(mode 1)
			(useauxorigin no)
			(hpglpennumber 1)
			(hpglpenspeed 20)
			(hpglpendiameter 15.000000)
			(pdf_front_fp_property_popups yes)
			(pdf_back_fp_property_popups yes)
			(pdf_metadata yes)
			(pdf_single_document no)
			(dxfpolygonmode yes)
			(dxfimperialunits yes)
			(dxfusepcbnewfont yes)
			(psnegative no)
			(psa4output no)
			(plot_black_and_white yes)
			(sketchpadsonfab no)
			(plotpadnumbers no)
			(hidednponfab no)
			(sketchdnponfab yes)
			(crossoutdnponfab yes)
			(subtractmaskfromsilk no)
			(outputformat 1)
			(mirror no)
			(drillshape 1)
			(scaleselection 1)
			(outputdirectory "")
		)
	)
	(net 0 "")
	(net 1 "GND")
	(net 2 "VCC3V3")
	(net 3 "VCC1V35")
	(net 4 "VCC5V0")
	(net 5 "VCC1V8")
	(net 6 "VCC1V0")
	(net 7 "/Interfaces/1V0_EN")
	(net 8 "Net-(D3-C)")
	(net 9 "Net-(U8-REFIN)")
	(net 10 "Net-(U16-FB)")
	(net 11 "Net-(U18-VDDA1.8)")
	(net 12 "Net-(U17-VDDA1.8)")
	(net 13 "JTAG_TDI")
	(net 14 "JTAG_TDO")
	(net 15 "JTAG_TCK")
	(net 16 "JTAG_TMS")
	(net 17 "I2C[5]_SDA")
	(net 18 "I2C[5]_SCL")
	(net 19 "I2C[3]_SCL")
	(net 20 "I2C[7]_SCL")
	(net 21 "I2C[3]_SDA")
	(net 22 "I2C[1]_SCL")
	(net 23 "I2C[1]_SDA")
	(net 24 "I2C[7]_SDA")
	(net 25 "I2C[2]_SDA")
	(net 26 "I2C[2]_SCL")
	(net 27 "I2C[4]_SDA")
	(net 28 "I2C[6]_SCL")
	(net 29 "I2C[6]_SDA")
	(net 30 "I2C[4]_SCL")
	(net 31 "I2C[0]_SCL")
	(net 32 "I2C[0]_SDA")
	(net 33 "UART1_SCM_RX")
	(net 34 "I2C[11]_SCL")
	(net 35 "UART0_SCM_TX")
	(net 36 "I2C[11]_SDA")
	(net 37 "I2C[9]_SCL")
	(net 38 "I2C[9]_SDA")
	(net 39 "UART0_SCM_RX")
	(net 40 "UART1_SCM_TX")
	(net 41 "I2C[10]_SDA")
	(net 42 "I2C[10]_SCL")
	(net 43 "I2C[12]_SDA")
	(net 44 "I2C[12]_SCL")
	(net 45 "I2C[8]_SCL")
	(net 46 "I2C[8]_SDA")
	(net 47 "I3C[2]_SCL")
	(net 48 "I3C[0]_SDA")
	(net 49 "I3C[0]_SCL")
	(net 50 "I3C[2]_SDA")
	(net 51 "I3C[1]_SDA")
	(net 52 "I3C[1]_SCL")
	(net 53 "I3C[3]_SDA")
	(net 54 "I3C[3]_SCL")
	(net 55 "SPI0_CS_N")
	(net 56 "SPI0_CLK")
	(net 57 "SPI0_MOSI")
	(net 58 "SPI0_MISO")
	(net 59 "P12V_AUX")
	(net 60 "Net-(C101-Pad2)")
	(net 61 "ESPI_CLK")
	(net 62 "ESPI_CS0_N")
	(net 63 "ESPI_ALERT_N")
	(net 64 "ESPI_RESET_N")
	(net 65 "ESPI_IO0")
	(net 66 "ESPI_IO1")
	(net 67 "ESPI_IO2")
	(net 68 "ESPI_IO3")
	(net 69 "ESPI_CS1_N")
	(net 70 "QSPI0_CLK")
	(net 71 "QSPI0_CS0_N")
	(net 72 "QSPI0_D0")
	(net 73 "QSPI0_D1")
	(net 74 "QSPI0_D2")
	(net 75 "QSPI0_D3")
	(net 76 "NCSI_CLK")
	(net 77 "NCSI_CRS_DV")
	(net 78 "NCSI_TXEN")
	(net 79 "NCSI_TXD0")
	(net 80 "NCSI_TXD1")
	(net 81 "NCSI_RXER")
	(net 82 "NCSI_RXD0")
	(net 83 "NCSI_RXD1")
	(net 84 "PECI_BMC")
	(net 85 "PVCCIO_PECI")
	(net 86 "SGPIO0_DO")
	(net 87 "SGPIO0_CLK")
	(net 88 "SGPIO0_DI")
	(net 89 "SGPIO0_LD")
	(net 90 "SGPIO1_DO")
	(net 91 "RSVD2")
	(net 92 "SGPIO1_DI")
	(net 93 "SGPIO1_LD")
	(net 94 "SGPIO_RESET_N")
	(net 95 "SGPIO_INTR_N")
	(net 96 "QSPI0_CS1_N")
	(net 97 "QSPI1_CLK")
	(net 98 "QSPI1_CS0_N")
	(net 99 "QSPI1_D0")
	(net 100 "QSPI1_D1")
	(net 101 "QSPI1_D2")
	(net 102 "QSPI1_D3")
	(net 103 "Net-(U9-TADJ)")
	(net 104 "/Power supply/VCC12V")
	(net 105 "Net-(C20-Pad2)")
	(net 106 "Net-(U25-SS{slash}TR)")
	(net 107 "Net-(U25-COMP)")
	(net 108 "Net-(C177-Pad2)")
	(net 109 "Net-(C63-Pad1)")
	(net 110 "Net-(U25-BOOT)")
	(net 111 "Net-(C68-Pad2)")
	(net 112 "Net-(D1-A)")
	(net 113 "Net-(U10-FB)")
	(net 114 "Net-(C72-Pad2)")
	(net 115 "/Interfaces/FT_VPHY")
	(net 116 "/Interfaces/FT_VPLL")
	(net 117 "Net-(U11-FB)")
	(net 118 "PRSNT1_N")
	(net 119 "QSPIB_CLK")
	(net 120 "QSPIB1_D0")
	(net 121 "QSPIB1_D1")
	(net 122 "QSPIB1_D2")
	(net 123 "QSPIB1_D3")
	(net 124 "QSPIB1_CS_N")
	(net 125 "QSPIB2_D0")
	(net 126 "QSPIB2_D1")
	(net 127 "QSPIB2_D2")
	(net 128 "QSPIB2_D3")
	(net 129 "QSPIB2_CS_N")
	(net 130 "QSPIA_CLK")
	(net 131 "QSPIA1_D0")
	(net 132 "QSPIA1_D1")
	(net 133 "QSPIA1_D2")
	(net 134 "QSPIA1_D3")
	(net 135 "QSPIA1_CS_N")
	(net 136 "QSPIA2_D0")
	(net 137 "QSPIA2_D1")
	(net 138 "QSPIA2_D2")
	(net 139 "QSPIA2_D3")
	(net 140 "QSPIA2_CS_N")
	(net 141 "ETH_MDC")
	(net 142 "ETH_MDIO")
	(net 143 "/DDR3/DDR3_VTT")
	(net 144 "DDR3_A14")
	(net 145 "DDR3_A8")
	(net 146 "DDR3_A6")
	(net 147 "DDR3_A2")
	(net 148 "DDR3_A7")
	(net 149 "DDR3_A9")
	(net 150 "DDR3_A11")
	(net 151 "DDR3_A13")
	(net 152 "DDR3_BA2")
	(net 153 "DDR3_WE")
	(net 154 "DDR3_A10")
	(net 155 "DDR3_BA1")
	(net 156 "DDR3_A12")
	(net 157 "DDR3_A1")
	(net 158 "DDR3_A0")
	(net 159 "DDR3_A4")
	(net 160 "DDR3_CKE")
	(net 161 "DDR3_ODT")
	(net 162 "DDR3_RAS")
	(net 163 "DDR3_CS")
	(net 164 "DDR3_BA0")
	(net 165 "DDR3_A3")
	(net 166 "DDR3_CAS")
	(net 167 "DDR3_A5")
	(net 168 "I3C[0]_SDA_3V3")
	(net 169 "I3C[0]_SCL_3V3")
	(net 170 "I3C[1]_SDA_3V3")
	(net 171 "I3C[1]_SCL_3V3")
	(net 172 "I3C[2]_SDA_3V3")
	(net 173 "I3C[2]_SCL_3V3")
	(net 174 "I3C[3]_SDA_3V3")
	(net 175 "I3C[3]_SCL_3V3")
	(net 176 "DDR3_DM0")
	(net 177 "DDR3_DQ15")
	(net 178 "DDR3_DQ13")
	(net 179 "DDR3_DQ14")
	(net 180 "DDR3_DQ9")
	(net 181 "DDR3_DM1")
	(net 182 "DDR3_DQ12")
	(net 183 "DDR3_DQ10")
	(net 184 "DDR3_DQ11")
	(net 185 "DDR3_DQ7")
	(net 186 "DDR3_DQ5")
	(net 187 "DDR3_DQ2")
	(net 188 "DDR3_DQ1")
	(net 189 "DDR3_DQ4")
	(net 190 "DDR3_DQ3")
	(net 191 "DDR3_RESET")
	(net 192 "DDR3_DQ6")
	(net 193 "DDR3_DQ8")
	(net 194 "DDR3_DQ0")
	(net 195 "Net-(U12-FB)")
	(net 196 "Net-(U13-FB)")
	(net 197 "Net-(U19-OSCI)")
	(net 198 "Net-(U19-OSCO)")
	(net 199 "Net-(U20-XO)")
	(net 200 "Net-(U1-VDDIM)")
	(net 201 "Net-(U20-XI)")
	(net 202 "Net-(J1-TRCT1)")
	(net 203 "Net-(J1-TRCT2)")
	(net 204 "Net-(J1-TRCT3)")
	(net 205 "Net-(R70-Pad2)")
	(net 206 "Net-(J1-TRCT4)")
	(net 207 "Net-(D4-C)")
	(net 208 "Net-(D4-A)")
	(net 209 "unconnected-(D2-Pad12)")
	(net 210 "unconnected-(D2-Pad11)")
	(net 211 "DDR3_VREF")
	(net 212 "/Interfaces/DBG_USB_D_P")
	(net 213 "/Interfaces/DBG_USB_D_N")
	(net 214 "Net-(D5-C)")
	(net 215 "Net-(D5-A)")
	(net 216 "Net-(D6-C)")
	(net 217 "Net-(D6-A)")
	(net 218 "Net-(D7-C)")
	(net 219 "Net-(D7-A)")
	(net 220 "DONE")
	(net 221 "PROGRAM")
	(net 222 "INIT")
	(net 223 "Net-(D8-C)")
	(net 224 "Net-(D8-A)")
	(net 225 "Net-(D9-C)")
	(net 226 "Net-(U25-RT{slash}CLK)")
	(net 227 "Net-(U25-FB)")
	(net 228 "Net-(U25-EN)")
	(net 229 "unconnected-(J2-NC-Pad6)")
	(net 230 "unconnected-(J2-NC-Pad8)")
	(net 231 "unconnected-(J2-NC-Pad20)")
	(net 232 "unconnected-(J2-NC-Pad22)")
	(net 233 "unconnected-(J2-NC-Pad24)")
	(net 234 "unconnected-(J2-NC-Pad26)")
	(net 235 "unconnected-(J2-NC-Pad28)")
	(net 236 "unconnected-(J2-NC-Pad30)")
	(net 237 "unconnected-(J2-NC-Pad32)")
	(net 238 "unconnected-(J2-NC-Pad34)")
	(net 239 "unconnected-(J2-NC-Pad36)")
	(net 240 "/Interfaces/VBUS")
	(net 241 "unconnected-(J6-Pad14)")
	(net 242 "unconnected-(J6-Pad12)")
	(net 243 "/Edge connector/PRSNT0_N")
	(net 244 "/Edge connector/VIRTUAL_RESEAT")
	(net 245 "/Edge connector/IRQ_N")
	(net 246 "/Edge connector/SPARE0")
	(net 247 "/Edge connector/CHASI#")
	(net 248 "/Edge connector/RST_PLTRST_BUF_N")
	(net 249 "/Edge connector/SPARE1")
	(net 250 "/Edge connector/RoT_CPU_RST_N")
	(net 251 "/Edge connector/DBP_PRDY_N")
	(net 252 "/Edge connector/DBP_PREQ_N")
	(net 253 "/Edge connector/SYS_PWROK")
	(net 254 "/Edge connector/SYS_PWRBTN_N")
	(net 255 "/Edge connector/HPM_STBY_RST_N")
	(net 256 "/Edge connector/HPM_STBY_EN")
	(net 257 "/Edge connector/HPM_STBY_RDY")
	(net 258 "/Edge connector/HPM_FW_RECOVERY")
	(net 259 "/FPGA banks 34-35 & CFG/MODE2")
	(net 260 "/FPGA banks 13-16/PUDC_B")
	(net 261 "unconnected-(J2-NC-Pad38)")
	(net 262 "unconnected-(J2-SMB_CLK-Pad40)")
	(net 263 "unconnected-(J2-SMB_DATA-Pad42)")
	(net 264 "Net-(J2-ALERT)")
	(net 265 "unconnected-(J2-NC-Pad46)")
	(net 266 "unconnected-(J2-NC-Pad48)")
	(net 267 "/FPGA banks 34-35 & CFG/MODE0")
	(net 268 "/FPGA banks 34-35 & CFG/MODE1")
	(net 269 "Net-(J2-~{CLKREQ})")
	(net 270 "Net-(J2-~{PEWAKE})")
	(net 271 "unconnected-(J2-NC-Pad56)")
	(net 272 "unconnected-(J2-NC-Pad58)")
	(net 273 "unconnected-(J2-NC-Pad67)")
	(net 274 "Net-(C79-Pad2)")
	(net 275 "Net-(C80-Pad2)")
	(net 276 "Net-(C81-Pad2)")
	(net 277 "Net-(C82-Pad2)")
	(net 278 "unconnected-(J2-SUSCLK-Pad68)")
	(net 279 "Net-(D9-A)")
	(net 280 "unconnected-(J2-NC-Pad69)")
	(net 281 "Net-(D10-C)")
	(net 282 "Net-(J3-ID)")
	(net 283 "Net-(D10-A)")
	(net 284 "Net-(D11-C)")
	(net 285 "Net-(U10-SW)")
	(net 286 "Net-(D11-A)")
	(net 287 "3V0_BAT")
	(net 288 "Net-(U11-SW)")
	(net 289 "Net-(U12-SW)")
	(net 290 "Net-(U13-SW)")
	(net 291 "Net-(U16-SW)")
	(net 292 "/Power supply/1V8_PG")
	(net 293 "/Power supply/1V35_PG")
	(net 294 "/Power supply/2V5_PG")
	(net 295 "/Power supply/VCCINT_EN")
	(net 296 "/Power supply/VCCAUX_EN")
	(net 297 "/Power supply/VCCIO_EN")
	(net 298 "Net-(U19-REF)")
	(net 299 "Net-(U19-~{RESET})")
	(net 300 "Net-(U17-RBIAS)")
	(net 301 "ROT_RDY\\ROT_GPIO0")
	(net 302 "Net-(U17-VBUS)")
	(net 303 "Net-(U18-RBIAS)")
	(net 304 "Net-(U18-VBUS)")
	(net 305 "Net-(D12-C)")
	(net 306 "Net-(U1-CLK)")
	(net 307 "Net-(D12-A)")
	(net 308 "Net-(U17-REG_EN)")
	(net 309 "Net-(D13-C)")
	(net 310 "Net-(U18-REG_EN)")
	(net 311 "Net-(D13-A)")
	(net 312 "Net-(U21-EN)")
	(net 313 "Net-(D14-C)")
	(net 314 "Net-(U10-EN)")
	(net 315 "Net-(U11-EN)")
	(net 316 "USR_LED0")
	(net 317 "USR_LED1")
	(net 318 "USR_LED2")
	(net 319 "Net-(U12-EN)")
	(net 320 "ROT_QSPI_SCK")
	(net 321 "MMC_DAT0")
	(net 322 "MMC_DAT1")
	(net 323 "MMC_DAT2")
	(net 324 "MMC_DAT3")
	(net 325 "MMC_DAT4")
	(net 326 "MMC_DAT5")
	(net 327 "MMC_DAT6")
	(net 328 "MMC_DAT7")
	(net 329 "MMC_CMD")
	(net 330 "MMC_CLK")
	(net 331 "MMC_RSTN")
	(net 332 "ROT_QSPI_DQ2")
	(net 333 "ROT_QSPI_DQ3")
	(net 334 "Net-(U8-PGOOD)")
	(net 335 "ROT_QSPI_DQ0")
	(net 336 "ROT_QSPI_DQ1")
	(net 337 "Net-(U7-ZQ)")
	(net 338 "Net-(U22-EN)")
	(net 339 "VCC1V2")
	(net 340 "Net-(D14-A)")
	(net 341 "Net-(U8-EN)")
	(net 342 "Net-(U14D-CFGBVS_0)")
	(net 343 "Net-(U13-EN)")
	(net 344 "Net-(U14A-IO_L6P_T0_FCS_B_14)")
	(net 345 "Net-(U20-ISET)")
	(net 346 "Net-(U19-ADBUS0)")
	(net 347 "Net-(U16-EN)")
	(net 348 "Net-(U19-ADBUS1)")
	(net 349 "Net-(U19-ADBUS2)")
	(net 350 "ROT_QSPI_CS_B")
	(net 351 "PCIE_HPM_TX[0]_P")
	(net 352 "PCIE_HPM_TX[1]_P")
	(net 353 "PCIE_HPM_TX[0]_N")
	(net 354 "PCIE_HPM_TX[1]_N")
	(net 355 "PCIE_HPM_TX[2]_P")
	(net 356 "PCIE_HPM_TX[3]_P")
	(net 357 "PCIE_HPM_TX[2]_N")
	(net 358 "PCIE_HPM_TX[3]_N")
	(net 359 "PCIE_HPM_CLK_P")
	(net 360 "PCIE_HPM_CLK_N")
	(net 361 "PCIE_HPM_RX[0]_P")
	(net 362 "PCIE_HPM_RX[0]_N")
	(net 363 "PCIE_HPM_RX[1]_P")
	(net 364 "PCIE_HPM_RX[1]_N")
	(net 365 "PCIE_HPM_RX[2]_P")
	(net 366 "PCIE_HPM_RX[2]_N")
	(net 367 "PCIE_HPM_RX[3]_P")
	(net 368 "PCIE_HPM_RX[3]_N")
	(net 369 "/PCIe-connector/PCIE_HPM_TX0_C_P")
	(net 370 "/PCIe-connector/PCIE_HPM_TX1_C_P")
	(net 371 "/PCIe-connector/PCIE_HPM_TX0_C_N")
	(net 372 "/PCIe-connector/PCIE_HPM_TX1_C_N")
	(net 373 "/PCIe-connector/PCIE_HPM_TX2_C_P")
	(net 374 "/PCIe-connector/PCIE_HPM_TX3_C_P")
	(net 375 "/PCIe-connector/PCIE_HPM_TX2_C_N")
	(net 376 "/PCIe-connector/PCIE_HPM_TX3_C_N")
	(net 377 "PCIE_BMC_TX_N")
	(net 378 "PCIE_BMC_TX_P")
	(net 379 "PCIE_BMC_CLK_100_P")
	(net 380 "PCIE_BMC_CLK_100_N")
	(net 381 "PCIE_BMC_RX_P")
	(net 382 "PCIE_BMC_RX_N")
	(net 383 "USB2_D_P")
	(net 384 "USB2_D_N")
	(net 385 "USB1_D_P")
	(net 386 "USB1_D_N")
	(net 387 "HPM_FW_RECOVERY_R")
	(net 388 "HPM_STBY_RST_N_R")
	(net 389 "SYS_PWRBTN_N_R")
	(net 390 "SYS_PWROK_R")
	(net 391 "DBP_PREQ_N_R")
	(net 392 "DBP_PRDY_N_R")
	(net 393 "RST_PLTRST_BUF_N_R")
	(net 394 "SPARE1_R")
	(net 395 "RoT_CPU_RST_N_R")
	(net 396 "CHASI#_R")
	(net 397 "SPARE0_R")
	(net 398 "IRQ_N_R")
	(net 399 "Net-(U19-ADBUS3)")
	(net 400 "Net-(U19-CDBUS0)")
	(net 401 "Net-(U19-CDBUS1)")
	(net 402 "Net-(U1-DS)")
	(net 403 "Net-(U19-ADBUS5)")
	(net 404 "/Ethernet/AVDDL_PLL")
	(net 405 "/Ethernet/AVDDL")
	(net 406 "/Ethernet/AVDDH")
	(net 407 "RGMII_RXD0")
	(net 408 "RGMII_RXD1")
	(net 409 "RGMII_RXD2")
	(net 410 "RGMII_RXD3")
	(net 411 "RGMII_RX_DV")
	(net 412 "RGMII_RX_CLK")
	(net 413 "RGMII_REF_CLK")
	(net 414 "ETH_~{RESET}")
	(net 415 "/Ethernet/ETH_LED1")
	(net 416 "/Ethernet/ETH_LED2")
	(net 417 "unconnected-(U1-NC-PadA1)")
	(net 418 "unconnected-(U1-NC-PadA2)")
	(net 419 "unconnected-(U1-NC-PadA9)")
	(net 420 "ETH_INT_N")
	(net 421 "RGMII_TX_CLK")
	(net 422 "RGMII_TXD3")
	(net 423 "RGMII_TXD2")
	(net 424 "RGMII_TXD1")
	(net 425 "RGMII_TXD0")
	(net 426 "unconnected-(U1-NC-PadA10)")
	(net 427 "RGMII_TX_DV")
	(net 428 "/Ethernet/ETH4_N")
	(net 429 "/Ethernet/ETH4_P")
	(net 430 "/Ethernet/ETH3_N")
	(net 431 "/Ethernet/ETH3_P")
	(net 432 "/Ethernet/ETH2_N")
	(net 433 "/Ethernet/ETH2_P")
	(net 434 "/Ethernet/ETH1_N")
	(net 435 "/Ethernet/ETH1_P")
	(net 436 "unconnected-(U1-NC-PadB1)")
	(net 437 "unconnected-(U1-NC-PadB10)")
	(net 438 "unconnected-(U1-VSF1-PadD2)")
	(net 439 "unconnected-(U1-VSF2-PadD3)")
	(net 440 "unconnected-(U1-VSF3-PadD4)")
	(net 441 "unconnected-(U1-VSF4-PadD5)")
	(net 442 "ULPI1_RESET")
	(net 443 "unconnected-(U1-VSF5-PadD6)")
	(net 444 "ULPI1_NXT")
	(net 445 "ULPI1_DIR")
	(net 446 "ULPI1_STP")
	(net 447 "ULPI1_CLKOUT")
	(net 448 "ULPI1_DATA7")
	(net 449 "ULPI1_DATA6")
	(net 450 "ULPI1_DATA5")
	(net 451 "ULPI1_DATA4")
	(net 452 "ULPI1_DATA3")
	(net 453 "ULPI1_DATA2")
	(net 454 "ULPI1_DATA1")
	(net 455 "ULPI1_DATA0")
	(net 456 "unconnected-(U1-VSF6-PadD7)")
	(net 457 "ULPI2_RESET")
	(net 458 "ULPI2_NXT")
	(net 459 "ULPI2_DIR")
	(net 460 "ULPI2_STP")
	(net 461 "ULPI2_CLKOUT")
	(net 462 "ULPI2_DATA7")
	(net 463 "ULPI2_DATA6")
	(net 464 "ULPI2_DATA5")
	(net 465 "ULPI2_DATA4")
	(net 466 "ULPI2_DATA3")
	(net 467 "ULPI2_DATA2")
	(net 468 "ULPI2_DATA1")
	(net 469 "ULPI2_DATA0")
	(net 470 "unconnected-(U1-VSF7-PadD8)")
	(net 471 "unconnected-(U1-VSF8-PadD9)")
	(net 472 "unconnected-(U1-RFU-PadE2)")
	(net 473 "unconnected-(U1-RFU-PadE3)")
	(net 474 "DDR3_DQS1_N")
	(net 475 "DDR3_DQS1_P")
	(net 476 "DDR3_DQS0_N")
	(net 477 "DDR3_DQS0_P")
	(net 478 "DDR3_CLK_N")
	(net 479 "DDR3_CLK_P")
	(net 480 "unconnected-(U1-RFU-PadE5)")
	(net 481 "unconnected-(U1-RFU-PadE6)")
	(net 482 "unconnected-(U1-RFU-PadE7)")
	(net 483 "unconnected-(U1-RFU-PadE8)")
	(net 484 "unconnected-(U1-RFU-PadE9)")
	(net 485 "unconnected-(U1-RFU-PadH4)")
	(net 486 "unconnected-(U1-RFU-PadH5)")
	(net 487 "unconnected-(U1-RFU-PadH6)")
	(net 488 "unconnected-(U1-RFU-PadH7)")
	(net 489 "/Interfaces/PCIE_BMC_TX_C_N")
	(net 490 "/Interfaces/PCIE_BMC_TX_C_P")
	(net 491 "unconnected-(U1-RFU-PadJ2)")
	(net 492 "unconnected-(U1-RFU-PadJ3)")
	(net 493 "unconnected-(U1-RFU-PadJ4)")
	(net 494 "unconnected-(U1-RFU-PadJ6)")
	(net 495 "unconnected-(U1-RFU-PadJ7)")
	(net 496 "unconnected-(U1-RFU-PadJ8)")
	(net 497 "unconnected-(U1-RFU-PadJ9)")
	(net 498 "unconnected-(U1-RFU-PadK4)")
	(net 499 "unconnected-(U1-RFU-PadK6)")
	(net 500 "unconnected-(U1-RFU-PadK7)")
	(net 501 "unconnected-(U1-RFU-PadL5)")
	(net 502 "unconnected-(U1-RFU-PadL6)")
	(net 503 "/FPGA banks 13-16/GCLK100")
	(net 504 "unconnected-(U1-RFU-PadM2)")
	(net 505 "unconnected-(U1-RFU-PadM3)")
	(net 506 "unconnected-(U1-RFU-PadM6)")
	(net 507 "unconnected-(U1-RFU-PadM8)")
	(net 508 "unconnected-(U1-RFU-PadM9)")
	(net 509 "unconnected-(U1-RFU-PadN4)")
	(net 510 "unconnected-(U1-RFU-PadN5)")
	(net 511 "unconnected-(U1-RFU-PadN6)")
	(net 512 "unconnected-(U1-RFU-PadN7)")
	(net 513 "unconnected-(U1-RFU-PadP4)")
	(net 514 "unconnected-(U1-RFU-PadP7)")
	(net 515 "unconnected-(U1-NC-PadT1)")
	(net 516 "unconnected-(U1-NC-PadT10)")
	(net 517 "unconnected-(U1-NC-PadU1)")
	(net 518 "unconnected-(U1-NC-PadU2)")
	(net 519 "unconnected-(U1-NC-PadU9)")
	(net 520 "unconnected-(U1-NC-PadU10)")
	(net 521 "PRSNT0_N_R")
	(net 522 "VIRTUAL_RESEAT_R")
	(net 523 "SPI0_MOSI_R")
	(net 524 "SPI0_CLK_R")
	(net 525 "SPI0_CS_N_R")
	(net 526 "SPI0_MISO_R")
	(net 527 "/PCIe-connector/NVME_LED")
	(net 528 "unconnected-(U10-NC-Pad4)")
	(net 529 "unconnected-(U10-PG-Pad8)")
	(net 530 "unconnected-(U11-NC-Pad4)")
	(net 531 "unconnected-(U12-NC-Pad4)")
	(net 532 "unconnected-(U13-NC-Pad4)")
	(net 533 "Net-(U14E-MGTRREF_216)")
	(net 534 "/Power supply/1V2_PG")
	(net 535 "unconnected-(U14E-MGTPTXN2_216-PadA6)")
	(net 536 "unconnected-(U14E-MGTPRXN2_216-PadA10)")
	(net 537 "unconnected-(U14A-IO_L8P_T1_13-PadAA9)")
	(net 538 "1V0_PG")
	(net 539 "unconnected-(U14A-IO_L9P_T1_DQS_13-PadAA10)")
	(net 540 "unconnected-(U14A-IO_L9N_T1_DQS_13-PadAA11)")
	(net 541 "unconnected-(U14A-IO_L3P_T0_DQS_13-PadAA13)")
	(net 542 "unconnected-(U14A-IO_L5N_T0_13-PadAA14)")
	(net 543 "unconnected-(U14A-IO_L4P_T0_13-PadAA15)")
	(net 544 "unconnected-(U14A-IO_L1N_T0_13-PadAA16)")
	(net 545 "unconnected-(U14A-IO_L8N_T1_13-PadAB10)")
	(net 546 "unconnected-(U14A-IO_L7P_T1_13-PadAB11)")
	(net 547 "unconnected-(U14A-IO_L7N_T1_13-PadAB12)")
	(net 548 "unconnected-(U14A-IO_L3N_T0_DQS_13-PadAB13)")
	(net 549 "unconnected-(U14A-IO_L4N_T0_13-PadAB15)")
	(net 550 "unconnected-(U14A-IO_L2P_T0_13-PadAB16)")
	(net 551 "unconnected-(U14A-IO_L2N_T0_13-PadAB17)")
	(net 552 "unconnected-(U14E-MGTPTXP2_216-PadB6)")
	(net 553 "unconnected-(U14E-MGTPRXP2_216-PadB10)")
	(net 554 "unconnected-(U14B-IO_L11P_T1_SRCC_16-PadB17)")
	(net 555 "unconnected-(U14B-IO_L11N_T1_SRCC_16-PadB18)")
	(net 556 "unconnected-(U14B-IO_L21P_T3_DQS_16-PadB21)")
	(net 557 "unconnected-(U14E-MGTPTXN1_216-PadC5)")
	(net 558 "unconnected-(U14E-MGTPTXN3_216-PadC7)")
	(net 559 "ROT_MISO")
	(net 560 "ROT_MOSI")
	(net 561 "ROT_SS")
	(net 562 "ROT_TX")
	(net 563 "ROT_RX")
	(net 564 "ROT_SCLK")
	(net 565 "ROT_GPIO2")
	(net 566 "ROT_GPIO1")
	(net 567 "unconnected-(U14E-MGTPRXN3_216-PadC9)")
	(net 568 "unconnected-(U14E-MGTPRXN1_216-PadC11)")
	(net 569 "unconnected-(U14B-IO_L12N_T1_MRCC_16-PadC17)")
	(net 570 "unconnected-(U14E-MGTPTXP1_216-PadD5)")
	(net 571 "unconnected-(U14E-MGTPTXP3_216-PadD7)")
	(net 572 "unconnected-(U14E-MGTPRXP3_216-PadD9)")
	(net 573 "/Power supply/5V0_PG")
	(net 574 "Net-(J1-Pad15)")
	(net 575 "Net-(J1-Pad13)")
	(net 576 "ESPI_CS1_N_1V8")
	(net 577 "ESPI_IO3_1V8")
	(net 578 "ESPI_IO2_1V8")
	(net 579 "ESPI_IO1_1V8")
	(net 580 "ESPI_IO0_1V8")
	(net 581 "ESPI_RESET_N_1V8")
	(net 582 "ESPI_ALERT_N_1V8")
	(net 583 "ESPI_CS0_N_1V8")
	(net 584 "ESPI_CLK_1V8")
	(net 585 "HPM_STBY_EN_R")
	(net 586 "HPM_STBY_RDY_R")
	(net 587 "unconnected-(U14E-MGTPRXP1_216-PadD11)")
	(net 588 "unconnected-(U14B-IO_L6N_T0_VREF_16-PadD15)")
	(net 589 "TPM_PP")
	(net 590 "TPM_GPIO")
	(net 591 "TPM_RST")
	(net 592 "TPM_PIRQ#")
	(net 593 "unconnected-(U14B-IO_L23N_T3_16-PadD21)")
	(net 594 "unconnected-(U14E-MGTREFCLK1N_216-PadE10)")
	(net 595 "unconnected-(U14B-IO_L15N_T2_DQS_16-PadE18)")
	(net 596 "unconnected-(U14B-IO_L14P_T2_SRCC_16-PadE19)")
	(net 597 "1V8_FT")
	(net 598 "unconnected-(U14C-IO_0_35-PadF4)")
	(net 599 "unconnected-(U14E-MGTREFCLK1P_216-PadF10)")
	(net 600 "unconnected-(U14B-IO_L1N_T0_16-PadF14)")
	(net 601 "unconnected-(U14B-IO_0_16-PadF15)")
	(net 602 "unconnected-(U14B-IO_L2P_T0_16-PadF16)")
	(net 603 "unconnected-(U14C-IO_L12N_T1_MRCC_35-PadG4)")
	(net 604 "unconnected-(U14B-IO_L2N_T0_AD8N_15-PadG16)")
	(net 605 "unconnected-(U14B-IO_L24P_T3_16-PadG21)")
	(net 606 "unconnected-(U14B-IO_L3N_T0_DQS_AD1N_15-PadH14)")
	(net 607 "unconnected-(U14B-IO_L5N_T0_AD9N_15-PadH15)")
	(net 608 "unconnected-(U14B-IO_L6P_T0_15-PadH17)")
	(net 609 "unconnected-(U14B-IO_L21N_T3_DQS_A18_15-PadJ17)")
	(net 610 "unconnected-(U14B-IO_L11P_T1_SRCC_15-PadJ20)")
	(net 611 "unconnected-(U14B-IO_L14P_T2_SRCC_15-PadL19)")
	(net 612 "unconnected-(U14B-IO_L16P_T2_A28_15-PadM18)")
	(net 613 "unconnected-(U14B-IO_L18N_T2_A23_15-PadM20)")
	(net 614 "unconnected-(U14A-IO_25_14-PadN15)")
	(net 615 "unconnected-(U14A-IO_L21P_T3_DQS_14-PadN17)")
	(net 616 "unconnected-(U14B-IO_L17N_T2_A25_15-PadN19)")
	(net 617 "unconnected-(U14A-IO_L19P_T3_A10_D26_14-PadP14)")
	(net 618 "unconnected-(U14A-IO_L22P_T3_A05_D21_14-PadP15)")
	(net 619 "unconnected-(U14A-IO_0_14-PadP20)")
	(net 620 "unconnected-(U14C-IO_L17P_T2_34-PadR6)")
	(net 621 "unconnected-(U14A-IO_L19N_T3_A09_D25_VREF_14-PadR14)")
	(net 622 "unconnected-(U14A-IO_L22N_T3_A04_D20_14-PadR16)")
	(net 623 "unconnected-(U14A-IO_L15P_T2_DQS_13-PadT14)")
	(net 624 "DBG_UART_RX")
	(net 625 "unconnected-(U14A-IO_L15N_T2_DQS_13-PadT15)")
	(net 626 "DBG_UART_TX")
	(net 627 "unconnected-(U14A-IO_L17P_T2_13-PadT16)")
	(net 628 "unconnected-(U14A-IO_L14P_T2_SRCC_13-PadU15)")
	(net 629 "unconnected-(U14A-IO_L17N_T2_13-PadU16)")
	(net 630 "unconnected-(U14A-IO_L10P_T1_13-PadV10)")
	(net 631 "unconnected-(U14A-IO_L13P_T2_MRCC_13-PadV13)")
	(net 632 "unconnected-(U14A-IO_L13N_T2_MRCC_13-PadV14)")
	(net 633 "unconnected-(U14A-IO_L14N_T2_SRCC_13-PadV15)")
	(net 634 "unconnected-(U14A-IO_L10N_T1_13-PadW10)")
	(net 635 "unconnected-(U14A-IO_L12P_T1_MRCC_13-PadW11)")
	(net 636 "unconnected-(U14A-IO_L12N_T1_MRCC_13-PadW12)")
	(net 637 "unconnected-(U14A-IO_L6P_T0_13-PadW14)")
	(net 638 "unconnected-(U14A-IO_L16P_T2_13-PadW15)")
	(net 639 "unconnected-(U14A-IO_L16N_T2_13-PadW16)")
	(net 640 "unconnected-(U14A-IO_L11P_T1_SRCC_13-PadY11)")
	(net 641 "unconnected-(U14A-IO_L11N_T1_SRCC_13-PadY12)")
	(net 642 "unconnected-(U14A-IO_L5P_T0_13-PadY13)")
	(net 643 "unconnected-(U14A-IO_L6N_T0_VREF_13-PadY14)")
	(net 644 "unconnected-(U14A-IO_L1P_T0_13-PadY16)")
	(net 645 "unconnected-(U14A-IO_0_13-PadY17)")
	(net 646 "unconnected-(U16-NC-Pad4)")
	(net 647 "unconnected-(U17-CPEN-Pad3)")
	(net 648 "unconnected-(U17-ID-Pad5)")
	(net 649 "unconnected-(U17-EXTVBUS-Pad10)")
	(net 650 "unconnected-(U17-XO-Pad27)")
	(net 651 "Net-(U17-XI)")
	(net 652 "unconnected-(U18-CPEN-Pad3)")
	(net 653 "unconnected-(U18-ID-Pad5)")
	(net 654 "unconnected-(U18-EXTVBUS-Pad10)")
	(net 655 "unconnected-(U18-XO-Pad27)")
	(net 656 "Net-(U18-XI)")
	(net 657 "unconnected-(U19-ADBUS4-Pad21)")
	(net 658 "unconnected-(U19-ADBUS6-Pad23)")
	(net 659 "unconnected-(U19-ADBUS7-Pad24)")
	(net 660 "unconnected-(U19-BDBUS0-Pad26)")
	(net 661 "unconnected-(U19-BDBUS1-Pad27)")
	(net 662 "unconnected-(U19-BDBUS2-Pad28)")
	(net 663 "unconnected-(U19-BDBUS3-Pad29)")
	(net 664 "unconnected-(U19-BDBUS4-Pad30)")
	(net 665 "unconnected-(U19-BDBUS5-Pad32)")
	(net 666 "unconnected-(U19-BDBUS6-Pad33)")
	(net 667 "unconnected-(U19-BDBUS7-Pad34)")
	(net 668 "unconnected-(U19-SUSPEND-Pad36)")
	(net 669 "unconnected-(U19-CDBUS2-Pad40)")
	(net 670 "unconnected-(U19-CDBUS3-Pad41)")
	(net 671 "unconnected-(U19-CDBUS4-Pad43)")
	(net 672 "unconnected-(U19-CDBUS5-Pad44)")
	(net 673 "unconnected-(U19-CDBUS6-Pad45)")
	(net 674 "unconnected-(U19-CDBUS7-Pad46)")
	(net 675 "unconnected-(U19-DDBUS0-Pad48)")
	(net 676 "unconnected-(U19-DDBUS1-Pad52)")
	(net 677 "unconnected-(U19-DDBUS2-Pad53)")
	(net 678 "unconnected-(U19-DDBUS3-Pad54)")
	(net 679 "unconnected-(U19-DDBUS4-Pad55)")
	(net 680 "unconnected-(U19-DDBUS5-Pad57)")
	(net 681 "unconnected-(U19-DDBUS6-Pad58)")
	(net 682 "unconnected-(U19-DDBUS7-Pad59)")
	(net 683 "unconnected-(U19-PWREN-Pad60)")
	(net 684 "unconnected-(U19-EEDATA-Pad61)")
	(net 685 "unconnected-(U19-EECLK-Pad62)")
	(net 686 "unconnected-(U19-EECS-Pad63)")
	(net 687 "unconnected-(U20-NC-Pad13)")
	(net 688 "unconnected-(U20-LDO_O-Pad43)")
	(net 689 "unconnected-(U20-NC-Pad47)")
	(net 690 "unconnected-(MP1-Pad1)")
	(net 691 "unconnected-(MP2-Pad1)")
	(net 692 "unconnected-(H1-Pad1)")
	(net 693 "unconnected-(H2-Pad1)")
	(net 694 "Net-(J9-PadB35)")
	(net 695 "unconnected-(D2-Pad12)_1")
	(net 696 "unconnected-(D2-Pad11)_1")
	(net 697 "unconnected-(U7-NC-PadM7)")
	(net 698 "unconnected-(U7-NC-PadJ1)")
	(net 699 "unconnected-(U7-NC-PadL1)")
	(net 700 "unconnected-(U7-NC-PadJ9)")
	(net 701 "unconnected-(U7-NC-PadL9)")
	(footprint "antmicro-footprints:R_0402_1005Metric"
		(layer "F.Cu")
		(at 100.574 140.075 90)
		(descr "Resistor SMD 0402")
		(tags "resistor SMD 0402")
		(property "Reference" "R60"
			(at 0.775 0.326 90)
			(layer "F.SilkS")
			(effects
				(font
					(size 0.7 0.7)
					(thickness 0.15)
				)
				(justify left bottom)
			)
		)
		(property "Value" "R_240R_0402"
			(at 0 1.4 90)
			(layer "F.Fab")
			(effects
				(font
					(size 0.7 0.7)
					(thickness 0.15)
				)
				(justify left bottom)
			)
		)
		(property "Datasheet" "https://www.bourns.com/docs/product-datasheets/cr.pdf"
			(at 0 0 90)
			(layer "F.Fab")
			(hide yes)
			(effects
				(font
					(size 1.27 1.27)
					(thickness 0.15)
				)
			)
		)
		(property "Description" "SMD Chip Resistor, 240 ohm, ± 1%, 63 mW, 0402 [1005 Metric], Thick Film, General Purpose"
			(at 0 0 90)
			(layer "F.Fab")
			(hide yes)
			(effects
				(font
					(size 1.27 1.27)
					(thickness 0.15)
				)
			)
		)
		(property "Author" "Antmicro"
			(at 240.649 39.501 0)
			(layer "F.Fab")
			(hide yes)
			(effects
				(font
					(size 1 1)
					(thickness 0.15)
				)
			)
		)
		(property "License" "Apache-2.0"
			(at 240.649 39.501 0)
			(layer "F.Fab")
			(hide yes)
			(effects
				(font
					(size 1 1)
					(thickness 0.15)
				)
			)
		)
		(property "MPN" "CR0402-FX-2400GLF"
			(at 240.649 39.501 0)
			(layer "F.Fab")
			(hide yes)
			(effects
				(font
					(size 1 1)
					(thickness 0.15)
				)
			)
		)
		(property "Manufacturer" "Bourns"
			(at 240.649 39.501 0)
			(layer "F.Fab")
			(hide yes)
			(effects
				(font
					(size 1 1)
					(thickness 0.15)
				)
			)
		)
		(property "Tolerance" "1%"
			(at 240.649 39.501 0)
			(layer "F.Fab")
			(hide yes)
			(effects
				(font
					(size 1 1)
					(thickness 0.15)
				)
			)
		)
		(property "Val" "240R"
			(at 240.649 39.501 0)
			(layer "F.Fab")
			(hide yes)
			(effects
				(font
					(size 1 1)
					(thickness 0.15)
				)
			)
		)
		(sheetname "/DDR3/")
		(sheetfile "ddr3.kicad_sch")
		(attr smd)
		(fp_rect
			(start -0.925 -0.47)
			(end 0.925 0.47)
			(stroke
				(width 0.05)
				(type default)
			)
			(fill no)
			(layer "F.CrtYd")
		)
		(fp_rect
			(start -0.5 -0.25)
			(end 0.5 0.25)
			(stroke
				(width 0.15)
				(type solid)
			)
			(fill no)
			(layer "F.Fab")
		)
		(pad "1" smd roundrect
			(at -0.48 0 90)
			(size 0.59 0.64)
			(layers "F.Cu" "F.Mask" "F.Paste")
			(roundrect_rratio 0.25)
			(net 337 "Net-(U7-ZQ)")
			(pintype "passive")
		)
		(pad "2" smd roundrect
			(at 0.48 0 90)
			(size 0.59 0.64)
			(layers "F.Cu" "F.Mask" "F.Paste")
			(roundrect_rratio 0.25)
			(net 1 "GND")
			(pintype "passive")
		)
	)
	(footprint "antmicro-footprints:C_0402_1005Metric"
		(layer "F.Cu")
		(at 98.574 154.675 90)
		(descr "Capacitor SMD 0402")
		(tags "capacitor SMD 0402")
		(property "Reference" "C62"
			(at -3.425 -8.274 90)
			(layer "F.SilkS")
			(effects
				(font
					(size 0.7 0.7)
					(thickness 0.15)
				)
				(justify left bottom)
			)
		)
		(property "Value" "C_100n_6V3_0402"
			(at 0 1.4 90)
			(layer "F.Fab")
			(effects
				(font
					(size 0.7 0.7)
					(thickness 0.15)
				)
				(justify left bottom)
			)
		)
		(property "Datasheet" "https://www.passivecomponent.com/wp-content/uploads/datasheet/WTC_MLCC_General_Purpose.pdf"
			(at 0 0 90)
			(layer "F.Fab")
			(hide yes)
			(effects
				(font
					(size 1.27 1.27)
					(thickness 0.15)
				)
			)
		)
		(property "Description" "SMT Multilayer Ceramic Capacitor, 0.1 µF, 6.3 V, 0402 [1005 Metric], ± 10%, X5R, Walsin MLCC"
			(at 0 0 90)
			(layer "F.Fab")
			(hide yes)
			(effects
				(font
					(size 1.27 1.27)
					(thickness 0.15)
				)
			)
		)
		(property "Author" "Antmicro"
			(at 253.249 56.101 0)
			(layer "F.Fab")
			(hide yes)
			(effects
				(font
					(size 1 1)
					(thickness 0.15)
				)
			)
		)
		(property "Dielectric" ""
			(at 253.249 56.101 0)
			(layer "F.Fab")
			(hide yes)
			(effects
				(font
					(size 1 1)
					(thickness 0.15)
				)
			)
		)
		(property "License" "Apache-2.0"
			(at 253.249 56.101 0)
			(layer "F.Fab")
			(hide yes)
			(effects
				(font
					(size 1 1)
					(thickness 0.15)
				)
			)
		)
		(property "MPN" "0402X104K6R3CT"
			(at 253.249 56.101 0)
			(layer "F.Fab")
			(hide yes)
			(effects
				(font
					(size 1 1)
					(thickness 0.15)
				)
			)
		)
		(property "Manufacturer" "Walsin"
			(at 253.249 56.101 0)
			(layer "F.Fab")
			(hide yes)
			(effects
				(font
					(size 1 1)
					(thickness 0.15)
				)
			)
		)
		(property "Public" "False"
			(at 253.249 56.101 0)
			(layer "F.Fab")
			(hide yes)
			(effects
				(font
					(size 1 1)
					(thickness 0.15)
				)
			)
		)
		(property "Val" "100n"
			(at 253.249 56.101 0)
			(layer "F.Fab")
			(hide yes)
			(effects
				(font
					(size 1 1)
					(thickness 0.15)
				)
			)
		)
		(property "Voltage" ""
			(at 253.249 56.101 0)
			(layer "F.Fab")
			(hide yes)
			(effects
				(font
					(size 1 1)
					(thickness 0.15)
				)
			)
		)
		(sheetname "/DDR3/")
		(sheetfile "ddr3.kicad_sch")
		(attr smd)
		(fp_rect
			(start -0.925 -0.47)
			(end 0.925 0.47)
			(stroke
				(width 0.05)
				(type default)
			)
			(fill no)
			(layer "F.CrtYd")
		)
		(fp_line
			(start 0.504 -0.25)
			(end 0.504 0.248)
			(stroke
				(width 0.15)
				(type solid)
			)
			(layer "F.Fab")
		)
		(fp_line
			(start -0.494 -0.25)
			(end 0.504 -0.25)
			(stroke
				(width 0.15)
				(type solid)
			)
			(layer "F.Fab")
		)
		(fp_line
			(start 0.504 0.248)
			(end -0.494 0.248)
			(stroke
				(width 0.15)
				(type solid)
			)
			(layer "F.Fab")
		)
		(fp_line
			(start -0.494 0.248)
			(end -0.494 -0.25)
			(stroke
				(width 0.15)
				(type solid)
			)
			(layer "F.Fab")
		)
		(pad "1" smd roundrect
			(at -0.48 0 90)
			(size 0.59 0.64)
			(layers "F.Cu" "F.Mask" "F.Paste")
			(roundrect_rratio 0.25)
			(net 1 "GND")
			(pintype "passive")
		)
		(pad "2" smd roundrect
			(at 0.48 0 90)
			(size 0.59 0.64)
			(layers "F.Cu" "F.Mask" "F.Paste")
			(roundrect_rratio 0.25)
			(net 211 "DDR3_VREF")
			(pintype "passive")
		)
	)
	(footprint "antmicro-footprints:C_0402_1005Metric"
		(layer "F.Cu")
		(at 92.174 154.675 90)
		(descr "Capacitor SMD 0402")
		(tags "capacitor SMD 0402")
		(property "Reference" "C48"
			(at -3.425 -7.574 90)
			(layer "F.SilkS")
			(effects
				(font
					(size 0.7 0.7)
					(thickness 0.15)
				)
				(justify left bottom)
			)
		)
		(property "Value" "C_4u7_0402"
			(at 0 1.4 90)
			(layer "F.Fab")
			(effects
				(font
					(size 0.7 0.7)
					(thickness 0.15)
				)
				(justify left bottom)
			)
		)
		(property "Datasheet" "https://www.murata.com/products/productdetail?partno=GRM155R61A475MEAA%23"
			(at 0 0 90)
			(layer "F.Fab")
			(hide yes)
			(effects
				(font
					(size 1.27 1.27)
					(thickness 0.15)
				)
			)
		)
		(property "Description" "SMD Multilayer Ceramic Capacitor, 4.7 µF, 10 V, 0402 [1005 Metric], ± 20%, X5R, GRM Series"
			(at 0 0 90)
			(layer "F.Fab")
			(hide yes)
			(effects
				(font
					(size 1.27 1.27)
					(thickness 0.15)
				)
			)
		)
		(property "Author" "Antmicro"
			(at 246.849 62.501 0)
			(layer "F.Fab")
			(hide yes)
			(effects
				(font
					(size 1 1)
					(thickness 0.15)
				)
			)
		)
		(property "Dielectric" ""
			(at 246.849 62.501 0)
			(layer "F.Fab")
			(hide yes)
			(effects
				(font
					(size 1 1)
					(thickness 0.15)
				)
			)
		)
		(property "License" "Apache-2.0"
			(at 246.849 62.501 0)
			(layer "F.Fab")
			(hide yes)
			(effects
				(font
					(size 1 1)
					(thickness 0.15)
				)
			)
		)
		(property "MPN" "GRM155R61A475MEAAD"
			(at 246.849 62.501 0)
			(layer "F.Fab")
			(hide yes)
			(effects
				(font
					(size 1 1)
					(thickness 0.15)
				)
			)
		)
		(property "Manufacturer" "Murata"
			(at 246.849 62.501 0)
			(layer "F.Fab")
			(hide yes)
			(effects
				(font
					(size 1 1)
					(thickness 0.15)
				)
			)
		)
		(property "Val" "4u7"
			(at 246.849 62.501 0)
			(layer "F.Fab")
			(hide yes)
			(effects
				(font
					(size 1 1)
					(thickness 0.15)
				)
			)
		)
		(property "Voltage" ""
			(at 246.849 62.501 0)
			(layer "F.Fab")
			(hide yes)
			(effects
				(font
					(size 1 1)
					(thickness 0.15)
				)
			)
		)
		(sheetname "/DDR3/")
		(sheetfile "ddr3.kicad_sch")
		(attr smd)
		(fp_rect
			(start -0.925 -0.47)
			(end 0.925 0.47)
			(stroke
				(width 0.05)
				(type default)
			)
			(fill no)
			(layer "F.CrtYd")
		)
		(fp_line
			(start 0.504 -0.25)
			(end 0.504 0.248)
			(stroke
				(width 0.15)
				(type solid)
			)
			(layer "F.Fab")
		)
		(fp_line
			(start -0.494 -0.25)
			(end 0.504 -0.25)
			(stroke
				(width 0.15)
				(type solid)
			)
			(layer "F.Fab")
		)
		(fp_line
			(start 0.504 0.248)
			(end -0.494 0.248)
			(stroke
				(width 0.15)
				(type solid)
			)
			(layer "F.Fab")
		)
		(fp_line
			(start -0.494 0.248)
			(end -0.494 -0.25)
			(stroke
				(width 0.15)
				(type solid)
			)
			(layer "F.Fab")
		)
		(pad "1" smd roundrect
			(at -0.48 0 90)
			(size 0.59 0.64)
			(layers "F.Cu" "F.Mask" "F.Paste")
			(roundrect_rratio 0.25)
			(net 1 "GND")
			(pintype "passive")
		)
		(pad "2" smd roundrect
			(at 0.48 0 90)
			(size 0.59 0.64)
			(layers "F.Cu" "F.Mask" "F.Paste")
			(roundrect_rratio 0.25)
			(net 3 "VCC1V35")
			(pintype "passive")
		)
	)
	(footprint "antmicro-footprints:Bus_M.2_Socket_Key_M_TE_1-2199230-6"
		(layer "F.Cu")
		(at 125.999 160.975 180)
		(property "Reference" "J2"
			(at 10.499 4.475 0)
			(layer "F.SilkS")
			(effects
				(font
					(size 0.7 0.7)
					(thickness 0.15)
				)
				(justify right bottom)
			)
		)
		(property "Value" "Bus_M.2_1-2199230-6"
			(at -2 9.9 0)
			(layer "F.Fab")
			(effects
				(font
					(size 0.7 0.7)
					(thickness 0.15)
				)
				(justify right bottom)
			)
		)
		(property "Datasheet" "https://www.te.com/commerce/DocumentDelivery/DDEController?Action=srchrtrv&DocNm=2199230&DocType=Customer+Drawing&DocLang=English"
			(at 0 0 180)
			(layer "F.Fab")
			(hide yes)
			(effects
				(font
					(size 1.27 1.27)
					(thickness 0.15)
				)
			)
		)
		(property "Description" "Key M Card Edge Connector, 0, Dual Side, 67 Contacts, Surface Mount, Right Angle, Solder"
			(at 0 0 180)
			(layer "F.Fab")
			(hide yes)
			(effects
				(font
					(size 1.27 1.27)
					(thickness 0.15)
				)
			)
		)
		(property "Author" "Antmicro"
			(at 251.998 321.95 0)
			(layer "F.Fab")
			(hide yes)
			(effects
				(font
					(size 1 1)
					(thickness 0.15)
				)
			)
		)
		(property "License" "Apache-2.0"
			(at 251.998 321.95 0)
			(layer "F.Fab")
			(hide yes)
			(effects
				(font
					(size 1 1)
					(thickness 0.15)
				)
			)
		)
		(property "MPN" "1-2199230-6"
			(at 251.998 321.95 0)
			(layer "F.Fab")
			(hide yes)
			(effects
				(font
					(size 1 1)
					(thickness 0.15)
				)
			)
		)
		(property "Manufacturer" "TE Connectivity"
			(at 251.998 321.95 0)
			(layer "F.Fab")
			(hide yes)
			(effects
				(font
					(size 1 1)
					(thickness 0.15)
				)
			)
		)
		(property "VSD_Class" "M.2 Key M"
			(at 251.998 321.95 0)
			(layer "F.Fab")
			(hide yes)
			(effects
				(font
					(size 1 1)
					(thickness 0.15)
				)
			)
		)
		(sheetname "/PCIe-connector/")
		(sheetfile "pcie-conn.kicad_sch")
		(attr smd)
		(fp_line
			(start 10.948 3.999)
			(end 10.948 2.3)
			(stroke
				(width 0.15)
				(type solid)
			)
			(layer "F.SilkS")
		)
		(fp_line
			(start 10.948 0.449)
			(end 10.948 -1.301)
			(stroke
				(width 0.15)
				(type solid)
			)
			(layer "F.SilkS")
		)
		(fp_line
			(start 9.448 3.999)
			(end 10.948 3.999)
			(stroke
				(width 0.15)
				(type solid)
			)
			(layer "F.SilkS")
		)
		(fp_line
			(start 5.347 3.999)
			(end 7.148 3.999)
			(stroke
				(width 0.15)
				(type solid)
			)
			(layer "F.SilkS")
		)
		(fp_line
			(start 5.097 -3.75)
			(end 6.898 -3.75)
			(stroke
				(width 0.15)
				(type solid)
			)
			(layer "F.SilkS")
		)
		(fp_line
			(start -10.951 3.999)
			(end -9.352 3.999)
			(stroke
				(width 0.15)
				(type solid)
			)
			(layer "F.SilkS")
		)
		(fp_line
			(start -10.951 2.7)
			(end -10.951 3.999)
			(stroke
				(width 0.15)
				(type solid)
			)
			(layer "F.SilkS")
		)
		(fp_line
			(start -10.951 -1.401)
			(end -10.951 0.55)
			(stroke
				(width 0.15)
				(type solid)
			)
			(layer "F.SilkS")
		)
		(fp_circle
			(center -9.25 -4.875)
			(end -9.201 -4.826)
			(stroke
				(width 0.15)
				(type solid)
			)
			(fill yes)
			(layer "F.SilkS")
		)
		(fp_circle
			(center -9.25 -5.651)
			(end -9.2 -5.651)
			(stroke
				(width 0.15)
				(type solid)
			)
			(fill yes)
			(layer "F.SilkS")
		)
		(fp_line
			(start 11.15 4.78)
			(end 11.15 -4.83)
			(stroke
				(width 0.05)
				(type solid)
			)
			(layer "F.CrtYd")
		)
		(fp_line
			(start 11.15 -4.83)
			(end -11.16 -4.83)
			(stroke
				(width 0.05)
				(type solid)
			)
			(layer "F.CrtYd")
		)
		(fp_line
			(start -11.16 4.78)
			(end 11.15 4.78)
			(stroke
				(width 0.05)
				(type solid)
			)
			(layer "F.CrtYd")
		)
		(fp_line
			(start -11.16 -4.83)
			(end -11.16 4.78)
			(stroke
				(width 0.05)
				(type solid)
			)
			(layer "F.CrtYd")
		)
		(fp_line
			(start 10.95 4.2)
			(end -10.949 4.2)
			(stroke
				(width 0.15)
				(type solid)
			)
			(layer "F.Fab")
		)
		(fp_line
			(start 10.95 -4.1)
			(end 10.95 4.2)
			(stroke
				(width 0.15)
				(type solid)
			)
			(layer "F.Fab")
		)
		(fp_line
			(start -10.4 -4.1)
			(end 10.95 -4.1)
			(stroke
				(width 0.15)
				(type solid)
			)
			(layer "F.Fab")
		)
		(fp_line
			(start -10.949 4.2)
			(end -10.949 -3.55)
			(stroke
				(width 0.15)
				(type solid)
			)
			(layer "F.Fab")
		)
		(fp_line
			(start -10.949 -3.55)
			(end -10.4 -4.1)
			(stroke
				(width 0.15)
				(type solid)
			)
			(layer "F.Fab")
		)
		(fp_text user "${REFERENCE}"
			(at -2.05 11.191 0)
			(layer "F.Fab")
			(effects
				(font
					(size 0.7 0.7)
					(thickness 0.15)
				)
				(justify right bottom)
			)
		)
		(fp_text user "Author: Antmicro"
			(at -2.05 12.5 0)
			(layer "F.Fab")
			(effects
				(font
					(size 0.7 0.7)
					(thickness 0.15)
				)
				(justify right bottom)
			)
		)
		(fp_text user "License: Apache-2.0"
			(at -2.05 13.809 0)
			(layer "F.Fab")
			(effects
				(font
					(size 0.7 0.7)
					(thickness 0.15)
				)
				(justify right bottom)
			)
		)
		(pad "" np_thru_hole circle
			(at -10 1.499 180)
			(size 1.1 1.1)
			(drill 1.1)
			(layers "*.Mask")
		)
		(pad "" np_thru_hole circle
			(at 9.997 1.499 180)
			(size 1.6 1.6)
			(drill 1.6)
			(layers "*.Mask")
		)
		(pad "1" smd rect
			(at -9.25 -3.775 180)
			(size 0.3 1.55)
			(layers "F.Cu" "F.Mask" "F.Paste")
			(net 1 "GND")
			(pinfunction "GND")
			(pintype "power_in")
		)
		(pad "2" smd rect
			(at -9.003 3.773 180)
			(size 0.3 1.55)
			(layers "F.Cu" "F.Mask" "F.Paste")
			(net 2 "VCC3V3")
			(pinfunction "3V3")
			(pintype "passive")
		)
		(pad "3" smd rect
			(at -8.753 -3.775 180)
			(size 0.3 1.55)
			(layers "F.Cu" "F.Mask" "F.Paste")
			(net 1 "GND")
			(pinfunction "GND")
			(pintype "passive")
		)
		(pad "4" smd rect
			(at -8.503 3.773 180)
			(size 0.3 1.55)
			(layers "F.Cu" "F.Mask" "F.Paste")
			(net 2 "VCC3V3")
			(pinfunction "3V3")
			(pintype "passive")
		)
		(pad "5" smd rect
			(at -8.253 -3.775 180)
			(size 0.3 1.55)
			(layers "F.Cu" "F.Mask" "F.Paste")
			(net 368 "PCIE_HPM_RX[3]_N")
			(pinfunction "PER3_N")
			(pintype "output")
		)
		(pad "6" smd rect
			(at -8.001 3.773 180)
			(size 0.3 1.55)
			(layers "F.Cu" "F.Mask" "F.Paste")
			(net 229 "unconnected-(J2-NC-Pad6)")
			(pinfunction "NC")
			(pintype "no_connect")
		)
		(pad "7" smd rect
			(at -7.752 -3.775 180)
			(size 0.3 1.55)
			(layers "F.Cu" "F.Mask" "F.Paste")
			(net 367 "PCIE_HPM_RX[3]_P")
			(pinfunction "PER3_P")
			(pintype "output")
		)
		(pad "8" smd rect
			(at -7.502 3.773 180)
			(size 0.3 1.55)
			(layers "F.Cu" "F.Mask" "F.Paste")
			(net 230 "unconnected-(J2-NC-Pad8)")
			(pinfunction "NC")
			(pintype "no_connect")
		)
		(pad "9" smd rect
			(at -7.252 -3.775 180)
			(size 0.3 1.55)
			(layers "F.Cu" "F.Mask" "F.Paste")
			(net 1 "GND")
			(pinfunction "GND")
			(pintype "passive")
		)
		(pad "10" smd rect
			(at -7.002 3.773 180)
			(size 0.3 1.55)
			(layers "F.Cu" "F.Mask" "F.Paste")
			(net 527 "/PCIe-connector/NVME_LED")
			(pinfunction "LED")
			(pintype "passive")
		)
		(pad "11" smd rect
			(at -6.752 -3.775 180)
			(size 0.3 1.55)
			(layers "F.Cu" "F.Mask" "F.Paste")
			(net 376 "/PCIe-connector/PCIE_HPM_TX3_C_N")
			(pinfunction "PET3_N")
			(pintype "input")
		)
		(pad "12" smd rect
			(at -6.502 3.773 180)
			(size 0.3 1.55)
			(layers "F.Cu" "F.Mask" "F.Paste")
			(net 2 "VCC3V3")
			(pinfunction "3V3")
			(pintype "passive")
		)
		(pad "13" smd rect
			(at -6.252 -3.775 180)
			(size 0.3 1.55)
			(layers "F.Cu" "F.Mask" "F.Paste")
			(net 374 "/PCIe-connector/PCIE_HPM_TX3_C_P")
			(pinfunction "PET3_P")
			(pintype "input")
		)
		(pad "14" smd rect
			(at -6.002 3.773 180)
			(size 0.3 1.55)
			(layers "F.Cu" "F.Mask" "F.Paste")
			(net 2 "VCC3V3")
			(pinfunction "3V3")
			(pintype "passive")
		)
		(pad "15" smd rect
			(at -5.752 -3.775 180)
			(size 0.3 1.55)
			(layers "F.Cu" "F.Mask" "F.Paste")
			(net 1 "GND")
			(pinfunction "GND")
			(pintype "passive")
		)
		(pad "16" smd rect
			(at -5.502 3.773 180)
			(size 0.3 1.55)
			(layers "F.Cu" "F.Mask" "F.Paste")
			(net 2 "VCC3V3")
			(pinfunction "3V3")
			(pintype "passive")
		)
		(pad "17" smd rect
			(at -5.252 -3.775 180)
			(size 0.3 1.55)
			(layers "F.Cu" "F.Mask" "F.Paste")
			(net 366 "PCIE_HPM_RX[2]_N")
			(pinfunction "PER2_N")
			(pintype "output")
		)
		(pad "18" smd rect
			(at -5.002 3.773 180)
			(size 0.3 1.55)
			(layers "F.Cu" "F.Mask" "F.Paste")
			(net 2 "VCC3V3")
			(pinfunction "3V3")
			(pintype "passive")
		)
		(pad "19" smd rect
			(at -4.752 -3.775 180)
			(size 0.3 1.55)
			(layers "F.Cu" "F.Mask" "F.Paste")
			(net 365 "PCIE_HPM_RX[2]_P")
			(pinfunction "PER2_P")
			(pintype "output")
		)
		(pad "20" smd rect
			(at -4.502 3.773 180)
			(size 0.3 1.55)
			(layers "F.Cu" "F.Mask" "F.Paste")
			(net 231 "unconnected-(J2-NC-Pad20)")
			(pinfunction "NC")
			(pintype "no_connect")
		)
		(pad "21" smd rect
			(at -4.252 -3.775 180)
			(size 0.3 1.55)
			(layers "F.Cu" "F.Mask" "F.Paste")
			(net 1 "GND")
			(pinfunction "GND")
			(pintype "passive")
		)
		(pad "22" smd rect
			(at -4.002 3.773 180)
			(size 0.3 1.55)
			(layers "F.Cu" "F.Mask" "F.Paste")
			(net 232 "unconnected-(J2-NC-Pad22)")
			(pinfunction "NC")
			(pintype "no_connect")
		)
		(pad "23" smd rect
			(at -3.751 -3.775 180)
			(size 0.3 1.55)
			(layers "F.Cu" "F.Mask" "F.Paste")
			(net 375 "/PCIe-connector/PCIE_HPM_TX2_C_N")
			(pinfunction "PET2_N")
			(pintype "input")
		)
		(pad "24" smd rect
			(at -3.501 3.773 180)
			(size 0.3 1.55)
			(layers "F.Cu" "F.Mask" "F.Paste")
			(net 233 "unconnected-(J2-NC-Pad24)")
			(pinfunction "NC")
			(pintype "no_connect")
		)
		(pad "25" smd rect
			(at -3.251 -3.775 180)
			(size 0.3 1.55)
			(layers "F.Cu" "F.Mask" "F.Paste")
			(net 373 "/PCIe-connector/PCIE_HPM_TX2_C_P")
			(pinfunction "PET2_P")
			(pintype "input")
		)
		(pad "26" smd rect
			(at -3.001 3.773 180)
			(size 0.3 1.55)
			(layers "F.Cu" "F.Mask" "F.Paste")
			(net 234 "unconnected-(J2-NC-Pad26)")
			(pinfunction "NC")
			(pintype "no_connect")
		)
		(pad "27" smd rect
			(at -2.751 -3.775 180)
			(size 0.3 1.55)
			(layers "F.Cu" "F.Mask" "F.Paste")
			(net 1 "GND")
			(pinfunction "GND")
			(pintype "passive")
		)
		(pad "28" smd rect
			(at -2.501 3.773 180)
			(size 0.3 1.55)
			(layers "F.Cu" "F.Mask" "F.Paste")
			(net 235 "unconnected-(J2-NC-Pad28)")
			(pinfunction "NC")
			(pintype "no_connect")
		)
		(pad "29" smd rect
			(at -2.251 -3.775 180)
			(size 0.3 1.55)
			(layers "F.Cu" "F.Mask" "F.Paste")
			(net 364 "PCIE_HPM_RX[1]_N")
			(pinfunction "PER1_N")
			(pintype "output")
		)
		(pad "30" smd rect
			(at -2.001 3.773 180)
			(size 0.3 1.55)
			(layers "F.Cu" "F.Mask" "F.Paste")
			(net 236 "unconnected-(J2-NC-Pad30)")
			(pinfunction "NC")
			(pintype "no_connect")
		)
		(pad "31" smd rect
			(at -1.752 -3.775 180)
			(size 0.3 1.55)
			(layers "F.Cu" "F.Mask" "F.Paste")
			(net 363 "PCIE_HPM_RX[1]_P")
			(pinfunction "PER1_P")
			(pintype "output")
		)
		(pad "32" smd rect
			(at -1.502 3.773 180)
			(size 0.3 1.55)
			(layers "F.Cu" "F.Mask" "F.Paste")
			(net 237 "unconnected-(J2-NC-Pad32)")
			(pinfunction "NC")
			(pintype "no_connect")
		)
		(pad "33" smd rect
			(at -1.252 -3.775 180)
			(size 0.3 1.55)
			(layers "F.Cu" "F.Mask" "F.Paste")
			(net 1 "GND")
			(pinfunction "GND")
			(pintype "passive")
		)
		(pad "34" smd rect
			(at -1.002 3.773 180)
			(size 0.3 1.55)
			(layers "F.Cu" "F.Mask" "F.Paste")
			(net 238 "unconnected-(J2-NC-Pad34)")
			(pinfunction "NC")
			(pintype "no_connect")
		)
		(pad "35" smd rect
			(at -0.751 -3.775 180)
			(size 0.3 1.55)
			(layers "F.Cu" "F.Mask" "F.Paste")
			(net 372 "/PCIe-connector/PCIE_HPM_TX1_C_N")
			(pinfunction "PET1_N")
			(pintype "input")
		)
		(pad "36" smd rect
			(at -0.501 3.773 180)
			(size 0.3 1.55)
			(layers "F.Cu" "F.Mask" "F.Paste")
			(net 239 "unconnected-(J2-NC-Pad36)")
			(pinfunction "NC")
			(pintype "no_connect")
		)
		(pad "37" smd rect
			(at -0.251 -3.775 180)
			(size 0.3 1.55)
			(layers "F.Cu" "F.Mask" "F.Paste")
			(net 370 "/PCIe-connector/PCIE_HPM_TX1_C_P")
			(pinfunction "PET1_P")
			(pintype "input")
		)
		(pad "38" smd rect
			(at -0.001 3.773 180)
			(size 0.3 1.55)
			(layers "F.Cu" "F.Mask" "F.Paste")
			(net 261 "unconnected-(J2-NC-Pad38)")
			(pinfunction "NC")
			(pintype "no_connect")
		)
		(pad "39" smd rect
			(at 0.248 -3.775 180)
			(size 0.3 1.55)
			(layers "F.Cu" "F.Mask" "F.Paste")
			(net 1 "GND")
			(pinfunction "GND")
			(pintype "passive")
		)
		(pad "40" smd rect
			(at 0.498 3.773 180)
			(size 0.3 1.55)
			(layers "F.Cu" "F.Mask" "F.Paste")
			(net 262 "unconnected-(J2-SMB_CLK-Pad40)")
			(pinfunction "SMB_CLK")
			(pintype "input+no_connect")
		)
		(pad "41" smd rect
			(at 0.748 -3.775 180)
			(size 0.3 1.55)
			(layers "F.Cu" "F.Mask" "F.Paste")
			(net 362 "PCIE_HPM_RX[0]_N")
			(pinfunction "PER0_N")
			(pintype "output")
		)
		(pad "42" smd rect
			(at 0.998 3.773 180)
			(size 0.3 1.55)
			(layers "F.Cu" "F.Mask" "F.Paste")
			(net 263 "unconnected-(J2-SMB_DATA-Pad42)")
			(pinfunction "SMB_DATA")
			(pintype "bidirectional+no_connect")
		)
		(pad "43" smd rect
			(at 1.249 -3.775 180)
			(size 0.3 1.55)
			(layers "F.Cu" "F.Mask" "F.Paste")
			(net 361 "PCIE_HPM_RX[0]_P")
			(pinfunction "PER0_P")
			(pintype "output")
		)
		(pad "44" smd rect
			(at 1.499 3.773 180)
			(size 0.3 1.55)
			(layers "F.Cu" "F.Mask" "F.Paste")
			(net 264 "Net-(J2-ALERT)")
			(pinfunction "ALERT")
			(pintype "output")
		)
		(pad "45" smd rect
			(at 1.749 -3.775 180)
			(size 0.3 1.55)
			(layers "F.Cu" "F.Mask" "F.Paste")
			(net 1 "GND")
			(pinfunction "GND")
			(pintype "passive")
		)
		(pad "46" smd rect
			(at 1.999 3.773 180)
			(size 0.3 1.55)
			(layers "F.Cu" "F.Mask" "F.Paste")
			(net 265 "unconnected-(J2-NC-Pad46)")
			(pinfunction "NC")
			(pintype "no_connect")
		)
		(pad "47" smd rect
			(at 2.249 -3.775 180)
			(size 0.3 1.55)
			(layers "F.Cu" "F.Mask" "F.Paste")
			(net 371 "/PCIe-connector/PCIE_HPM_TX0_C_N")
			(pinfunction "PET0_N")
			(pintype "input")
		)
		(pad "48" smd rect
			(at 2.499 3.773 180)
			(size 0.3 1.55)
			(layers "F.Cu" "F.Mask" "F.Paste")
			(net 266 "unconnected-(J2-NC-Pad48)")
			(pinfunction "NC")
			(pintype "no_connect")
		)
		(pad "49" smd rect
			(at 2.749 -3.775 180)
			(size 0.3 1.55)
			(layers "F.Cu" "F.Mask" "F.Paste")
			(net 369 "/PCIe-connector/PCIE_HPM_TX0_C_P")
			(pinfunction "PET0_P")
			(pintype "input")
		)
		(pad "50" smd rect
			(at 2.999 3.773 180)
			(size 0.3 1.55)
			(layers "F.Cu" "F.Mask" "F.Paste")
			(net 118 "PRSNT1_N")
			(pinfunction "~{PERST}")
			(pintype "input")
		)
		(pad "51" smd rect
			(at 3.249 -3.775 180)
			(size 0.3 1.55)
			(layers "F.Cu" "F.Mask" "F.Paste")
			(net 1 "GND")
			(pinfunction "GND")
			(pintype "passive")
		)
		(pad "52" smd rect
			(at 3.499 3.773 180)
			(size 0.3 1.55)
			(layers "F.Cu" "F.Mask" "F.Paste")
			(net 269 "Net-(J2-~{CLKREQ})")
			(pinfunction "~{CLKREQ}")
			(pintype "output")
		)
		(pad "53" smd rect
			(at 3.749 -3.775 180)
			(size 0.3 1.55)
			(layers "F.Cu" "F.Mask" "F.Paste")
			(net 360 "PCIE_HPM_CLK_N")
			(pinfunction "REFCLK_N")
			(pintype "input")
		)
		(pad "54" smd rect
			(at 3.999 3.773 180)
			(size 0.3 1.55)
			(layers "F.Cu" "F.Mask" "F.Paste")
			(net 270 "Net-(J2-~{PEWAKE})")
			(pinfunction "~{PEWAKE}")
			(pintype "input")
		)
		(pad "55" smd rect
			(at 4.248 -3.775 180)
			(size 0.3 1.55)
			(layers "F.Cu" "F.Mask" "F.Paste")
			(net 359 "PCIE_HPM_CLK_P")
			(pinfunction "REFCLK_P")
			(pintype "input")
		)
		(pad "56" smd rect
			(at 4.498 3.773 180)
			(size 0.3 1.55)
			(layers "F.Cu" "F.Mask" "F.Paste")
			(net 271 "unconnected-(J2-NC-Pad56)")
			(pinfunction "NC")
			(pintype "no_connect")
		)
		(pad "57" smd rect
			(at 4.748 -3.775 180)
			(size 0.3 1.55)
			(layers "F.Cu" "F.Mask" "F.Paste")
			(net 1 "GND")
			(pinfunction "GND")
			(pintype "passive")
		)
		(pad "58" smd rect
			(at 4.998 3.773 180)
			(size 0.3 1.55)
			(layers "F.Cu" "F.Mask" "F.Paste")
			(net 272 "unconnected-(J2-NC-Pad58)")
			(pinfunction "NC")
			(pintype "no_connect")
		)
		(pad "67" smd rect
			(at 7.248 -3.775 180)
			(size 0.3 1.55)
			(layers "F.Cu" "F.Mask" "F.Paste")
			(net 273 "unconnected-(J2-NC-Pad67)")
			(pinfunction "NC")
			(pintype "no_connect")
		)
		(pad "68" smd rect
			(at 7.498 3.773 180)
			(size 0.3 1.55)
			(layers "F.Cu" "F.Mask" "F.Paste")
			(net 278 "unconnected-(J2-SUSCLK-Pad68)")
			(pinfunction "SUSCLK")
			(pintype "input+no_connect")
		)
		(pad "69" smd rect
			(at 7.748 -3.775 180)
			(size 0.3 1.55)
			(layers "F.Cu" "F.Mask" "F.Paste")
			(net 280 "unconnected-(J2-NC-Pad69)")
			(pinfunction "NC")
			(pintype "no_connect")
		)
		(pad "70" smd rect
			(at 7.998 3.773 180)
			(size 0.3 1.55)
			(layers "F.Cu" "F.Mask" "F.Paste")
			(net 2 "VCC3V3")
			(pinfunction "3V3")
			(pintype "passive")
		)
		(pad "71" smd rect
			(at 8.247 -3.775 180)
			(size 0.3 1.55)
			(layers "F.Cu" "F.Mask" "F.Paste")
			(net 1 "GND")
			(pinfunction "GND")
			(pintype "passive")
		)
		(pad "72" smd rect
			(at 8.497 3.773 180)
			(size 0.3 1.55)
			(layers "F.Cu" "F.Mask" "F.Paste")
			(net 2 "VCC3V3")
			(pinfunction "3V3")
			(pintype "passive")
		)
		(pad "73" smd rect
			(at 8.747 -3.775 180)
			(size 0.3 1.55)
			(layers "F.Cu" "F.Mask" "F.Paste")
			(net 1 "GND")
			(pinfunction "GND")
			(pintype "passive")
		)
		(pad "74" smd rect
			(at 8.997 3.773 180)
			(size 0.3 1.55)
			(layers "F.Cu" "F.Mask" "F.Paste")
			(net 2 "VCC3V3")
			(pinfunction "3V3")
			(pintype "passive")
		)
		(pad "75" smd rect
			(at 9.247 -3.775 180)
			(size 0.3 1.55)
			(layers "F.Cu" "F.Mask" "F.Paste")
			(net 1 "GND")
			(pinfunction "GND")
			(pintype "passive")
		)
		(pad "MP1" smd rect
			(at -10.352 -3 180)
			(size 1.2 2.75)
			(layers "F.Cu" "F.Mask" "F.Paste")
			(net 1 "GND")
			(pinfunction "MP")
			(pintype "passive")
		)
		(pad "MP2" smd rect
			(at 10.349 -3 180)
			(size 1.2 2.75)
			(layers "F.Cu" "F.Mask" "F.Paste")
			(net 1 "GND")
			(pinfunction "MP")
			(pintype "passive")
		)
	)
	(footprint "antmicro-footprints:C_0402_1005Metric"
		(layer "F.Cu")
		(at 131.275 154.375 -90)
		(descr "Capacitor SMD 0402")
		(tags "capacitor SMD 0402")
		(property "Reference" "C34"
			(at -2.98 -0.33 90)
			(layer "F.SilkS")
			(effects
				(font
					(size 0.7 0.7)
					(thickness 0.15)
				)
				(justify right bottom)
			)
		)
		(property "Value" "C_10u_0402"
			(at 0 1.4 90)
			(layer "F.Fab")
			(effects
				(font
					(size 0.7 0.7)
					(thickness 0.15)
				)
				(justify right bottom)
			)
		)
		(property "Datasheet" "https://www.yageo.com/en/Chart/Download/pdf/CC0402MRX5R5BB106"
			(at 0 0 270)
			(layer "F.Fab")
			(hide yes)
			(effects
				(font
					(size 1.27 1.27)
					(thickness 0.15)
				)
			)
		)
		(property "Description" "SMD Multilayer Ceramic Capacitor, 10 µF, 6.3 V, 0402 [1005 Metric], ± 20%, X5R, CC Series"
			(at 0 0 270)
			(layer "F.Fab")
			(hide yes)
			(effects
				(font
					(size 1.27 1.27)
					(thickness 0.15)
				)
			)
		)
		(property "Author" "Antmicro"
			(at -23.1 285.65 0)
			(layer "F.Fab")
			(hide yes)
			(effects
				(font
					(size 1 1)
					(thickness 0.15)
				)
			)
		)
		(property "Dielectric" ""
			(at -23.1 285.65 0)
			(layer "F.Fab")
			(hide yes)
			(effects
				(font
					(size 1 1)
					(thickness 0.15)
				)
			)
		)
		(property "License" "Apache-2.0"
			(at -23.1 285.65 0)
			(layer "F.Fab")
			(hide yes)
			(effects
				(font
					(size 1 1)
					(thickness 0.15)
				)
			)
		)
		(property "MPN" "CC0402MRX5R5BB106"
			(at -23.1 285.65 0)
			(layer "F.Fab")
			(hide yes)
			(effects
				(font
					(size 1 1)
					(thickness 0.15)
				)
			)
		)
		(property "Manufacturer" "YAGEO"
			(at -23.1 285.65 0)
			(layer "F.Fab")
			(hide yes)
			(effects
				(font
					(size 1 1)
					(thickness 0.15)
				)
			)
		)
		(property "Val" "10u"
			(at -23.1 285.65 0)
			(layer "F.Fab")
			(hide yes)
			(effects
				(font
					(size 1 1)
					(thickness 0.15)
				)
			)
		)
		(property "Voltage" ""
			(at -23.1 285.65 0)
			(layer "F.Fab")
			(hide yes)
			(effects
				(font
					(size 1 1)
					(thickness 0.15)
				)
			)
		)
		(sheetname "/PCIe-connector/")
		(sheetfile "pcie-conn.kicad_sch")
		(attr smd)
		(fp_rect
			(start -0.925 -0.47)
			(end 0.925 0.47)
			(stroke
				(width 0.05)
				(type default)
			)
			(fill no)
			(layer "F.CrtYd")
		)
		(fp_line
			(start -0.494 0.248)
			(end -0.494 -0.25)
			(stroke
				(width 0.15)
				(type solid)
			)
			(layer "F.Fab")
		)
		(fp_line
			(start 0.504 0.248)
			(end -0.494 0.248)
			(stroke
				(width 0.15)
				(type solid)
			)
			(layer "F.Fab")
		)
		(fp_line
			(start -0.494 -0.25)
			(end 0.504 -0.25)
			(stroke
				(width 0.15)
				(type solid)
			)
			(layer "F.Fab")
		)
		(fp_line
			(start 0.504 -0.25)
			(end 0.504 0.248)
			(stroke
				(width 0.15)
				(type solid)
			)
			(layer "F.Fab")
		)
		(pad "1" smd roundrect
			(at -0.48 0 270)
			(size 0.59 0.64)
			(layers "F.Cu" "F.Mask" "F.Paste")
			(roundrect_rratio 0.25)
			(net 1 "GND")
			(pintype "passive")
		)
		(pad "2" smd roundrect
			(at 0.48 0 270)
			(size 0.59 0.64)
			(layers "F.Cu" "F.Mask" "F.Paste")
			(roundrect_rratio 0.25)
			(net 2 "VCC3V3")
			(pintype "passive")
		)
	)
	(footprint "antmicro-footprints:C_0402_1005Metric"
		(layer "F.Cu")
		(at 125.995 168.181 -90)
		(descr "Capacitor SMD 0402")
		(tags "capacitor SMD 0402")
		(property "Reference" "C28"
			(at 0.819 -0.404 90)
			(layer "F.SilkS")
			(effects
				(font
					(size 0.7 0.7)
					(thickness 0.15)
				)
				(justify right bottom)
			)
		)
		(property "Value" "C_100n_6V3_0402"
			(at 0 1.4 90)
			(layer "F.Fab")
			(effects
				(font
					(size 0.7 0.7)
					(thickness 0.15)
				)
				(justify right bottom)
			)
		)
		(property "Datasheet" "https://www.passivecomponent.com/wp-content/uploads/datasheet/WTC_MLCC_General_Purpose.pdf"
			(at 0 0 270)
			(layer "F.Fab")
			(hide yes)
			(effects
				(font
					(size 1.27 1.27)
					(thickness 0.15)
				)
			)
		)
		(property "Description" "SMT Multilayer Ceramic Capacitor, 0.1 µF, 6.3 V, 0402 [1005 Metric], ± 10%, X5R, Walsin MLCC"
			(at 0 0 270)
			(layer "F.Fab")
			(hide yes)
			(effects
				(font
					(size 1.27 1.27)
					(thickness 0.15)
				)
			)
		)
		(property "Author" "Antmicro"
			(at -42.186 294.176 0)
			(layer "F.Fab")
			(hide yes)
			(effects
				(font
					(size 1 1)
					(thickness 0.15)
				)
			)
		)
		(property "Dielectric" ""
			(at -42.186 294.176 0)
			(layer "F.Fab")
			(hide yes)
			(effects
				(font
					(size 1 1)
					(thickness 0.15)
				)
			)
		)
		(property "License" "Apache-2.0"
			(at -42.186 294.176 0)
			(layer "F.Fab")
			(hide yes)
			(effects
				(font
					(size 1 1)
					(thickness 0.15)
				)
			)
		)
		(property "MPN" "0402X104K6R3CT"
			(at -42.186 294.176 0)
			(layer "F.Fab")
			(hide yes)
			(effects
				(font
					(size 1 1)
					(thickness 0.15)
				)
			)
		)
		(property "Manufacturer" "Walsin"
			(at -42.186 294.176 0)
			(layer "F.Fab")
			(hide yes)
			(effects
				(font
					(size 1 1)
					(thickness 0.15)
				)
			)
		)
		(property "Public" "False"
			(at -42.186 294.176 0)
			(layer "F.Fab")
			(hide yes)
			(effects
				(font
					(size 1 1)
					(thickness 0.15)
				)
			)
		)
		(property "Val" "100n"
			(at -42.186 294.176 0)
			(layer "F.Fab")
			(hide yes)
			(effects
				(font
					(size 1 1)
					(thickness 0.15)
				)
			)
		)
		(property "Voltage" ""
			(at -42.186 294.176 0)
			(layer "F.Fab")
			(hide yes)
			(effects
				(font
					(size 1 1)
					(thickness 0.15)
				)
			)
		)
		(sheetname "/PCIe-connector/")
		(sheetfile "pcie-conn.kicad_sch")
		(attr smd)
		(fp_rect
			(start -0.925 -0.47)
			(end 0.925 0.47)
			(stroke
				(width 0.05)
				(type default)
			)
			(fill no)
			(layer "F.CrtYd")
		)
		(fp_line
			(start -0.494 0.248)
			(end -0.494 -0.25)
			(stroke
				(width 0.15)
				(type solid)
			)
			(layer "F.Fab")
		)
		(fp_line
			(start 0.504 0.248)
			(end -0.494 0.248)
			(stroke
				(width 0.15)
				(type solid)
			)
			(layer "F.Fab")
		)
		(fp_line
			(start -0.494 -0.25)
			(end 0.504 -0.25)
			(stroke
				(width 0.15)
				(type solid)
			)
			(layer "F.Fab")
		)
		(fp_line
			(start 0.504 -0.25)
			(end 0.504 0.248)
			(stroke
				(width 0.15)
				(type solid)
			)
			(layer "F.Fab")
		)
		(pad "1" smd roundrect
			(at -0.48 0 270)
			(size 0.59 0.64)
			(layers "F.Cu" "F.Mask" "F.Paste")
			(roundrect_rratio 0.25)
			(net 370 "/PCIe-connector/PCIE_HPM_TX1_C_P")
			(pintype "passive")
		)
		(pad "2" smd roundrect
			(at 0.48 0 270)
			(size 0.59 0.64)
			(layers "F.Cu" "F.Mask" "F.Paste")
			(roundrect_rratio 0.25)
			(net 352 "PCIE_HPM_TX[1]_P")
			(pintype "passive")
		)
	)
	(footprint "antmicro-footprints:C_0402_1005Metric"
		(layer "F.Cu")
		(at 127.005 168.181 -90)
		(descr "Capacitor SMD 0402")
		(tags "capacitor SMD 0402")
		(property "Reference" "C30"
			(at 0.819 -0.404 90)
			(layer "F.SilkS")
			(effects
				(font
					(size 0.7 0.7)
					(thickness 0.15)
				)
				(justify right bottom)
			)
		)
		(property "Value" "C_100n_6V3_0402"
			(at 0 1.4 90)
			(layer "F.Fab")
			(effects
				(font
					(size 0.7 0.7)
					(thickness 0.15)
				)
				(justify right bottom)
			)
		)
		(property "Datasheet" "https://www.passivecomponent.com/wp-content/uploads/datasheet/WTC_MLCC_General_Purpose.pdf"
			(at 0 0 270)
			(layer "F.Fab")
			(hide yes)
			(effects
				(font
					(size 1.27 1.27)
					(thickness 0.15)
				)
			)
		)
		(property "Description" "SMT Multilayer Ceramic Capacitor, 0.1 µF, 6.3 V, 0402 [1005 Metric], ± 10%, X5R, Walsin MLCC"
			(at 0 0 270)
			(layer "F.Fab")
			(hide yes)
			(effects
				(font
					(size 1.27 1.27)
					(thickness 0.15)
				)
			)
		)
		(property "Author" "Antmicro"
			(at -41.176 295.186 0)
			(layer "F.Fab")
			(hide yes)
			(effects
				(font
					(size 1 1)
					(thickness 0.15)
				)
			)
		)
		(property "Dielectric" ""
			(at -41.176 295.186 0)
			(layer "F.Fab")
			(hide yes)
			(effects
				(font
					(size 1 1)
					(thickness 0.15)
				)
			)
		)
		(property "License" "Apache-2.0"
			(at -41.176 295.186 0)
			(layer "F.Fab")
			(hide yes)
			(effects
				(font
					(size 1 1)
					(thickness 0.15)
				)
			)
		)
		(property "MPN" "0402X104K6R3CT"
			(at -41.176 295.186 0)
			(layer "F.Fab")
			(hide yes)
			(effects
				(font
					(size 1 1)
					(thickness 0.15)
				)
			)
		)
		(property "Manufacturer" "Walsin"
			(at -41.176 295.186 0)
			(layer "F.Fab")
			(hide yes)
			(effects
				(font
					(size 1 1)
					(thickness 0.15)
				)
			)
		)
		(property "Public" "False"
			(at -41.176 295.186 0)
			(layer "F.Fab")
			(hide yes)
			(effects
				(font
					(size 1 1)
					(thickness 0.15)
				)
			)
		)
		(property "Val" "100n"
			(at -41.176 295.186 0)
			(layer "F.Fab")
			(hide yes)
			(effects
				(font
					(size 1 1)
					(thickness 0.15)
				)
			)
		)
		(property "Voltage" ""
			(at -41.176 295.186 0)
			(layer "F.Fab")
			(hide yes)
			(effects
				(font
					(size 1 1)
					(thickness 0.15)
				)
			)
		)
		(sheetname "/PCIe-connector/")
		(sheetfile "pcie-conn.kicad_sch")
		(attr smd)
		(fp_rect
			(start -0.925 -0.47)
			(end 0.925 0.47)
			(stroke
				(width 0.05)
				(type default)
			)
			(fill no)
			(layer "F.CrtYd")
		)
		(fp_line
			(start -0.494 0.248)
			(end -0.494 -0.25)
			(stroke
				(width 0.15)
				(type solid)
			)
			(layer "F.Fab")
		)
		(fp_line
			(start 0.504 0.248)
			(end -0.494 0.248)
			(stroke
				(width 0.15)
				(type solid)
			)
			(layer "F.Fab")
		)
		(fp_line
			(start -0.494 -0.25)
			(end 0.504 -0.25)
			(stroke
				(width 0.15)
				(type solid)
			)
			(layer "F.Fab")
		)
		(fp_line
			(start 0.504 -0.25)
			(end 0.504 0.248)
			(stroke
				(width 0.15)
				(type solid)
			)
			(layer "F.Fab")
		)
		(pad "1" smd roundrect
			(at -0.48 0 270)
			(size 0.59 0.64)
			(layers "F.Cu" "F.Mask" "F.Paste")
			(roundrect_rratio 0.25)
			(net 372 "/PCIe-connector/PCIE_HPM_TX1_C_N")
			(pintype "passive")
		)
		(pad "2" smd roundrect
			(at 0.48 0 270)
			(size 0.59 0.64)
			(layers "F.Cu" "F.Mask" "F.Paste")
			(roundrect_rratio 0.25)
			(net 354 "PCIE_HPM_TX[1]_N")
			(pintype "passive")
		)
	)
	(footprint "antmicro-footprints:C_0402_1005Metric"
		(layer "F.Cu")
		(at 134.77 154.48 -90)
		(descr "Capacitor SMD 0402")
		(tags "capacitor SMD 0402")
		(property "Reference" "C32"
			(at -2.98 -0.33 90)
			(layer "F.SilkS")
			(effects
				(font
					(size 0.7 0.7)
					(thickness 0.15)
				)
				(justify right bottom)
			)
		)
		(property "Value" "C_10u_0402"
			(at 0 1.4 90)
			(layer "F.Fab")
			(effects
				(font
					(size 0.7 0.7)
					(thickness 0.15)
				)
				(justify right bottom)
			)
		)
		(property "Datasheet" "https://www.yageo.com/en/Chart/Download/pdf/CC0402MRX5R5BB106"
			(at 0 0 270)
			(layer "F.Fab")
			(hide yes)
			(effects
				(font
					(size 1.27 1.27)
					(thickness 0.15)
				)
			)
		)
		(property "Description" "SMD Multilayer Ceramic Capacitor, 10 µF, 6.3 V, 0402 [1005 Metric], ± 20%, X5R, CC Series"
			(at 0 0 270)
			(layer "F.Fab")
			(hide yes)
			(effects
				(font
					(size 1.27 1.27)
					(thickness 0.15)
				)
			)
		)
		(property "Author" "Antmicro"
			(at -19.71 289.25 0)
			(layer "F.Fab")
			(hide yes)
			(effects
				(font
					(size 1 1)
					(thickness 0.15)
				)
			)
		)
		(property "Dielectric" ""
			(at -19.71 289.25 0)
			(layer "F.Fab")
			(hide yes)
			(effects
				(font
					(size 1 1)
					(thickness 0.15)
				)
			)
		)
		(property "License" "Apache-2.0"
			(at -19.71 289.25 0)
			(layer "F.Fab")
			(hide yes)
			(effects
				(font
					(size 1 1)
					(thickness 0.15)
				)
			)
		)
		(property "MPN" "CC0402MRX5R5BB106"
			(at -19.71 289.25 0)
			(layer "F.Fab")
			(hide yes)
			(effects
				(font
					(size 1 1)
					(thickness 0.15)
				)
			)
		)
		(property "Manufacturer" "YAGEO"
			(at -19.71 289.25 0)
			(layer "F.Fab")
			(hide yes)
			(effects
				(font
					(size 1 1)
					(thickness 0.15)
				)
			)
		)
		(property "Val" "10u"
			(at -19.71 289.25 0)
			(layer "F.Fab")
			(hide yes)
			(effects
				(font
					(size 1 1)
					(thickness 0.15)
				)
			)
		)
		(property "Voltage" ""
			(at -19.71 289.25 0)
			(layer "F.Fab")
			(hide yes)
			(effects
				(font
					(size 1 1)
					(thickness 0.15)
				)
			)
		)
		(sheetname "/PCIe-connector/")
		(sheetfile "pcie-conn.kicad_sch")
		(attr smd)
		(fp_rect
			(start -0.925 -0.47)
			(end 0.925 0.47)
			(stroke
				(width 0.05)
				(type default)
			)
			(fill no)
			(layer "F.CrtYd")
		)
		(fp_line
			(start -0.494 0.248)
			(end -0.494 -0.25)
			(stroke
				(width 0.15)
				(type solid)
			)
			(layer "F.Fab")
		)
		(fp_line
			(start 0.504 0.248)
			(end -0.494 0.248)
			(stroke
				(width 0.15)
				(type solid)
			)
			(layer "F.Fab")
		)
		(fp_line
			(start -0.494 -0.25)
			(end 0.504 -0.25)
			(stroke
				(width 0.15)
				(type solid)
			)
			(layer "F.Fab")
		)
		(fp_line
			(start 0.504 -0.25)
			(end 0.504 0.248)
			(stroke
				(width 0.15)
				(type solid)
			)
			(layer "F.Fab")
		)
		(pad "1" smd roundrect
			(at -0.48 0 270)
			(size 0.59 0.64)
			(layers "F.Cu" "F.Mask" "F.Paste")
			(roundrect_rratio 0.25)
			(net 1 "GND")
			(pintype "passive")
		)
		(pad "2" smd roundrect
			(at 0.48 0 270)
			(size 0.59 0.64)
			(layers "F.Cu" "F.Mask" "F.Paste")
			(roundrect_rratio 0.25)
			(net 2 "VCC3V3")
			(pintype "passive")
		)
	)
	(footprint "antmicro-footprints:C_0402_1005Metric"
		(layer "F.Cu")
		(at 117.475 154.575 -90)
		(descr "Capacitor SMD 0402")
		(tags "capacitor SMD 0402")
		(property "Reference" "C33"
			(at -2.975 -0.325 90)
			(layer "F.SilkS")
			(effects
				(font
					(size 0.7 0.7)
					(thickness 0.15)
				)
				(justify right bottom)
			)
		)
		(property "Value" "C_10u_0402"
			(at 0 1.4 90)
			(layer "F.Fab")
			(effects
				(font
					(size 0.7 0.7)
					(thickness 0.15)
				)
				(justify right bottom)
			)
		)
		(property "Datasheet" "https://www.yageo.com/en/Chart/Download/pdf/CC0402MRX5R5BB106"
			(at 0 0 270)
			(layer "F.Fab")
			(hide yes)
			(effects
				(font
					(size 1.27 1.27)
					(thickness 0.15)
				)
			)
		)
		(property "Description" "SMD Multilayer Ceramic Capacitor, 10 µF, 6.3 V, 0402 [1005 Metric], ± 20%, X5R, CC Series"
			(at 0 0 270)
			(layer "F.Fab")
			(hide yes)
			(effects
				(font
					(size 1.27 1.27)
					(thickness 0.15)
				)
			)
		)
		(property "Author" "Antmicro"
			(at -37.1 272.05 0)
			(layer "F.Fab")
			(hide yes)
			(effects
				(font
					(size 1 1)
					(thickness 0.15)
				)
			)
		)
		(property "Dielectric" ""
			(at -37.1 272.05 0)
			(layer "F.Fab")
			(hide yes)
			(effects
				(font
					(size 1 1)
					(thickness 0.15)
				)
			)
		)
		(property "License" "Apache-2.0"
			(at -37.1 272.05 0)
			(layer "F.Fab")
			(hide yes)
			(effects
				(font
					(size 1 1)
					(thickness 0.15)
				)
			)
		)
		(property "MPN" "CC0402MRX5R5BB106"
			(at -37.1 272.05 0)
			(layer "F.Fab")
			(hide yes)
			(effects
				(font
					(size 1 1)
					(thickness 0.15)
				)
			)
		)
		(property "Manufacturer" "YAGEO"
			(at -37.1 272.05 0)
			(layer "F.Fab")
			(hide yes)
			(effects
				(font
					(size 1 1)
					(thickness 0.15)
				)
			)
		)
		(property "Val" "10u"
			(at -37.1 272.05 0)
			(layer "F.Fab")
			(hide yes)
			(effects
				(font
					(size 1 1)
					(thickness 0.15)
				)
			)
		)
		(property "Voltage" ""
			(at -37.1 272.05 0)
			(layer "F.Fab")
			(hide yes)
			(effects
				(font
					(size 1 1)
					(thickness 0.15)
				)
			)
		)
		(sheetname "/PCIe-connector/")
		(sheetfile "pcie-conn.kicad_sch")
		(attr smd)
		(fp_rect
			(start -0.925 -0.47)
			(end 0.925 0.47)
			(stroke
				(width 0.05)
				(type default)
			)
			(fill no)
			(layer "F.CrtYd")
		)
		(fp_line
			(start -0.494 0.248)
			(end -0.494 -0.25)
			(stroke
				(width 0.15)
				(type solid)
			)
			(layer "F.Fab")
		)
		(fp_line
			(start 0.504 0.248)
			(end -0.494 0.248)
			(stroke
				(width 0.15)
				(type solid)
			)
			(layer "F.Fab")
		)
		(fp_line
			(start -0.494 -0.25)
			(end 0.504 -0.25)
			(stroke
				(width 0.15)
				(type solid)
			)
			(layer "F.Fab")
		)
		(fp_line
			(start 0.504 -0.25)
			(end 0.504 0.248)
			(stroke
				(width 0.15)
				(type solid)
			)
			(layer "F.Fab")
		)
		(pad "1" smd roundrect
			(at -0.48 0 270)
			(size 0.59 0.64)
			(layers "F.Cu" "F.Mask" "F.Paste")
			(roundrect_rratio 0.25)
			(net 1 "GND")
			(pintype "passive")
		)
		(pad "2" smd roundrect
			(at 0.48 0 270)
			(size 0.59 0.64)
			(layers "F.Cu" "F.Mask" "F.Paste")
			(roundrect_rratio 0.25)
			(net 2 "VCC3V3")
			(pintype "passive")
		)
	)
	(footprint "antmicro-footprints:LED_0603_1608Metric_G"
		(layer "F.Cu")
		(at 138.575 157.875 -90)
		(descr "LED SMD 0603 Green")
		(tags "LED SMD 0603 Green")
		(property "Reference" "D1"
			(at -2.775 -0.425 90)
			(layer "F.SilkS")
			(effects
				(font
					(size 0.7 0.7)
					(thickness 0.15)
				)
				(justify right bottom)
			)
		)
		(property "Value" "LED_G_0603_KP-1608CGCK"
			(at 0 1.6 90)
			(layer "F.Fab")
			(effects
				(font
					(size 0.7 0.7)
					(thickness 0.15)
				)
				(justify right bottom)
			)
		)
		(property "Datasheet" "http://www.kingbright.com/attachments/file/psearch//000/00/00/KP-1608CGCK(Ver.23B).pdf"
			(at 0 0 270)
			(layer "F.Fab")
			(hide yes)
			(effects
				(font
					(size 1.27 1.27)
					(thickness 0.15)
				)
			)
		)
		(property "Description" "LED, Green, SMD, 0603, 20 mA, 2.1 V, 570 nm"
			(at 0 0 270)
			(layer "F.Fab")
			(hide yes)
			(effects
				(font
					(size 1.27 1.27)
					(thickness 0.15)
				)
			)
		)
		(property "Author" "Antmicro"
			(at -19.3 296.45 0)
			(layer "F.Fab")
			(hide yes)
			(effects
				(font
					(size 1 1)
					(thickness 0.15)
				)
			)
		)
		(property "Color" "Green"
			(at -19.3 296.45 0)
			(layer "F.Fab")
			(hide yes)
			(effects
				(font
					(size 1 1)
					(thickness 0.15)
				)
			)
		)
		(property "License" "Apache-2.0"
			(at -19.3 296.45 0)
			(layer "F.Fab")
			(hide yes)
			(effects
				(font
					(size 1 1)
					(thickness 0.15)
				)
			)
		)
		(property "MPN" "KP-1608CGCK"
			(at -19.3 296.45 0)
			(layer "F.Fab")
			(hide yes)
			(effects
				(font
					(size 1 1)
					(thickness 0.15)
				)
			)
		)
		(property "Manufacturer" "Kingbright"
			(at -19.3 296.45 0)
			(layer "F.Fab")
			(hide yes)
			(effects
				(font
					(size 1 1)
					(thickness 0.15)
				)
			)
		)
		(sheetname "/PCIe-connector/")
		(sheetfile "pcie-conn.kicad_sch")
		(attr smd)
		(fp_line
			(start 0.22 0.35)
			(end -0.22 0.35)
			(stroke
				(width 0.15)
				(type solid)
			)
			(layer "F.SilkS")
		)
		(fp_line
			(start -0.094672 0.201008)
			(end -0.094672 -0.198992)
			(stroke
				(width 0.1)
				(type solid)
			)
			(layer "F.SilkS")
		)
		(fp_line
			(start 0.105328 0.201008)
			(end -0.094672 0.001008)
			(stroke
				(width 0.1)
				(type solid)
			)
			(layer "F.SilkS")
		)
		(fp_line
			(start 0.105328 0.201008)
			(end 0.105328 -0.198992)
			(stroke
				(width 0.1)
				(type solid)
			)
			(layer "F.SilkS")
		)
		(fp_line
			(start -0.094672 0.001008)
			(end -0.24 0.001008)
			(stroke
				(width 0.1)
				(type solid)
			)
			(layer "F.SilkS")
		)
		(fp_line
			(start -0.094672 0.001008)
			(end 0.105328 -0.198992)
			(stroke
				(width 0.1)
				(type solid)
			)
			(layer "F.SilkS")
		)
		(fp_line
			(start 0.105328 0.001008)
			(end 0.24 0.001)
			(stroke
				(width 0.1)
				(type solid)
			)
			(layer "F.SilkS")
		)
		(fp_line
			(start -1.18 -0.319)
			(end -1.18 0.321)
			(stroke
				(width 0.15)
				(type solid)
			)
			(layer "F.SilkS")
		)
		(fp_line
			(start 0.22 -0.35)
			(end -0.22 -0.35)
			(stroke
				(width 0.15)
				(type solid)
			)
			(layer "F.SilkS")
		)
		(fp_rect
			(start 1.25 0.65)
			(end -1.25 -0.65)
			(stroke
				(width 0.05)
				(type solid)
			)
			(fill no)
			(layer "F.CrtYd")
		)
		(fp_line
			(start -0.199 0.2)
			(end -0.199 0.1)
			(stroke
				(width 0.15)
				(type solid)
			)
			(layer "F.Fab")
		)
		(fp_line
			(start 0.201 0.2)
			(end 0.201 0)
			(stroke
				(width 0.15)
				(type solid)
			)
			(layer "F.Fab")
		)
		(fp_line
			(start -0.199 0)
			(end -0.597 0)
			(stroke
				(width 0.15)
				(type solid)
			)
			(layer "F.Fab")
		)
		(fp_line
			(start -0.101 0)
			(end 0.201 0.2)
			(stroke
				(width 0.15)
				(type solid)
			)
			(layer "F.Fab")
		)
		(fp_line
			(start 0.201 0)
			(end 0.201 -0.202)
			(stroke
				(width 0.15)
				(type solid)
			)
			(layer "F.Fab")
		)
		(fp_line
			(start 0.599 0)
			(end 0.201 0)
			(stroke
				(width 0.15)
				(type solid)
			)
			(layer "F.Fab")
		)
		(fp_line
			(start -0.199 -0.202)
			(end -0.199 0.1)
			(stroke
				(width 0.15)
				(type solid)
			)
			(layer "F.Fab")
		)
		(fp_line
			(start 0.201 -0.202)
			(end -0.101 0)
			(stroke
				(width 0.15)
				(type solid)
			)
			(layer "F.Fab")
		)
		(fp_rect
			(start 0.848 0.4)
			(end -0.85 -0.402)
			(stroke
				(width 0.15)
				(type solid)
			)
			(fill no)
			(layer "F.Fab")
		)
		(pad "1" smd roundrect
			(at -0.7 0 90)
			(size 0.8 1)
			(layers "F.Cu" "F.Mask" "F.Paste")
			(roundrect_rratio 0.2)
			(net 527 "/PCIe-connector/NVME_LED")
			(pinfunction "C")
			(pintype "passive")
		)
		(pad "2" smd roundrect
			(at 0.7 0 90)
			(size 0.8 1)
			(layers "F.Cu" "F.Mask" "F.Paste")
			(roundrect_rratio 0.2)
			(net 112 "Net-(D1-A)")
			(pinfunction "A")
			(pintype "passive")
		)
	)
	(footprint "antmicro-footprints:R_0402_1005Metric"
		(layer "F.Cu")
		(at 122.5 154.21 -90)
		(descr "Resistor SMD 0402")
		(tags "resistor SMD 0402")
		(property "Reference" "R17"
			(at -2.92 -0.33 90)
			(layer "F.SilkS")
			(effects
				(font
					(size 0.7 0.7)
					(thickness 0.15)
				)
				(justify right bottom)
			)
		)
		(property "Value" "R_10k_0402"
			(at 0 1.4 90)
			(layer "F.Fab")
			(effects
				(font
					(size 0.7 0.7)
					(thickness 0.15)
				)
				(justify right bottom)
			)
		)
		(property "Datasheet" "https://www.bourns.com/docs/product-datasheets/cr.pdf"
			(at 0 0 270)
			(layer "F.Fab")
			(hide yes)
			(effects
				(font
					(size 1.27 1.27)
					(thickness 0.15)
				)
			)
		)
		(property "Description" "SMD Chip Resistor, 10 kohm, ± 1%, 62.5 mW, 0402 [1005 Metric], Thick Film, General Purpose"
			(at 0 0 270)
			(layer "F.Fab")
			(hide yes)
			(effects
				(font
					(size 1.27 1.27)
					(thickness 0.15)
				)
			)
		)
		(property "Author" "Antmicro"
			(at -31.71 276.71 0)
			(layer "F.Fab")
			(hide yes)
			(effects
				(font
					(size 1 1)
					(thickness 0.15)
				)
			)
		)
		(property "License" "Apache-2.0"
			(at -31.71 276.71 0)
			(layer "F.Fab")
			(hide yes)
			(effects
				(font
					(size 1 1)
					(thickness 0.15)
				)
			)
		)
		(property "MPN" "CR0402-FX-1002GLF"
			(at -31.71 276.71 0)
			(layer "F.Fab")
			(hide yes)
			(effects
				(font
					(size 1 1)
					(thickness 0.15)
				)
			)
		)
		(property "Manufacturer" "Bourns"
			(at -31.71 276.71 0)
			(layer "F.Fab")
			(hide yes)
			(effects
				(font
					(size 1 1)
					(thickness 0.15)
				)
			)
		)
		(property "Tolerance" "1%"
			(at -31.71 276.71 0)
			(layer "F.Fab")
			(hide yes)
			(effects
				(font
					(size 1 1)
					(thickness 0.15)
				)
			)
		)
		(property "Val" "10k"
			(at -31.71 276.71 0)
			(layer "F.Fab")
			(hide yes)
			(effects
				(font
					(size 1 1)
					(thickness 0.15)
				)
			)
		)
		(sheetname "/PCIe-connector/")
		(sheetfile "pcie-conn.kicad_sch")
		(attr smd)
		(fp_rect
			(start -0.925 -0.47)
			(end 0.925 0.47)
			(stroke
				(width 0.05)
				(type default)
			)
			(fill no)
			(layer "F.CrtYd")
		)
		(fp_rect
			(start -0.5 -0.25)
			(end 0.5 0.25)
			(stroke
				(width 0.15)
				(type solid)
			)
			(fill no)
			(layer "F.Fab")
		)
		(pad "1" smd roundrect
			(at -0.48 0 270)
			(size 0.59 0.64)
			(layers "F.Cu" "F.Mask" "F.Paste")
			(roundrect_rratio 0.25)
			(net 2 "VCC3V3")
			(pintype "passive")
		)
		(pad "2" smd roundrect
			(at 0.48 0 270)
			(size 0.59 0.64)
			(layers "F.Cu" "F.Mask" "F.Paste")
			(roundrect_rratio 0.25)
			(net 269 "Net-(J2-~{CLKREQ})")
			(pintype "passive")
		)
	)
	(footprint "antmicro-footprints:R_0402_1005Metric"
		(layer "F.Cu")
		(at 139.065 160.465)
		(descr "Resistor SMD 0402")
		(tags "resistor SMD 0402")
		(property "Reference" "R18"
			(at -1.065 1.335 0)
			(layer "F.SilkS")
			(effects
				(font
					(size 0.7 0.7)
					(thickness 0.15)
				)
				(justify left bottom)
			)
		)
		(property "Value" "R_330R_0402"
			(at 0 1.4 0)
			(layer "F.Fab")
			(effects
				(font
					(size 0.7 0.7)
					(thickness 0.15)
				)
				(justify left bottom)
			)
		)
		(property "Datasheet" "https://www.bourns.com/docs/product-datasheets/cr.pdf"
			(at 0 0 0)
			(layer "F.Fab")
			(hide yes)
			(effects
				(font
					(size 1.27 1.27)
					(thickness 0.15)
				)
			)
		)
		(property "Description" "SMD Chip Resistor, 330 ohm, ± 1%, 62.5 mW, 0402 [1005 Metric], Thick Film, General Purpose"
			(at 0 0 0)
			(layer "F.Fab")
			(hide yes)
			(effects
				(font
					(size 1.27 1.27)
					(thickness 0.15)
				)
			)
		)
		(property "Author" "Antmicro"
			(at 0 0 0)
			(layer "F.Fab")
			(hide yes)
			(effects
				(font
					(size 1 1)
					(thickness 0.15)
				)
			)
		)
		(property "License" "Apache-2.0"
			(at 0 0 0)
			(layer "F.Fab")
			(hide yes)
			(effects
				(font
					(size 1 1)
					(thickness 0.15)
				)
			)
		)
		(property "MPN" "CR0402-FX-3300GLF"
			(at 0 0 0)
			(layer "F.Fab")
			(hide yes)
			(effects
				(font
					(size 1 1)
					(thickness 0.15)
				)
			)
		)
		(property "Manufacturer" "Bourns"
			(at 0 0 0)
			(layer "F.Fab")
			(hide yes)
			(effects
				(font
					(size 1 1)
					(thickness 0.15)
				)
			)
		)
		(property "Tolerance" "1%"
			(at 0 0 0)
			(layer "F.Fab")
			(hide yes)
			(effects
				(font
					(size 1 1)
					(thickness 0.15)
				)
			)
		)
		(property "Val" "330R"
			(at 0 0 0)
			(layer "F.Fab")
			(hide yes)
			(effects
				(font
					(size 1 1)
					(thickness 0.15)
				)
			)
		)
		(sheetname "/PCIe-connector/")
		(sheetfile "pcie-conn.kicad_sch")
		(attr smd)
		(fp_rect
			(start -0.925 -0.47)
			(end 0.925 0.47)
			(stroke
				(width 0.05)
				(type default)
			)
			(fill no)
			(layer "F.CrtYd")
		)
		(fp_rect
			(start -0.5 -0.25)
			(end 0.5 0.25)
			(stroke
				(width 0.15)
				(type solid)
			)
			(fill no)
			(layer "F.Fab")
		)
		(pad "1" smd roundrect
			(at -0.48 0)
			(size 0.59 0.64)
			(layers "F.Cu" "F.Mask" "F.Paste")
			(roundrect_rratio 0.25)
			(net 112 "Net-(D1-A)")
			(pintype "passive")
		)
		(pad "2" smd roundrect
			(at 0.48 0)
			(size 0.59 0.64)
			(layers "F.Cu" "F.Mask" "F.Paste")
			(roundrect_rratio 0.25)
			(net 2 "VCC3V3")
			(pintype "passive")
		)
	)
	(footprint "antmicro-footprints:R_0402_1005Metric"
		(layer "F.Cu")
		(at 123.54 154.21 -90)
		(descr "Resistor SMD 0402")
		(tags "resistor SMD 0402")
		(property "Reference" "R19"
			(at -2.92 -0.33 90)
			(layer "F.SilkS")
			(effects
				(font
					(size 0.7 0.7)
					(thickness 0.15)
				)
				(justify right bottom)
			)
		)
		(property "Value" "R_10k_0402"
			(at 0 1.4 90)
			(layer "F.Fab")
			(effects
				(font
					(size 0.7 0.7)
					(thickness 0.15)
				)
				(justify right bottom)
			)
		)
		(property "Datasheet" "https://www.bourns.com/docs/product-datasheets/cr.pdf"
			(at 0 0 270)
			(layer "F.Fab")
			(hide yes)
			(effects
				(font
					(size 1.27 1.27)
					(thickness 0.15)
				)
			)
		)
		(property "Description" "SMD Chip Resistor, 10 kohm, ± 1%, 62.5 mW, 0402 [1005 Metric], Thick Film, General Purpose"
			(at 0 0 270)
			(layer "F.Fab")
			(hide yes)
			(effects
				(font
					(size 1.27 1.27)
					(thickness 0.15)
				)
			)
		)
		(property "Author" "Antmicro"
			(at -30.67 277.75 0)
			(layer "F.Fab")
			(hide yes)
			(effects
				(font
					(size 1 1)
					(thickness 0.15)
				)
			)
		)
		(property "License" "Apache-2.0"
			(at -30.67 277.75 0)
			(layer "F.Fab")
			(hide yes)
			(effects
				(font
					(size 1 1)
					(thickness 0.15)
				)
			)
		)
		(property "MPN" "CR0402-FX-1002GLF"
			(at -30.67 277.75 0)
			(layer "F.Fab")
			(hide yes)
			(effects
				(font
					(size 1 1)
					(thickness 0.15)
				)
			)
		)
		(property "Manufacturer" "Bourns"
			(at -30.67 277.75 0)
			(layer "F.Fab")
			(hide yes)
			(effects
				(font
					(size 1 1)
					(thickness 0.15)
				)
			)
		)
		(property "Tolerance" "1%"
			(at -30.67 277.75 0)
			(layer "F.Fab")
			(hide yes)
			(effects
				(font
					(size 1 1)
					(thickness 0.15)
				)
			)
		)
		(property "Val" "10k"
			(at -30.67 277.75 0)
			(layer "F.Fab")
			(hide yes)
			(effects
				(font
					(size 1 1)
					(thickness 0.15)
				)
			)
		)
		(sheetname "/PCIe-connector/")
		(sheetfile "pcie-conn.kicad_sch")
		(attr smd)
		(fp_rect
			(start -0.925 -0.47)
			(end 0.925 0.47)
			(stroke
				(width 0.05)
				(type default)
			)
			(fill no)
			(layer "F.CrtYd")
		)
		(fp_rect
			(start -0.5 -0.25)
			(end 0.5 0.25)
			(stroke
				(width 0.15)
				(type solid)
			)
			(fill no)
			(layer "F.Fab")
		)
		(pad "1" smd roundrect
			(at -0.48 0 270)
			(size 0.59 0.64)
			(layers "F.Cu" "F.Mask" "F.Paste")
			(roundrect_rratio 0.25)
			(net 2 "VCC3V3")
			(pintype "passive")
		)
		(pad "2" smd roundrect
			(at 0.48 0 270)
			(size 0.59 0.64)
			(layers "F.Cu" "F.Mask" "F.Paste")
			(roundrect_rratio 0.25)
			(net 118 "PRSNT1_N")
			(pintype "passive")
		)
	)
	(footprint "antmicro-footprints:C_0402_1005Metric"
		(layer "F.Cu")
		(at 99.375 161.875 90)
		(descr "Capacitor SMD 0402")
		(tags "capacitor SMD 0402")
		(property "Reference" "C40"
			(at -1.025 -0.675 90)
			(layer "F.SilkS")
			(effects
				(font
					(size 0.7 0.7)
					(thickness 0.15)
				)
				(justify left bottom)
			)
		)
		(property "Value" "C_10u_0402"
			(at 0 1.4 90)
			(layer "F.Fab")
			(effects
				(font
					(size 0.7 0.7)
					(thickness 0.15)
				)
				(justify left bottom)
			)
		)
		(property "Datasheet" "https://www.yageo.com/en/Chart/Download/pdf/CC0402MRX5R5BB106"
			(at 0 0 90)
			(layer "F.Fab")
			(hide yes)
			(effects
				(font
					(size 1.27 1.27)
					(thickness 0.15)
				)
			)
		)
		(property "Description" "SMD Multilayer Ceramic Capacitor, 10 µF, 6.3 V, 0402 [1005 Metric], ± 20%, X5R, CC Series"
			(at 0 0 90)
			(layer "F.Fab")
			(hide yes)
			(effects
				(font
					(size 1.27 1.27)
					(thickness 0.15)
				)
			)
		)
		(property "Author" "Antmicro"
			(at 261.25 62.5 0)
			(layer "F.Fab")
			(hide yes)
			(effects
				(font
					(size 1 1)
					(thickness 0.15)
				)
			)
		)
		(property "Dielectric" ""
			(at 261.25 62.5 0)
			(layer "F.Fab")
			(hide yes)
			(effects
				(font
					(size 1 1)
					(thickness 0.15)
				)
			)
		)
		(property "License" "Apache-2.0"
			(at 261.25 62.5 0)
			(layer "F.Fab")
			(hide yes)
			(effects
				(font
					(size 1 1)
					(thickness 0.15)
				)
			)
		)
		(property "MPN" "CC0402MRX5R5BB106"
			(at 261.25 62.5 0)
			(layer "F.Fab")
			(hide yes)
			(effects
				(font
					(size 1 1)
					(thickness 0.15)
				)
			)
		)
		(property "Manufacturer" "YAGEO"
			(at 261.25 62.5 0)
			(layer "F.Fab")
			(hide yes)
			(effects
				(font
					(size 1 1)
					(thickness 0.15)
				)
			)
		)
		(property "Val" "10u"
			(at 261.25 62.5 0)
			(layer "F.Fab")
			(hide yes)
			(effects
				(font
					(size 1 1)
					(thickness 0.15)
				)
			)
		)
		(property "Voltage" ""
			(at 261.25 62.5 0)
			(layer "F.Fab")
			(hide yes)
			(effects
				(font
					(size 1 1)
					(thickness 0.15)
				)
			)
		)
		(sheetname "/DDR3/")
		(sheetfile "ddr3.kicad_sch")
		(attr smd)
		(fp_rect
			(start -0.925 -0.47)
			(end 0.925 0.47)
			(stroke
				(width 0.05)
				(type default)
			)
			(fill no)
			(layer "F.CrtYd")
		)
		(fp_line
			(start 0.504 -0.25)
			(end 0.504 0.248)
			(stroke
				(width 0.15)
				(type solid)
			)
			(layer "F.Fab")
		)
		(fp_line
			(start -0.494 -0.25)
			(end 0.504 -0.25)
			(stroke
				(width 0.15)
				(type solid)
			)
			(layer "F.Fab")
		)
		(fp_line
			(start 0.504 0.248)
			(end -0.494 0.248)
			(stroke
				(width 0.15)
				(type solid)
			)
			(layer "F.Fab")
		)
		(fp_line
			(start -0.494 0.248)
			(end -0.494 -0.25)
			(stroke
				(width 0.15)
				(type solid)
			)
			(layer "F.Fab")
		)
		(pad "1" smd roundrect
			(at -0.48 0 90)
			(size 0.59 0.64)
			(layers "F.Cu" "F.Mask" "F.Paste")
			(roundrect_rratio 0.25)
			(net 1 "GND")
			(pintype "passive")
		)
		(pad "2" smd roundrect
			(at 0.48 0 90)
			(size 0.59 0.64)
			(layers "F.Cu" "F.Mask" "F.Paste")
			(roundrect_rratio 0.25)
			(net 143 "/DDR3/DDR3_VTT")
			(pintype "passive")
		)
	)
	(footprint "antmicro-footprints:C_0402_1005Metric"
		(layer "F.Cu")
		(at 98.3 159.8 90)
		(descr "Capacitor SMD 0402")
		(tags "capacitor SMD 0402")
		(property "Reference" "C41"
			(at -1.2 -1.6 90)
			(layer "F.SilkS")
			(effects
				(font
					(size 0.7 0.7)
					(thickness 0.15)
				)
				(justify left bottom)
			)
		)
		(property "Value" "C_10u_0402"
			(at 0 1.4 90)
			(layer "F.Fab")
			(effects
				(font
					(size 0.7 0.7)
					(thickness 0.15)
				)
				(justify left bottom)
			)
		)
		(property "Datasheet" "https://www.yageo.com/en/Chart/Download/pdf/CC0402MRX5R5BB106"
			(at 0 0 90)
			(layer "F.Fab")
			(hide yes)
			(effects
				(font
					(size 1.27 1.27)
					(thickness 0.15)
				)
			)
		)
		(property "Description" "SMD Multilayer Ceramic Capacitor, 10 µF, 6.3 V, 0402 [1005 Metric], ± 20%, X5R, CC Series"
			(at 0 0 90)
			(layer "F.Fab")
			(hide yes)
			(effects
				(font
					(size 1.27 1.27)
					(thickness 0.15)
				)
			)
		)
		(property "Author" "Antmicro"
			(at 258.1 61.5 0)
			(layer "F.Fab")
			(hide yes)
			(effects
				(font
					(size 1 1)
					(thickness 0.15)
				)
			)
		)
		(property "Dielectric" ""
			(at 258.1 61.5 0)
			(layer "F.Fab")
			(hide yes)
			(effects
				(font
					(size 1 1)
					(thickness 0.15)
				)
			)
		)
		(property "License" "Apache-2.0"
			(at 258.1 61.5 0)
			(layer "F.Fab")
			(hide yes)
			(effects
				(font
					(size 1 1)
					(thickness 0.15)
				)
			)
		)
		(property "MPN" "CC0402MRX5R5BB106"
			(at 258.1 61.5 0)
			(layer "F.Fab")
			(hide yes)
			(effects
				(font
					(size 1 1)
					(thickness 0.15)
				)
			)
		)
		(property "Manufacturer" "YAGEO"
			(at 258.1 61.5 0)
			(layer "F.Fab")
			(hide yes)
			(effects
				(font
					(size 1 1)
					(thickness 0.15)
				)
			)
		)
		(property "Val" "10u"
			(at 258.1 61.5 0)
			(layer "F.Fab")
			(hide yes)
			(effects
				(font
					(size 1 1)
					(thickness 0.15)
				)
			)
		)
		(property "Voltage" ""
			(at 258.1 61.5 0)
			(layer "F.Fab")
			(hide yes)
			(effects
				(font
					(size 1 1)
					(thickness 0.15)
				)
			)
		)
		(sheetname "/DDR3/")
		(sheetfile "ddr3.kicad_sch")
		(attr smd)
		(fp_rect
			(start -0.925 -0.47)
			(end 0.925 0.47)
			(stroke
				(width 0.05)
				(type default)
			)
			(fill no)
			(layer "F.CrtYd")
		)
		(fp_line
			(start 0.504 -0.25)
			(end 0.504 0.248)
			(stroke
				(width 0.15)
				(type solid)
			)
			(layer "F.Fab")
		)
		(fp_line
			(start -0.494 -0.25)
			(end 0.504 -0.25)
			(stroke
				(width 0.15)
				(type solid)
			)
			(layer "F.Fab")
		)
		(fp_line
			(start 0.504 0.248)
			(end -0.494 0.248)
			(stroke
				(width 0.15)
				(type solid)
			)
			(layer "F.Fab")
		)
		(fp_line
			(start -0.494 0.248)
			(end -0.494 -0.25)
			(stroke
				(width 0.15)
				(type solid)
			)
			(layer "F.Fab")
		)
		(pad "1" smd roundrect
			(at -0.48 0 90)
			(size 0.59 0.64)
			(layers "F.Cu" "F.Mask" "F.Paste")
			(roundrect_rratio 0.25)
			(net 1 "GND")
			(pintype "passive")
		)
		(pad "2" smd roundrect
			(at 0.48 0 90)
			(size 0.59 0.64)
			(layers "F.Cu" "F.Mask" "F.Paste")
			(roundrect_rratio 0.25)
			(net 143 "/DDR3/DDR3_VTT")
			(pintype "passive")
		)
	)
	(footprint "antmicro-footprints:C_0402_1005Metric"
		(layer "F.Cu")
		(at 108 144.6 -90)
		(descr "Capacitor SMD 0402")
		(tags "capacitor SMD 0402")
		(property "Reference" "C44"
			(at -3 -0.4 90)
			(layer "F.SilkS")
			(effects
				(font
					(size 0.7 0.7)
					(thickness 0.15)
				)
				(justify right bottom)
			)
		)
		(property "Value" "C_100n_6V3_0402"
			(at 0 1.4 90)
			(layer "F.Fab")
			(effects
				(font
					(size 0.7 0.7)
					(thickness 0.15)
				)
				(justify right bottom)
			)
		)
		(property "Datasheet" "https://www.passivecomponent.com/wp-content/uploads/datasheet/WTC_MLCC_General_Purpose.pdf"
			(at 0 0 270)
			(layer "F.Fab")
			(hide yes)
			(effects
				(font
					(size 1.27 1.27)
					(thickness 0.15)
				)
			)
		)
		(property "Description" "SMT Multilayer Ceramic Capacitor, 0.1 µF, 6.3 V, 0402 [1005 Metric], ± 10%, X5R, Walsin MLCC"
			(at 0 0 270)
			(layer "F.Fab")
			(hide yes)
			(effects
				(font
					(size 1.27 1.27)
					(thickness 0.15)
				)
			)
		)
		(property "Author" "Antmicro"
			(at -36.6 252.6 0)
			(layer "F.Fab")
			(hide yes)
			(effects
				(font
					(size 1 1)
					(thickness 0.15)
				)
			)
		)
		(property "Dielectric" ""
			(at -36.6 252.6 0)
			(layer "F.Fab")
			(hide yes)
			(effects
				(font
					(size 1 1)
					(thickness 0.15)
				)
			)
		)
		(property "License" "Apache-2.0"
			(at -36.6 252.6 0)
			(layer "F.Fab")
			(hide yes)
			(effects
				(font
					(size 1 1)
					(thickness 0.15)
				)
			)
		)
		(property "MPN" "0402X104K6R3CT"
			(at -36.6 252.6 0)
			(layer "F.Fab")
			(hide yes)
			(effects
				(font
					(size 1 1)
					(thickness 0.15)
				)
			)
		)
		(property "Manufacturer" "Walsin"
			(at -36.6 252.6 0)
			(layer "F.Fab")
			(hide yes)
			(effects
				(font
					(size 1 1)
					(thickness 0.15)
				)
			)
		)
		(property "Public" "False"
			(at -36.6 252.6 0)
			(layer "F.Fab")
			(hide yes)
			(effects
				(font
					(size 1 1)
					(thickness 0.15)
				)
			)
		)
		(property "Val" "100n"
			(at -36.6 252.6 0)
			(layer "F.Fab")
			(hide yes)
			(effects
				(font
					(size 1 1)
					(thickness 0.15)
				)
			)
		)
		(property "Voltage" ""
			(at -36.6 252.6 0)
			(layer "F.Fab")
			(hide yes)
			(effects
				(font
					(size 1 1)
					(thickness 0.15)
				)
			)
		)
		(sheetname "/DDR3/")
		(sheetfile "ddr3.kicad_sch")
		(attr smd)
		(fp_rect
			(start -0.925 -0.47)
			(end 0.925 0.47)
			(stroke
				(width 0.05)
				(type default)
			)
			(fill no)
			(layer "F.CrtYd")
		)
		(fp_line
			(start -0.494 0.248)
			(end -0.494 -0.25)
			(stroke
				(width 0.15)
				(type solid)
			)
			(layer "F.Fab")
		)
		(fp_line
			(start 0.504 0.248)
			(end -0.494 0.248)
			(stroke
				(width 0.15)
				(type solid)
			)
			(layer "F.Fab")
		)
		(fp_line
			(start -0.494 -0.25)
			(end 0.504 -0.25)
			(stroke
				(width 0.15)
				(type solid)
			)
			(layer "F.Fab")
		)
		(fp_line
			(start 0.504 -0.25)
			(end 0.504 0.248)
			(stroke
				(width 0.15)
				(type solid)
			)
			(layer "F.Fab")
		)
		(pad "1" smd roundrect
			(at -0.48 0 270)
			(size 0.59 0.64)
			(layers "F.Cu" "F.Mask" "F.Paste")
			(roundrect_rratio 0.25)
			(net 1 "GND")
			(pintype "passive")
		)
		(pad "2" smd roundrect
			(at 0.48 0 270)
			(size 0.59 0.64)
			(layers "F.Cu" "F.Mask" "F.Paste")
			(roundrect_rratio 0.25)
			(net 211 "DDR3_VREF")
			(pintype "passive")
		)
	)
	(footprint "antmicro-footprints:C_0402_1005Metric"
		(layer "F.Cu")
		(at 105.275 158.275 180)
		(descr "Capacitor SMD 0402")
		(tags "capacitor SMD 0402")
		(property "Reference" "C47"
			(at -2.925 -0.325 0)
			(layer "F.SilkS")
			(effects
				(font
					(size 0.7 0.7)
					(thickness 0.15)
				)
				(justify right bottom)
			)
		)
		(property "Value" "C_10u_0402"
			(at 0 1.4 0)
			(layer "F.Fab")
			(effects
				(font
					(size 0.7 0.7)
					(thickness 0.15)
				)
				(justify right bottom)
			)
		)
		(property "Datasheet" "https://www.yageo.com/en/Chart/Download/pdf/CC0402MRX5R5BB106"
			(at 0 0 180)
			(layer "F.Fab")
			(hide yes)
			(effects
				(font
					(size 1.27 1.27)
					(thickness 0.15)
				)
			)
		)
		(property "Description" "SMD Multilayer Ceramic Capacitor, 10 µF, 6.3 V, 0402 [1005 Metric], ± 20%, X5R, CC Series"
			(at 0 0 180)
			(layer "F.Fab")
			(hide yes)
			(effects
				(font
					(size 1.27 1.27)
					(thickness 0.15)
				)
			)
		)
		(property "Author" "Antmicro"
			(at 210.55 316.55 0)
			(layer "F.Fab")
			(hide yes)
			(effects
				(font
					(size 1 1)
					(thickness 0.15)
				)
			)
		)
		(property "Dielectric" ""
			(at 210.55 316.55 0)
			(layer "F.Fab")
			(hide yes)
			(effects
				(font
					(size 1 1)
					(thickness 0.15)
				)
			)
		)
		(property "License" "Apache-2.0"
			(at 210.55 316.55 0)
			(layer "F.Fab")
			(hide yes)
			(effects
				(font
					(size 1 1)
					(thickness 0.15)
				)
			)
		)
		(property "MPN" "CC0402MRX5R5BB106"
			(at 210.55 316.55 0)
			(layer "F.Fab")
			(hide yes)
			(effects
				(font
					(size 1 1)
					(thickness 0.15)
				)
			)
		)
		(property "Manufacturer" "YAGEO"
			(at 210.55 316.55 0)
			(layer "F.Fab")
			(hide yes)
			(effects
				(font
					(size 1 1)
					(thickness 0.15)
				)
			)
		)
		(property "Val" "10u"
			(at 210.55 316.55 0)
			(layer "F.Fab")
			(hide yes)
			(effects
				(font
					(size 1 1)
					(thickness 0.15)
				)
			)
		)
		(property "Voltage" ""
			(at 210.55 316.55 0)
			(layer "F.Fab")
			(hide yes)
			(effects
				(font
					(size 1 1)
					(thickness 0.15)
				)
			)
		)
		(sheetname "/DDR3/")
		(sheetfile "ddr3.kicad_sch")
		(attr smd)
		(fp_rect
			(start -0.925 -0.47)
			(end 0.925 0.47)
			(stroke
				(width 0.05)
				(type default)
			)
			(fill no)
			(layer "F.CrtYd")
		)
		(fp_line
			(start 0.504 0.248)
			(end -0.494 0.248)
			(stroke
				(width 0.15)
				(type solid)
			)
			(layer "F.Fab")
		)
		(fp_line
			(start 0.504 -0.25)
			(end 0.504 0.248)
			(stroke
				(width 0.15)
				(type solid)
			)
			(layer "F.Fab")
		)
		(fp_line
			(start -0.494 0.248)
			(end -0.494 -0.25)
			(stroke
				(width 0.15)
				(type solid)
			)
			(layer "F.Fab")
		)
		(fp_line
			(start -0.494 -0.25)
			(end 0.504 -0.25)
			(stroke
				(width 0.15)
				(type solid)
			)
			(layer "F.Fab")
		)
		(pad "1" smd roundrect
			(at -0.48 0 180)
			(size 0.59 0.64)
			(layers "F.Cu" "F.Mask" "F.Paste")
			(roundrect_rratio 0.25)
			(net 1 "GND")
			(pintype "passive")
		)
		(pad "2" smd roundrect
			(at 0.48 0 180)
			(size 0.59 0.64)
			(layers "F.Cu" "F.Mask" "F.Paste")
			(roundrect_rratio 0.25)
			(net 2 "VCC3V3")
			(pintype "passive")
		)
	)
	(footprint "antmicro-footprints:R_0402_1005Metric"
		(layer "F.Cu")
		(at 99.675 154.675 -90)
		(descr "Resistor SMD 0402")
		(tags "resistor SMD 0402")
		(property "Reference" "R57"
			(at 1.225 8.275 90)
			(layer "F.SilkS")
			(effects
				(font
					(size 0.7 0.7)
					(thickness 0.15)
				)
				(justify right bottom)
			)
		)
		(property "Value" "R_10k_0402"
			(at 0 1.4 90)
			(layer "F.Fab")
			(effects
				(font
					(size 0.7 0.7)
					(thickness 0.15)
				)
				(justify right bottom)
			)
		)
		(property "Datasheet" "https://www.bourns.com/docs/product-datasheets/cr.pdf"
			(at 0 0 270)
			(layer "F.Fab")
			(hide yes)
			(effects
				(font
					(size 1.27 1.27)
					(thickness 0.15)
				)
			)
		)
		(property "Description" "SMD Chip Resistor, 10 kohm, ± 1%, 62.5 mW, 0402 [1005 Metric], Thick Film, General Purpose"
			(at 0 0 270)
			(layer "F.Fab")
			(hide yes)
			(effects
				(font
					(size 1.27 1.27)
					(thickness 0.15)
				)
			)
		)
		(property "Author" "Antmicro"
			(at -55 254.35 0)
			(layer "F.Fab")
			(hide yes)
			(effects
				(font
					(size 1 1)
					(thickness 0.15)
				)
			)
		)
		(property "License" "Apache-2.0"
			(at -55 254.35 0)
			(layer "F.Fab")
			(hide yes)
			(effects
				(font
					(size 1 1)
					(thickness 0.15)
				)
			)
		)
		(property "MPN" "CR0402-FX-1002GLF"
			(at -55 254.35 0)
			(layer "F.Fab")
			(hide yes)
			(effects
				(font
					(size 1 1)
					(thickness 0.15)
				)
			)
		)
		(property "Manufacturer" "Bourns"
			(at -55 254.35 0)
			(layer "F.Fab")
			(hide yes)
			(effects
				(font
					(size 1 1)
					(thickness 0.15)
				)
			)
		)
		(property "Tolerance" "1%"
			(at -55 254.35 0)
			(layer "F.Fab")
			(hide yes)
			(effects
				(font
					(size 1 1)
					(thickness 0.15)
				)
			)
		)
		(property "Val" "10k"
			(at -55 254.35 0)
			(layer "F.Fab")
			(hide yes)
			(effects
				(font
					(size 1 1)
					(thickness 0.15)
				)
			)
		)
		(sheetname "/DDR3/")
		(sheetfile "ddr3.kicad_sch")
		(attr smd)
		(fp_rect
			(start -0.925 -0.47)
			(end 0.925 0.47)
			(stroke
				(width 0.05)
				(type default)
			)
			(fill no)
			(layer "F.CrtYd")
		)
		(fp_rect
			(start -0.5 -0.25)
			(end 0.5 0.25)
			(stroke
				(width 0.15)
				(type solid)
			)
			(fill no)
			(layer "F.Fab")
		)
		(pad "1" smd roundrect
			(at -0.48 0 270)
			(size 0.59 0.64)
			(layers "F.Cu" "F.Mask" "F.Paste")
			(roundrect_rratio 0.25)
			(net 1 "GND")
			(pintype "passive")
		)
		(pad "2" smd roundrect
			(at 0.48 0 270)
			(size 0.59 0.64)
			(layers "F.Cu" "F.Mask" "F.Paste")
			(roundrect_rratio 0.25)
			(net 9 "Net-(U8-REFIN)")
			(pintype "passive")
		)
	)
	(footprint "antmicro-footprints:R_0402_1005Metric"
		(layer "F.Cu")
		(at 100.675 154.675 -90)
		(descr "Resistor SMD 0402")
		(tags "resistor SMD 0402")
		(property "Reference" "R58"
			(at 1.225 8.175 90)
			(layer "F.SilkS")
			(effects
				(font
					(size 0.7 0.7)
					(thickness 0.15)
				)
				(justify right bottom)
			)
		)
		(property "Value" "R_10k_0402"
			(at 0 1.4 90)
			(layer "F.Fab")
			(effects
				(font
					(size 0.7 0.7)
					(thickness 0.15)
				)
				(justify right bottom)
			)
		)
		(property "Datasheet" "https://www.bourns.com/docs/product-datasheets/cr.pdf"
			(at 0 0 270)
			(layer "F.Fab")
			(hide yes)
			(effects
				(font
					(size 1.27 1.27)
					(thickness 0.15)
				)
			)
		)
		(property "Description" "SMD Chip Resistor, 10 kohm, ± 1%, 62.5 mW, 0402 [1005 Metric], Thick Film, General Purpose"
			(at 0 0 270)
			(layer "F.Fab")
			(hide yes)
			(effects
				(font
					(size 1.27 1.27)
					(thickness 0.15)
				)
			)
		)
		(property "Author" "Antmicro"
			(at -54 255.35 0)
			(layer "F.Fab")
			(hide yes)
			(effects
				(font
					(size 1 1)
					(thickness 0.15)
				)
			)
		)
		(property "License" "Apache-2.0"
			(at -54 255.35 0)
			(layer "F.Fab")
			(hide yes)
			(effects
				(font
					(size 1 1)
					(thickness 0.15)
				)
			)
		)
		(property "MPN" "CR0402-FX-1002GLF"
			(at -54 255.35 0)
			(layer "F.Fab")
			(hide yes)
			(effects
				(font
					(size 1 1)
					(thickness 0.15)
				)
			)
		)
		(property "Manufacturer" "Bourns"
			(at -54 255.35 0)
			(layer "F.Fab")
			(hide yes)
			(effects
				(font
					(size 1 1)
					(thickness 0.15)
				)
			)
		)
		(property "Tolerance" "1%"
			(at -54 255.35 0)
			(layer "F.Fab")
			(hide yes)
			(effects
				(font
					(size 1 1)
					(thickness 0.15)
				)
			)
		)
		(property "Val" "10k"
			(at -54 255.35 0)
			(layer "F.Fab")
			(hide yes)
			(effects
				(font
					(size 1 1)
					(thickness 0.15)
				)
			)
		)
		(sheetname "/DDR3/")
		(sheetfile "ddr3.kicad_sch")
		(attr smd)
		(fp_rect
			(start -0.925 -0.47)
			(end 0.925 0.47)
			(stroke
				(width 0.05)
				(type default)
			)
			(fill no)
			(layer "F.CrtYd")
		)
		(fp_rect
			(start -0.5 -0.25)
			(end 0.5 0.25)
			(stroke
				(width 0.15)
				(type solid)
			)
			(fill no)
			(layer "F.Fab")
		)
		(pad "1" smd roundrect
			(at -0.48 0 270)
			(size 0.59 0.64)
			(layers "F.Cu" "F.Mask" "F.Paste")
			(roundrect_rratio 0.25)
			(net 3 "VCC1V35")
			(pintype "passive")
		)
		(pad "2" smd roundrect
			(at 0.48 0 270)
			(size 0.59 0.64)
			(layers "F.Cu" "F.Mask" "F.Paste")
			(roundrect_rratio 0.25)
			(net 9 "Net-(U8-REFIN)")
			(pintype "passive")
		)
	)
	(footprint "antmicro-footprints:R_0402_1005Metric"
		(layer "F.Cu")
		(at 105.275 159.275 180)
		(descr "Resistor SMD 0402")
		(tags "resistor SMD 0402")
		(property "Reference" "R59"
			(at -2.926 -0.325 0)
			(layer "F.SilkS")
			(effects
				(font
					(size 0.7 0.7)
					(thickness 0.15)
				)
				(justify right bottom)
			)
		)
		(property "Value" "R_10k_0402"
			(at 0 1.4 0)
			(layer "F.Fab")
			(effects
				(font
					(size 0.7 0.7)
					(thickness 0.15)
				)
				(justify right bottom)
			)
		)
		(property "Datasheet" "https://www.bourns.com/docs/product-datasheets/cr.pdf"
			(at 0 0 180)
			(layer "F.Fab")
			(hide yes)
			(effects
				(font
					(size 1.27 1.27)
					(thickness 0.15)
				)
			)
		)
		(property "Description" "SMD Chip Resistor, 10 kohm, ± 1%, 62.5 mW, 0402 [1005 Metric], Thick Film, General Purpose"
			(at 0 0 180)
			(layer "F.Fab")
			(hide yes)
			(effects
				(font
					(size 1.27 1.27)
					(thickness 0.15)
				)
			)
		)
		(property "Author" "Antmicro"
			(at 210.55 318.55 0)
			(layer "F.Fab")
			(hide yes)
			(effects
				(font
					(size 1 1)
					(thickness 0.15)
				)
			)
		)
		(property "License" "Apache-2.0"
			(at 210.55 318.55 0)
			(layer "F.Fab")
			(hide yes)
			(effects
				(font
					(size 1 1)
					(thickness 0.15)
				)
			)
		)
		(property "MPN" "CR0402-FX-1002GLF"
			(at 210.55 318.55 0)
			(layer "F.Fab")
			(hide yes)
			(effects
				(font
					(size 1 1)
					(thickness 0.15)
				)
			)
		)
		(property "Manufacturer" "Bourns"
			(at 210.55 318.55 0)
			(layer "F.Fab")
			(hide yes)
			(effects
				(font
					(size 1 1)
					(thickness 0.15)
				)
			)
		)
		(property "Tolerance" "1%"
			(at 210.55 318.55 0)
			(layer "F.Fab")
			(hide yes)
			(effects
				(font
					(size 1 1)
					(thickness 0.15)
				)
			)
		)
		(property "Val" "10k"
			(at 210.55 318.55 0)
			(layer "F.Fab")
			(hide yes)
			(effects
				(font
					(size 1 1)
					(thickness 0.15)
				)
			)
		)
		(sheetname "/DDR3/")
		(sheetfile "ddr3.kicad_sch")
		(attr smd)
		(fp_rect
			(start -0.925 -0.47)
			(end 0.925 0.47)
			(stroke
				(width 0.05)
				(type default)
			)
			(fill no)
			(layer "F.CrtYd")
		)
		(fp_rect
			(start -0.5 -0.25)
			(end 0.5 0.25)
			(stroke
				(width 0.15)
				(type solid)
			)
			(fill no)
			(layer "F.Fab")
		)
		(pad "1" smd roundrect
			(at -0.48 0 180)
			(size 0.59 0.64)
			(layers "F.Cu" "F.Mask" "F.Paste")
			(roundrect_rratio 0.25)
			(net 2 "VCC3V3")
			(pintype "passive")
		)
		(pad "2" smd roundrect
			(at 0.48 0 180)
			(size 0.59 0.64)
			(layers "F.Cu" "F.Mask" "F.Paste")
			(roundrect_rratio 0.25)
			(net 334 "Net-(U8-PGOOD)")
			(pintype "passive")
		)
	)
	(footprint "antmicro-footprints:VSON-10-1EP_3x3mm"
		(layer "F.Cu")
		(at 102.0755 159.785)
		(property "Reference" "U8"
			(at 0.7245 -2.185 0)
			(layer "F.SilkS")
			(effects
				(font
					(size 0.7 0.7)
					(thickness 0.15)
				)
			)
		)
		(property "Value" "TPS51200DRCT"
			(at -0.3 2.9 0)
			(layer "F.Fab")
			(effects
				(font
					(size 1 1)
					(thickness 0.15)
				)
			)
		)
		(property "Datasheet" "https://www.ti.com/lit/ds/symlink/tps51200.pdf?ts=1685420125657"
			(at 0 0 0)
			(layer "F.Fab")
			(hide yes)
			(effects
				(font
					(size 1.27 1.27)
					(thickness 0.15)
				)
			)
		)
		(property "Description" "Fixed LDO Voltage Regulator, 2.375 V to 3.5 V, 0.8 V Dropout, 1.25 V / 3 A out, VSON-10"
			(at 0 0 0)
			(layer "F.Fab")
			(hide yes)
			(effects
				(font
					(size 1.27 1.27)
					(thickness 0.15)
				)
			)
		)
		(property "Author" "Antmicro"
			(at 0 0 0)
			(layer "F.Fab")
			(hide yes)
			(effects
				(font
					(size 1 1)
					(thickness 0.15)
				)
			)
		)
		(property "License" "Apache-2.0"
			(at 0 0 0)
			(layer "F.Fab")
			(hide yes)
			(effects
				(font
					(size 1 1)
					(thickness 0.15)
				)
			)
		)
		(property "MPN" "TPS51200DRCT"
			(at 0 0 0)
			(layer "F.Fab")
			(hide yes)
			(effects
				(font
					(size 1 1)
					(thickness 0.15)
				)
			)
		)
		(property "Manufacturer" "Texas Instruments"
			(at 0 0 0)
			(layer "F.Fab")
			(hide yes)
			(effects
				(font
					(size 1 1)
					(thickness 0.15)
				)
			)
		)
		(property "VSD_class" "TPS51200"
			(at 0 0 0)
			(layer "F.Fab")
			(hide yes)
			(effects
				(font
					(size 1 1)
					(thickness 0.15)
				)
			)
		)
		(property ki_fp_filters "*VSON?10?1EP?3x3mm?P0.5mm*")
		(sheetname "/DDR3/")
		(sheetfile "ddr3.kicad_sch")
		(attr smd)
		(fp_line
			(start -1.5 1.598)
			(end 1.499 1.598)
			(stroke
				(width 0.15)
				(type solid)
			)
			(layer "F.SilkS")
		)
		(fp_line
			(start 0 -1.621)
			(end 1.499 -1.621)
			(stroke
				(width 0.15)
				(type solid)
			)
			(layer "F.SilkS")
		)
		(fp_line
			(start -1.97 1.215)
			(end -1.97 -1.24)
			(stroke
				(width 0.05)
				(type solid)
			)
			(layer "F.CrtYd")
		)
		(fp_line
			(start -1.65 -1.65)
			(end -1.65 -1.24)
			(stroke
				(width 0.05)
				(type solid)
			)
			(layer "F.CrtYd")
		)
		(fp_line
			(start -1.65 -1.24)
			(end -1.97 -1.24)
			(stroke
				(width 0.05)
				(type solid)
			)
			(layer "F.CrtYd")
		)
		(fp_line
			(start -1.65 1.215)
			(end -1.97 1.215)
			(stroke
				(width 0.05)
				(type solid)
			)
			(layer "F.CrtYd")
		)
		(fp_line
			(start -1.65 1.215)
			(end -1.65 1.625)
			(stroke
				(width 0.05)
				(type solid)
			)
			(layer "F.CrtYd")
		)
		(fp_line
			(start -1.65 1.625)
			(end 1.65 1.625)
			(stroke
				(width 0.05)
				(type solid)
			)
			(layer "F.CrtYd")
		)
		(fp_line
			(start 1.65 -1.65)
			(end -1.65 -1.65)
			(stroke
				(width 0.05)
				(type solid)
			)
			(layer "F.CrtYd")
		)
		(fp_line
			(start 1.65 -1.24)
			(end 1.65 -1.65)
			(stroke
				(width 0.05)
				(type solid)
			)
			(layer "F.CrtYd")
		)
		(fp_line
			(start 1.65 -1.24)
			(end 1.97 -1.24)
			(stroke
				(width 0.05)
				(type solid)
			)
			(layer "F.CrtYd")
		)
		(fp_line
			(start 1.65 1.215)
			(end 1.97 1.215)
			(stroke
				(width 0.05)
				(type solid)
			)
			(layer "F.CrtYd")
		)
		(fp_line
			(start 1.65 1.625)
			(end 1.65 1.215)
			(stroke
				(width 0.05)
				(type solid)
			)
			(layer "F.CrtYd")
		)
		(fp_line
			(start 1.97 -1.24)
			(end 1.97 1.215)
			(stroke
				(width 0.05)
				(type solid)
			)
			(layer "F.CrtYd")
		)
		(fp_line
			(start -1.5 -0.76)
			(end -0.75 -1.51)
			(stroke
				(width 0.15)
				(type solid)
			)
			(layer "F.Fab")
		)
		(fp_line
			(start -1.5 1.489)
			(end -1.5 -0.76)
			(stroke
				(width 0.15)
				(type solid)
			)
			(layer "F.Fab")
		)
		(fp_line
			(start -0.75 -1.51)
			(end 1.499 -1.51)
			(stroke
				(width 0.15)
				(type solid)
			)
			(layer "F.Fab")
		)
		(fp_line
			(start 1.499 -1.51)
			(end 1.499 1.489)
			(stroke
				(width 0.15)
				(type solid)
			)
			(layer "F.Fab")
		)
		(fp_line
			(start 1.499 1.489)
			(end -1.5 1.489)
			(stroke
				(width 0.15)
				(type solid)
			)
			(layer "F.Fab")
		)
		(fp_text user "."
			(at -2.05 -1.65 0)
			(layer "F.SilkS")
			(effects
				(font
					(size 1 1)
					(thickness 0.15)
				)
			)
		)
		(fp_text user "${REFERENCE}"
			(at 0.2 -0.2 0)
			(layer "F.Fab")
			(effects
				(font
					(size 0.75 0.75)
					(thickness 0.11)
				)
			)
		)
		(pad "" smd roundrect
			(at -0.3 -0.51)
			(size 0.48 0.81)
			(layers "F.Paste")
			(roundrect_rratio 0.25)
		)
		(pad "" smd roundrect
			(at -0.3 0.488)
			(size 0.48 0.81)
			(layers "F.Paste")
			(roundrect_rratio 0.25)
		)
		(pad "" smd roundrect
			(at 0.299 -0.51)
			(size 0.48 0.81)
			(layers "F.Paste")
			(roundrect_rratio 0.25)
		)
		(pad "" smd roundrect
			(at 0.299 0.488)
			(size 0.48 0.81)
			(layers "F.Paste")
			(roundrect_rratio 0.25)
		)
		(pad "1" smd roundrect
			(at -1.438 -1.01)
			(size 0.875 0.25)
			(layers "F.Cu" "F.Mask" "F.Paste")
			(roundrect_rratio 0.25)
			(net 9 "Net-(U8-REFIN)")
			(pinfunction "REFIN")
			(pintype "input")
		)
		(pad "2" smd roundrect
			(at -1.438 -0.51)
			(size 0.875 0.25)
			(layers "F.Cu" "F.Mask" "F.Paste")
			(roundrect_rratio 0.25)
			(net 3 "VCC1V35")
			(pinfunction "VLDOIN")
			(pintype "power_in")
		)
		(pad "3" smd roundrect
			(at -1.438 -0.011)
			(size 0.875 0.25)
			(layers "F.Cu" "F.Mask" "F.Paste")
			(roundrect_rratio 0.25)
			(net 143 "/DDR3/DDR3_VTT")
			(pinfunction "VO")
			(pintype "power_out")
		)
		(pad "4" smd roundrect
			(at -1.438 0.488)
			(size 0.875 0.25)
			(layers "F.Cu" "F.Mask" "F.Paste")
			(roundrect_rratio 0.25)
			(net 1 "GND")
			(pinfunction "GND")
			(pintype "passive")
		)
		(pad "5" smd roundrect
			(at -1.438 0.988)
			(size 0.875 0.25)
			(layers "F.Cu" "F.Mask" "F.Paste")
			(roundrect_rratio 0.25)
			(net 143 "/DDR3/DDR3_VTT")
			(pinfunction "VOSNS")
			(pintype "input")
		)
		(pad "6" smd roundrect
			(at 1.437 0.988)
			(size 0.875 0.25)
			(layers "F.Cu" "F.Mask" "F.Paste")
			(roundrect_rratio 0.25)
			(net 211 "DDR3_VREF")
			(pinfunction "REFOUT")
			(pintype "power_out")
		)
		(pad "7" smd roundrect
			(at 1.437 0.488)
			(size 0.875 0.25)
			(layers "F.Cu" "F.Mask" "F.Paste")
			(roundrect_rratio 0.25)
			(net 341 "Net-(U8-EN)")
			(pinfunction "EN")
			(pintype "input")
		)
		(pad "8" smd roundrect
			(at 1.437 -0.011)
			(size 0.875 0.25)
			(layers "F.Cu" "F.Mask" "F.Paste")
			(roundrect_rratio 0.25)
			(net 1 "GND")
			(pinfunction "GND")
			(pintype "power_in")
		)
		(pad "9" smd roundrect
			(at 1.437 -0.51)
			(size 0.875 0.25)
			(layers "F.Cu" "F.Mask" "F.Paste")
			(roundrect_rratio 0.25)
			(net 334 "Net-(U8-PGOOD)")
			(pinfunction "PGOOD")
			(pintype "open_collector")
		)
		(pad "10" smd roundrect
			(at 1.437 -1.01)
			(size 0.875 0.25)
			(layers "F.Cu" "F.Mask" "F.Paste")
			(roundrect_rratio 0.25)
			(net 2 "VCC3V3")
			(pinfunction "VIN")
			(pintype "power_in")
		)
		(pad "11" smd roundrect
			(at 0 -0.011)
			(size 1.2 2)
			(layers "F.Cu" "F.Mask")
			(roundrect_rratio 0.208333)
			(net 1 "GND")
			(pinfunction "GND")
			(pintype "passive")
		)
	)
	(footprint "antmicro-footprints:C_0402_1005Metric"
		(layer "F.Cu")
		(at 91.545 96.575 90)
		(descr "Capacitor SMD 0402")
		(tags "capacitor SMD 0402")
		(property "Reference" "C80"
			(at 0.776 0.355 90)
			(layer "F.SilkS")
			(effects
				(font
					(size 0.7 0.7)
					(thickness 0.15)
				)
				(justify left bottom)
			)
		)
		(property "Value" "C_120p_0402"
			(at 0 1.4 90)
			(layer "F.Fab")
			(effects
				(font
					(size 0.7 0.7)
					(thickness 0.15)
				)
				(justify left bottom)
			)
		)
		(property "Datasheet" "https://www.kemet.com/en/us/capacitors/product/C0402C121J5GACTU.html"
			(at 0 0 90)
			(layer "F.Fab")
			(hide yes)
			(effects
				(font
					(size 1.27 1.27)
					(thickness 0.15)
				)
			)
		)
		(property "Description" "120 pF ±2% 100V Ceramic Capacitor C0G, NP0 0402 (1005 Metric)"
			(at 0 0 90)
			(layer "F.Fab")
			(hide yes)
			(effects
				(font
					(size 1.27 1.27)
					(thickness 0.15)
				)
			)
		)
		(property "Author" "Antmicro"
			(at 188.12 5.03 0)
			(layer "F.Fab")
			(hide yes)
			(effects
				(font
					(size 1 1)
					(thickness 0.15)
				)
			)
		)
		(property "Dielectric" "C0G"
			(at 188.12 5.03 0)
			(layer "F.Fab")
			(hide yes)
			(effects
				(font
					(size 1 1)
					(thickness 0.15)
				)
			)
		)
		(property "License" "Apache-2.0"
			(at 188.12 5.03 0)
			(layer "F.Fab")
			(hide yes)
			(effects
				(font
					(size 1 1)
					(thickness 0.15)
				)
			)
		)
		(property "MPN" "C0402C121J5GACTU"
			(at 188.12 5.03 0)
			(layer "F.Fab")
			(hide yes)
			(effects
				(font
					(size 1 1)
					(thickness 0.15)
				)
			)
		)
		(property "Manufacturer" "KEMET"
			(at 188.12 5.03 0)
			(layer "F.Fab")
			(hide yes)
			(effects
				(font
					(size 1 1)
					(thickness 0.15)
				)
			)
		)
		(property "Val" "120p"
			(at 188.12 5.03 0)
			(layer "F.Fab")
			(hide yes)
			(effects
				(font
					(size 1 1)
					(thickness 0.15)
				)
			)
		)
		(property "Voltage" "100V"
			(at 188.12 5.03 0)
			(layer "F.Fab")
			(hide yes)
			(effects
				(font
					(size 1 1)
					(thickness 0.15)
				)
			)
		)
		(sheetname "/Power supply/")
		(sheetfile "power-supply.kicad_sch")
		(attr smd)
		(fp_rect
			(start -0.925 -0.47)
			(end 0.925 0.47)
			(stroke
				(width 0.05)
				(type default)
			)
			(fill no)
			(layer "F.CrtYd")
		)
		(fp_line
			(start 0.504 -0.25)
			(end 0.504 0.248)
			(stroke
				(width 0.15)
				(type solid)
			)
			(layer "F.Fab")
		)
		(fp_line
			(start -0.494 -0.25)
			(end 0.504 -0.25)
			(stroke
				(width 0.15)
				(type solid)
			)
			(layer "F.Fab")
		)
		(fp_line
			(start 0.504 0.248)
			(end -0.494 0.248)
			(stroke
				(width 0.15)
				(type solid)
			)
			(layer "F.Fab")
		)
		(fp_line
			(start -0.494 0.248)
			(end -0.494 -0.25)
			(stroke
				(width 0.15)
				(type solid)
			)
			(layer "F.Fab")
		)
		(pad "1" smd roundrect
			(at -0.48 0 90)
			(size 0.59 0.64)
			(layers "F.Cu" "F.Mask" "F.Paste")
			(roundrect_rratio 0.25)
			(net 117 "Net-(U11-FB)")
			(pintype "passive")
		)
		(pad "2" smd roundrect
			(at 0.48 0 90)
			(size 0.59 0.64)
			(layers "F.Cu" "F.Mask" "F.Paste")
			(roundrect_rratio 0.25)
			(net 275 "Net-(C80-Pad2)")
			(pintype "passive")
		)
	)
	(footprint "antmicro-footprints:C_0402_1005Metric"
		(layer "F.Cu")
		(at 91.545 103.925 90)
		(descr "Capacitor SMD 0402")
		(tags "capacitor SMD 0402")
		(property "Reference" "C79"
			(at -0.875 3.355 90)
			(layer "F.SilkS")
			(effects
				(font
					(size 0.7 0.7)
					(thickness 0.15)
				)
				(justify left bottom)
			)
		)
		(property "Value" "C_120p_0402"
			(at 0 1.4 90)
			(layer "F.Fab")
			(effects
				(font
					(size 0.7 0.7)
					(thickness 0.15)
				)
				(justify left bottom)
			)
		)
		(property "Datasheet" "https://www.kemet.com/en/us/capacitors/product/C0402C121J5GACTU.html"
			(at 0 0 90)
			(layer "F.Fab")
			(hide yes)
			(effects
				(font
					(size 1.27 1.27)
					(thickness 0.15)
				)
			)
		)
		(property "Description" "120 pF ±2% 100V Ceramic Capacitor C0G, NP0 0402 (1005 Metric)"
			(at 0 0 90)
			(layer "F.Fab")
			(hide yes)
			(effects
				(font
					(size 1.27 1.27)
					(thickness 0.15)
				)
			)
		)
		(property "Author" "Antmicro"
			(at 195.47 12.38 0)
			(layer "F.Fab")
			(hide yes)
			(effects
				(font
					(size 1 1)
					(thickness 0.15)
				)
			)
		)
		(property "Dielectric" "C0G"
			(at 195.47 12.38 0)
			(layer "F.Fab")
			(hide yes)
			(effects
				(font
					(size 1 1)
					(thickness 0.15)
				)
			)
		)
		(property "License" "Apache-2.0"
			(at 195.47 12.38 0)
			(layer "F.Fab")
			(hide yes)
			(effects
				(font
					(size 1 1)
					(thickness 0.15)
				)
			)
		)
		(property "MPN" "C0402C121J5GACTU"
			(at 195.47 12.38 0)
			(layer "F.Fab")
			(hide yes)
			(effects
				(font
					(size 1 1)
					(thickness 0.15)
				)
			)
		)
		(property "Manufacturer" "KEMET"
			(at 195.47 12.38 0)
			(layer "F.Fab")
			(hide yes)
			(effects
				(font
					(size 1 1)
					(thickness 0.15)
				)
			)
		)
		(property "Val" "120p"
			(at 195.47 12.38 0)
			(layer "F.Fab")
			(hide yes)
			(effects
				(font
					(size 1 1)
					(thickness 0.15)
				)
			)
		)
		(property "Voltage" "100V"
			(at 195.47 12.38 0)
			(layer "F.Fab")
			(hide yes)
			(effects
				(font
					(size 1 1)
					(thickness 0.15)
				)
			)
		)
		(sheetname "/Power supply/")
		(sheetfile "power-supply.kicad_sch")
		(attr smd)
		(fp_rect
			(start -0.925 -0.47)
			(end 0.925 0.47)
			(stroke
				(width 0.05)
				(type default)
			)
			(fill no)
			(layer "F.CrtYd")
		)
		(fp_line
			(start 0.504 -0.25)
			(end 0.504 0.248)
			(stroke
				(width 0.15)
				(type solid)
			)
			(layer "F.Fab")
		)
		(fp_line
			(start -0.494 -0.25)
			(end 0.504 -0.25)
			(stroke
				(width 0.15)
				(type solid)
			)
			(layer "F.Fab")
		)
		(fp_line
			(start 0.504 0.248)
			(end -0.494 0.248)
			(stroke
				(width 0.15)
				(type solid)
			)
			(layer "F.Fab")
		)
		(fp_line
			(start -0.494 0.248)
			(end -0.494 -0.25)
			(stroke
				(width 0.15)
				(type solid)
			)
			(layer "F.Fab")
		)
		(pad "1" smd roundrect
			(at -0.48 0 90)
			(size 0.59 0.64)
			(layers "F.Cu" "F.Mask" "F.Paste")
			(roundrect_rratio 0.25)
			(net 113 "Net-(U10-FB)")
			(pintype "passive")
		)
		(pad "2" smd roundrect
			(at 0.48 0 90)
			(size 0.59 0.64)
			(layers "F.Cu" "F.Mask" "F.Paste")
			(roundrect_rratio 0.25)
			(net 274 "Net-(C79-Pad2)")
			(pintype "passive")
		)
	)
	(footprint "antmicro-footprints:C_0603_1608Metric"
		(layer "F.Cu")
		(at 85.175 103.9 -90)
		(descr "Capacitor SMD 0603")
		(tags "capacitor 0603")
		(property "Reference" "C75"
			(at 2 0.575 270)
			(layer "F.SilkS")
			(effects
				(font
					(size 0.7 0.7)
					(thickness 0.15)
				)
				(justify left bottom)
			)
		)
		(property "Value" "C_10u_0603"
			(at 0 1.6 270)
			(layer "F.Fab")
			(effects
				(font
					(size 0.7 0.7)
					(thickness 0.15)
				)
				(justify left bottom)
			)
		)
		(property "Datasheet" "https://www.murata.com/products/productdetail?partno=GRM188R61A106KE69%23"
			(at 0 0 270)
			(layer "F.Fab")
			(hide yes)
			(effects
				(font
					(size 1.27 1.27)
					(thickness 0.15)
				)
			)
		)
		(property "Description" "SMD Multilayer Ceramic Capacitor, 10 µF, 10 V, 0603 [1608 Metric], ± 10%, X5R, GRM Series"
			(at 0 0 270)
			(layer "F.Fab")
			(hide yes)
			(effects
				(font
					(size 1.27 1.27)
					(thickness 0.15)
				)
			)
		)
		(property "Author" "Antmicro"
			(at -18.725 189.075 0)
			(layer "F.Fab")
			(hide yes)
			(effects
				(font
					(size 1 1)
					(thickness 0.15)
				)
			)
		)
		(property "Dielectric" "template_dielectric"
			(at -18.725 189.075 0)
			(layer "F.Fab")
			(hide yes)
			(effects
				(font
					(size 1 1)
					(thickness 0.15)
				)
			)
		)
		(property "License" "Apache-2.0"
			(at -18.725 189.075 0)
			(layer "F.Fab")
			(hide yes)
			(effects
				(font
					(size 1 1)
					(thickness 0.15)
				)
			)
		)
		(property "MPN" "GRM188R61A106KE69D"
			(at -18.725 189.075 0)
			(layer "F.Fab")
			(hide yes)
			(effects
				(font
					(size 1 1)
					(thickness 0.15)
				)
			)
		)
		(property "Manufacturer" "Murata"
			(at -18.725 189.075 0)
			(layer "F.Fab")
			(hide yes)
			(effects
				(font
					(size 1 1)
					(thickness 0.15)
				)
			)
		)
		(property "Val" "10u"
			(at -18.725 189.075 0)
			(layer "F.Fab")
			(hide yes)
			(effects
				(font
					(size 1 1)
					(thickness 0.15)
				)
			)
		)
		(property "Voltage" ""
			(at -18.725 189.075 0)
			(layer "F.Fab")
			(hide yes)
			(effects
				(font
					(size 1 1)
					(thickness 0.15)
				)
			)
		)
		(sheetname "/Power supply/")
		(sheetfile "power-supply.kicad_sch")
		(attr smd)
		(fp_line
			(start -0.15 0.4)
			(end 0.15 0.4)
			(stroke
				(width 0.15)
				(type solid)
			)
			(layer "F.SilkS")
		)
		(fp_line
			(start -0.15 -0.4)
			(end 0.15 -0.4)
			(stroke
				(width 0.15)
				(type solid)
			)
			(layer "F.SilkS")
		)
		(fp_rect
			(start -1.25 -0.65)
			(end 1.25 0.65)
			(stroke
				(width 0.05)
				(type solid)
			)
			(fill no)
			(layer "F.CrtYd")
		)
		(fp_rect
			(start -0.8 -0.4)
			(end 0.8 0.4)
			(stroke
				(width 0.15)
				(type solid)
			)
			(fill no)
			(layer "F.Fab")
		)
		(pad "1" smd roundrect
			(at -0.7 0 270)
			(size 0.8 1)
			(layers "F.Cu" "F.Mask" "F.Paste")
			(roundrect_rratio 0.2)
			(net 1 "GND")
			(pintype "passive")
		)
		(pad "2" smd roundrect
			(at 0.7 0 270)
			(size 0.8 1)
			(layers "F.Cu" "F.Mask" "F.Paste")
			(roundrect_rratio 0.2)
			(net 4 "VCC5V0")
			(pintype "passive")
		)
	)
	(footprint "antmicro-footprints:C_0402_1005Metric"
		(layer "F.Cu")
		(at 85.895 94.175 180)
		(descr "Capacitor SMD 0402")
		(tags "capacitor SMD 0402")
		(property "Reference" "C84"
			(at -3.005 -0.325 0)
			(layer "F.SilkS")
			(effects
				(font
					(size 0.7 0.7)
					(thickness 0.15)
				)
				(justify right bottom)
			)
		)
		(property "Value" "C_10u_0402"
			(at 0 1.4 0)
			(layer "F.Fab")
			(effects
				(font
					(size 0.7 0.7)
					(thickness 0.15)
				)
				(justify right bottom)
			)
		)
		(property "Datasheet" "https://www.yageo.com/en/Chart/Download/pdf/CC0402MRX5R5BB106"
			(at 0 0 180)
			(layer "F.Fab")
			(hide yes)
			(effects
				(font
					(size 1.27 1.27)
					(thickness 0.15)
				)
			)
		)
		(property "Description" "SMD Multilayer Ceramic Capacitor, 10 µF, 6.3 V, 0402 [1005 Metric], ± 20%, X5R, CC Series"
			(at 0 0 180)
			(layer "F.Fab")
			(hide yes)
			(effects
				(font
					(size 1.27 1.27)
					(thickness 0.15)
				)
			)
		)
		(property "Author" "Antmicro"
			(at 171.79 188.35 0)
			(layer "F.Fab")
			(hide yes)
			(effects
				(font
					(size 1 1)
					(thickness 0.15)
				)
			)
		)
		(property "Dielectric" ""
			(at 171.79 188.35 0)
			(layer "F.Fab")
			(hide yes)
			(effects
				(font
					(size 1 1)
					(thickness 0.15)
				)
			)
		)
		(property "License" "Apache-2.0"
			(at 171.79 188.35 0)
			(layer "F.Fab")
			(hide yes)
			(effects
				(font
					(size 1 1)
					(thickness 0.15)
				)
			)
		)
		(property "MPN" "CC0402MRX5R5BB106"
			(at 171.79 188.35 0)
			(layer "F.Fab")
			(hide yes)
			(effects
				(font
					(size 1 1)
					(thickness 0.15)
				)
			)
		)
		(property "Manufacturer" "YAGEO"
			(at 171.79 188.35 0)
			(layer "F.Fab")
			(hide yes)
			(effects
				(font
					(size 1 1)
					(thickness 0.15)
				)
			)
		)
		(property "Val" "10u"
			(at 171.79 188.35 0)
			(layer "F.Fab")
			(hide yes)
			(effects
				(font
					(size 1 1)
					(thickness 0.15)
				)
			)
		)
		(property "Voltage" ""
			(at 171.79 188.35 0)
			(layer "F.Fab")
			(hide yes)
			(effects
				(font
					(size 1 1)
					(thickness 0.15)
				)
			)
		)
		(sheetname "/Power supply/")
		(sheetfile "power-supply.kicad_sch")
		(attr smd)
		(fp_rect
			(start -0.925 -0.47)
			(end 0.925 0.47)
			(stroke
				(width 0.05)
				(type default)
			)
			(fill no)
			(layer "F.CrtYd")
		)
		(fp_line
			(start 0.504 0.248)
			(end -0.494 0.248)
			(stroke
				(width 0.15)
				(type solid)
			)
			(layer "F.Fab")
		)
		(fp_line
			(start 0.504 -0.25)
			(end 0.504 0.248)
			(stroke
				(width 0.15)
				(type solid)
			)
			(layer "F.Fab")
		)
		(fp_line
			(start -0.494 0.248)
			(end -0.494 -0.25)
			(stroke
				(width 0.15)
				(type solid)
			)
			(layer "F.Fab")
		)
		(fp_line
			(start -0.494 -0.25)
			(end 0.504 -0.25)
			(stroke
				(width 0.15)
				(type solid)
			)
			(layer "F.Fab")
		)
		(pad "1" smd roundrect
			(at -0.48 0 180)
			(size 0.59 0.64)
			(layers "F.Cu" "F.Mask" "F.Paste")
			(roundrect_rratio 0.25)
			(net 1 "GND")
			(pintype "passive")
		)
		(pad "2" smd roundrect
			(at 0.48 0 180)
			(size 0.59 0.64)
			(layers "F.Cu" "F.Mask" "F.Paste")
			(roundrect_rratio 0.25)
			(net 275 "Net-(C80-Pad2)")
			(pintype "passive")
		)
	)
	(footprint "antmicro-footprints:C_0402_1005Metric"
		(layer "F.Cu")
		(at 86.789 101.514 180)
		(descr "Capacitor SMD 0402")
		(tags "capacitor SMD 0402")
		(property "Reference" "C83"
			(at -3.026 -0.386 0)
			(layer "F.SilkS")
			(effects
				(font
					(size 0.7 0.7)
					(thickness 0.15)
				)
				(justify right bottom)
			)
		)
		(property "Value" "C_10u_0402"
			(at 0 1.4 0)
			(layer "F.Fab")
			(effects
				(font
					(size 0.7 0.7)
					(thickness 0.15)
				)
				(justify right bottom)
			)
		)
		(property "Datasheet" "https://www.yageo.com/en/Chart/Download/pdf/CC0402MRX5R5BB106"
			(at 0 0 180)
			(layer "F.Fab")
			(hide yes)
			(effects
				(font
					(size 1.27 1.27)
					(thickness 0.15)
				)
			)
		)
		(property "Description" "SMD Multilayer Ceramic Capacitor, 10 µF, 6.3 V, 0402 [1005 Metric], ± 20%, X5R, CC Series"
			(at 0 0 180)
			(layer "F.Fab")
			(hide yes)
			(effects
				(font
					(size 1.27 1.27)
					(thickness 0.15)
				)
			)
		)
		(property "Author" "Antmicro"
			(at 173.578 203.028 0)
			(layer "F.Fab")
			(hide yes)
			(effects
				(font
					(size 1 1)
					(thickness 0.15)
				)
			)
		)
		(property "Dielectric" ""
			(at 173.578 203.028 0)
			(layer "F.Fab")
			(hide yes)
			(effects
				(font
					(size 1 1)
					(thickness 0.15)
				)
			)
		)
		(property "License" "Apache-2.0"
			(at 173.578 203.028 0)
			(layer "F.Fab")
			(hide yes)
			(effects
				(font
					(size 1 1)
					(thickness 0.15)
				)
			)
		)
		(property "MPN" "CC0402MRX5R5BB106"
			(at 173.578 203.028 0)
			(layer "F.Fab")
			(hide yes)
			(effects
				(font
					(size 1 1)
					(thickness 0.15)
				)
			)
		)
		(property "Manufacturer" "YAGEO"
			(at 173.578 203.028 0)
			(layer "F.Fab")
			(hide yes)
			(effects
				(font
					(size 1 1)
					(thickness 0.15)
				)
			)
		)
		(property "Val" "10u"
			(at 173.578 203.028 0)
			(layer "F.Fab")
			(hide yes)
			(effects
				(font
					(size 1 1)
					(thickness 0.15)
				)
			)
		)
		(property "Voltage" ""
			(at 173.578 203.028 0)
			(layer "F.Fab")
			(hide yes)
			(effects
				(font
					(size 1 1)
					(thickness 0.15)
				)
			)
		)
		(sheetname "/Power supply/")
		(sheetfile "power-supply.kicad_sch")
		(attr smd)
		(fp_rect
			(start -0.925 -0.47)
			(end 0.925 0.47)
			(stroke
				(width 0.05)
				(type default)
			)
			(fill no)
			(layer "F.CrtYd")
		)
		(fp_line
			(start 0.504 0.248)
			(end -0.494 0.248)
			(stroke
				(width 0.15)
				(type solid)
			)
			(layer "F.Fab")
		)
		(fp_line
			(start 0.504 -0.25)
			(end 0.504 0.248)
			(stroke
				(width 0.15)
				(type solid)
			)
			(layer "F.Fab")
		)
		(fp_line
			(start -0.494 0.248)
			(end -0.494 -0.25)
			(stroke
				(width 0.15)
				(type solid)
			)
			(layer "F.Fab")
		)
		(fp_line
			(start -0.494 -0.25)
			(end 0.504 -0.25)
			(stroke
				(width 0.15)
				(type solid)
			)
			(layer "F.Fab")
		)
		(pad "1" smd roundrect
			(at -0.48 0 180)
			(size 0.59 0.64)
			(layers "F.Cu" "F.Mask" "F.Paste")
			(roundrect_rratio 0.25)
			(net 1 "GND")
			(pintype "passive")
		)
		(pad "2" smd roundrect
			(at 0.48 0 180)
			(size 0.59 0.64)
			(layers "F.Cu" "F.Mask" "F.Paste")
			(roundrect_rratio 0.25)
			(net 274 "Net-(C79-Pad2)")
			(pintype "passive")
		)
	)
	(footprint "antmicro-footprints:R_0402_1005Metric"
		(layer "F.Cu")
		(at 89.549 103.927 90)
		(descr "Resistor SMD 0402")
		(tags "resistor SMD 0402")
		(property "Reference" "R74"
			(at -0.973 3.351 90)
			(layer "F.SilkS")
			(effects
				(font
					(size 0.7 0.7)
					(thickness 0.15)
				)
				(justify left bottom)
			)
		)
		(property "Value" "R_100k_0402"
			(at 0 1.4 90)
			(layer "F.Fab")
			(effects
				(font
					(size 0.7 0.7)
					(thickness 0.15)
				)
				(justify left bottom)
			)
		)
		(property "Datasheet" "https://www.bourns.com/docs/product-datasheets/cr.pdf"
			(at 0 0 90)
			(layer "F.Fab")
			(hide yes)
			(effects
				(font
					(size 1.27 1.27)
					(thickness 0.15)
				)
			)
		)
		(property "Description" "SMD Chip Resistor, 100 kohm, ± 1%, 62.5 mW, 0402 [1005 Metric], Thick Film, General Purpose"
			(at 0 0 90)
			(layer "F.Fab")
			(hide yes)
			(effects
				(font
					(size 1.27 1.27)
					(thickness 0.15)
				)
			)
		)
		(property "Author" "Antmicro"
			(at 193.476 14.378 0)
			(layer "F.Fab")
			(hide yes)
			(effects
				(font
					(size 1 1)
					(thickness 0.15)
				)
			)
		)
		(property "License" "Apache-2.0"
			(at 193.476 14.378 0)
			(layer "F.Fab")
			(hide yes)
			(effects
				(font
					(size 1 1)
					(thickness 0.15)
				)
			)
		)
		(property "MPN" "CR0402-FX-1003GLF"
			(at 193.476 14.378 0)
			(layer "F.Fab")
			(hide yes)
			(effects
				(font
					(size 1 1)
					(thickness 0.15)
				)
			)
		)
		(property "Manufacturer" "Bourns"
			(at 193.476 14.378 0)
			(layer "F.Fab")
			(hide yes)
			(effects
				(font
					(size 1 1)
					(thickness 0.15)
				)
			)
		)
		(property "Tolerance" "1%"
			(at 193.476 14.378 0)
			(layer "F.Fab")
			(hide yes)
			(effects
				(font
					(size 1 1)
					(thickness 0.15)
				)
			)
		)
		(property "Val" "100k"
			(at 193.476 14.378 0)
			(layer "F.Fab")
			(hide yes)
			(effects
				(font
					(size 1 1)
					(thickness 0.15)
				)
			)
		)
		(sheetname "/Power supply/")
		(sheetfile "power-supply.kicad_sch")
		(attr smd)
		(fp_rect
			(start -0.925 -0.47)
			(end 0.925 0.47)
			(stroke
				(width 0.05)
				(type default)
			)
			(fill no)
			(layer "F.CrtYd")
		)
		(fp_rect
			(start -0.5 -0.25)
			(end 0.5 0.25)
			(stroke
				(width 0.15)
				(type solid)
			)
			(fill no)
			(layer "F.Fab")
		)
		(pad "1" smd roundrect
			(at -0.48 0 90)
			(size 0.59 0.64)
			(layers "F.Cu" "F.Mask" "F.Paste")
			(roundrect_rratio 0.25)
			(net 113 "Net-(U10-FB)")
			(pintype "passive")
		)
		(pad "2" smd roundrect
			(at 0.48 0 90)
			(size 0.59 0.64)
			(layers "F.Cu" "F.Mask" "F.Paste")
			(roundrect_rratio 0.25)
			(net 1 "GND")
			(pintype "passive")
		)
	)
	(footprint "antmicro-footprints:R_0402_1005Metric"
		(layer "F.Cu")
		(at 90.545 96.575 90)
		(descr "Resistor SMD 0402")
		(tags "resistor SMD 0402")
		(property "Reference" "R75"
			(at 0.775 0.355 90)
			(layer "F.SilkS")
			(effects
				(font
					(size 0.7 0.7)
					(thickness 0.15)
				)
				(justify left bottom)
			)
		)
		(property "Value" "R_200k_0402"
			(at 0 1.4 90)
			(layer "F.Fab")
			(effects
				(font
					(size 0.7 0.7)
					(thickness 0.15)
				)
				(justify left bottom)
			)
		)
		(property "Datasheet" "https://www.bourns.com/docs/product-datasheets/cr.pdf"
			(at 0 0 90)
			(layer "F.Fab")
			(hide yes)
			(effects
				(font
					(size 1.27 1.27)
					(thickness 0.15)
				)
			)
		)
		(property "Description" "SMD Chip Resistor, 200 kohm, ± 1%, 62.5 mW, 0402 [1005 Metric], Thick Film, General Purpose"
			(at 0 0 90)
			(layer "F.Fab")
			(hide yes)
			(effects
				(font
					(size 1.27 1.27)
					(thickness 0.15)
				)
			)
		)
		(property "Author" "Antmicro"
			(at 187.12 6.03 0)
			(layer "F.Fab")
			(hide yes)
			(effects
				(font
					(size 1 1)
					(thickness 0.15)
				)
			)
		)
		(property "License" "Apache-2.0"
			(at 187.12 6.03 0)
			(layer "F.Fab")
			(hide yes)
			(effects
				(font
					(size 1 1)
					(thickness 0.15)
				)
			)
		)
		(property "MPN" "CR0402-FX-2003GLF"
			(at 187.12 6.03 0)
			(layer "F.Fab")
			(hide yes)
			(effects
				(font
					(size 1 1)
					(thickness 0.15)
				)
			)
		)
		(property "Manufacturer" "Bourns"
			(at 187.12 6.03 0)
			(layer "F.Fab")
			(hide yes)
			(effects
				(font
					(size 1 1)
					(thickness 0.15)
				)
			)
		)
		(property "Tolerance" "1%"
			(at 187.12 6.03 0)
			(layer "F.Fab")
			(hide yes)
			(effects
				(font
					(size 1 1)
					(thickness 0.15)
				)
			)
		)
		(property "Val" "200k"
			(at 187.12 6.03 0)
			(layer "F.Fab")
			(hide yes)
			(effects
				(font
					(size 1 1)
					(thickness 0.15)
				)
			)
		)
		(sheetname "/Power supply/")
		(sheetfile "power-supply.kicad_sch")
		(attr smd)
		(fp_rect
			(start -0.925 -0.47)
			(end 0.925 0.47)
			(stroke
				(width 0.05)
				(type default)
			)
			(fill no)
			(layer "F.CrtYd")
		)
		(fp_rect
			(start -0.5 -0.25)
			(end 0.5 0.25)
			(stroke
				(width 0.15)
				(type solid)
			)
			(fill no)
			(layer "F.Fab")
		)
		(pad "1" smd roundrect
			(at -0.48 0 90)
			(size 0.59 0.64)
			(layers "F.Cu" "F.Mask" "F.Paste")
			(roundrect_rratio 0.25)
			(net 117 "Net-(U11-FB)")
			(pintype "passive")
		)
		(pad "2" smd roundrect
			(at 0.48 0 90)
			(size 0.59 0.64)
			(layers "F.Cu" "F.Mask" "F.Paste")
			(roundrect_rratio 0.25)
			(net 275 "Net-(C80-Pad2)")
			(pintype "passive")
		)
	)
	(footprint "antmicro-footprints:C_0402_1005Metric"
		(layer "F.Cu")
		(at 86.774 100.114 180)
		(descr "Capacitor SMD 0402")
		(tags "capacitor SMD 0402")
		(property "Reference" "C87"
			(at -3.026 -0.386 0)
			(layer "F.SilkS")
			(effects
				(font
					(size 0.7 0.7)
					(thickness 0.15)
				)
				(justify right bottom)
			)
		)
		(property "Value" "C_10u_0402"
			(at 0 1.4 0)
			(layer "F.Fab")
			(effects
				(font
					(size 0.7 0.7)
					(thickness 0.15)
				)
				(justify right bottom)
			)
		)
		(property "Datasheet" "https://www.yageo.com/en/Chart/Download/pdf/CC0402MRX5R5BB106"
			(at 0 0 180)
			(layer "F.Fab")
			(hide yes)
			(effects
				(font
					(size 1.27 1.27)
					(thickness 0.15)
				)
			)
		)
		(property "Description" "SMD Multilayer Ceramic Capacitor, 10 µF, 6.3 V, 0402 [1005 Metric], ± 20%, X5R, CC Series"
			(at 0 0 180)
			(layer "F.Fab")
			(hide yes)
			(effects
				(font
					(size 1.27 1.27)
					(thickness 0.15)
				)
			)
		)
		(property "Author" "Antmicro"
			(at 173.548 200.228 0)
			(layer "F.Fab")
			(hide yes)
			(effects
				(font
					(size 1 1)
					(thickness 0.15)
				)
			)
		)
		(property "Dielectric" ""
			(at 173.548 200.228 0)
			(layer "F.Fab")
			(hide yes)
			(effects
				(font
					(size 1 1)
					(thickness 0.15)
				)
			)
		)
		(property "License" "Apache-2.0"
			(at 173.548 200.228 0)
			(layer "F.Fab")
			(hide yes)
			(effects
				(font
					(size 1 1)
					(thickness 0.15)
				)
			)
		)
		(property "MPN" "CC0402MRX5R5BB106"
			(at 173.548 200.228 0)
			(layer "F.Fab")
			(hide yes)
			(effects
				(font
					(size 1 1)
					(thickness 0.15)
				)
			)
		)
		(property "Manufacturer" "YAGEO"
			(at 173.548 200.228 0)
			(layer "F.Fab")
			(hide yes)
			(effects
				(font
					(size 1 1)
					(thickness 0.15)
				)
			)
		)
		(property "Val" "10u"
			(at 173.548 200.228 0)
			(layer "F.Fab")
			(hide yes)
			(effects
				(font
					(size 1 1)
					(thickness 0.15)
				)
			)
		)
		(property "Voltage" ""
			(at 173.548 200.228 0)
			(layer "F.Fab")
			(hide yes)
			(effects
				(font
					(size 1 1)
					(thickness 0.15)
				)
			)
		)
		(sheetname "/Power supply/")
		(sheetfile "power-supply.kicad_sch")
		(attr smd)
		(fp_rect
			(start -0.925 -0.47)
			(end 0.925 0.47)
			(stroke
				(width 0.05)
				(type default)
			)
			(fill no)
			(layer "F.CrtYd")
		)
		(fp_line
			(start 0.504 0.248)
			(end -0.494 0.248)
			(stroke
				(width 0.15)
				(type solid)
			)
			(layer "F.Fab")
		)
		(fp_line
			(start 0.504 -0.25)
			(end 0.504 0.248)
			(stroke
				(width 0.15)
				(type solid)
			)
			(layer "F.Fab")
		)
		(fp_line
			(start -0.494 0.248)
			(end -0.494 -0.25)
			(stroke
				(width 0.15)
				(type solid)
			)
			(layer "F.Fab")
		)
		(fp_line
			(start -0.494 -0.25)
			(end 0.504 -0.25)
			(stroke
				(width 0.15)
				(type solid)
			)
			(layer "F.Fab")
		)
		(pad "1" smd roundrect
			(at -0.48 0 180)
			(size 0.59 0.64)
			(layers "F.Cu" "F.Mask" "F.Paste")
			(roundrect_rratio 0.25)
			(net 1 "GND")
			(pintype "passive")
		)
		(pad "2" smd roundrect
			(at 0.48 0 180)
			(size 0.59 0.64)
			(layers "F.Cu" "F.Mask" "F.Paste")
			(roundrect_rratio 0.25)
			(net 274 "Net-(C79-Pad2)")
			(pintype "passive")
		)
	)
	(footprint "antmicro-footprints:C_0603_1608Metric"
		(layer "F.Cu")
		(at 85.1 96.5 -90)
		(descr "Capacitor SMD 0603")
		(tags "capacitor 0603")
		(property "Reference" "C76"
			(at 2.25 0.94 270)
			(layer "F.SilkS")
			(effects
				(font
					(size 0.7 0.7)
					(thickness 0.15)
				)
				(justify left bottom)
			)
		)
		(property "Value" "C_10u_0603"
			(at 0 1.6 270)
			(layer "F.Fab")
			(effects
				(font
					(size 0.7 0.7)
					(thickness 0.15)
				)
				(justify left bottom)
			)
		)
		(property "Datasheet" "https://www.murata.com/products/productdetail?partno=GRM188R61A106KE69%23"
			(at 0 0 270)
			(layer "F.Fab")
			(hide yes)
			(effects
				(font
					(size 1.27 1.27)
					(thickness 0.15)
				)
			)
		)
		(property "Description" "SMD Multilayer Ceramic Capacitor, 10 µF, 10 V, 0603 [1608 Metric], ± 10%, X5R, GRM Series"
			(at 0 0 270)
			(layer "F.Fab")
			(hide yes)
			(effects
				(font
					(size 1.27 1.27)
					(thickness 0.15)
				)
			)
		)
		(property "Author" "Antmicro"
			(at -11.4 181.6 0)
			(layer "F.Fab")
			(hide yes)
			(effects
				(font
					(size 1 1)
					(thickness 0.15)
				)
			)
		)
		(property "Dielectric" "template_dielectric"
			(at -11.4 181.6 0)
			(layer "F.Fab")
			(hide yes)
			(effects
				(font
					(size 1 1)
					(thickness 0.15)
				)
			)
		)
		(property "License" "Apache-2.0"
			(at -11.4 181.6 0)
			(layer "F.Fab")
			(hide yes)
			(effects
				(font
					(size 1 1)
					(thickness 0.15)
				)
			)
		)
		(property "MPN" "GRM188R61A106KE69D"
			(at -11.4 181.6 0)
			(layer "F.Fab")
			(hide yes)
			(effects
				(font
					(size 1 1)
					(thickness 0.15)
				)
			)
		)
		(property "Manufacturer" "Murata"
			(at -11.4 181.6 0)
			(layer "F.Fab")
			(hide yes)
			(effects
				(font
					(size 1 1)
					(thickness 0.15)
				)
			)
		)
		(property "Val" "10u"
			(at -11.4 181.6 0)
			(layer "F.Fab")
			(hide yes)
			(effects
				(font
					(size 1 1)
					(thickness 0.15)
				)
			)
		)
		(property "Voltage" ""
			(at -11.4 181.6 0)
			(layer "F.Fab")
			(hide yes)
			(effects
				(font
					(size 1 1)
					(thickness 0.15)
				)
			)
		)
		(sheetname "/Power supply/")
		(sheetfile "power-supply.kicad_sch")
		(attr smd)
		(fp_line
			(start -0.15 0.4)
			(end 0.15 0.4)
			(stroke
				(width 0.15)
				(type solid)
			)
			(layer "F.SilkS")
		)
		(fp_line
			(start -0.15 -0.4)
			(end 0.15 -0.4)
			(stroke
				(width 0.15)
				(type solid)
			)
			(layer "F.SilkS")
		)
		(fp_rect
			(start -1.25 -0.65)
			(end 1.25 0.65)
			(stroke
				(width 0.05)
				(type solid)
			)
			(fill no)
			(layer "F.CrtYd")
		)
		(fp_rect
			(start -0.8 -0.4)
			(end 0.8 0.4)
			(stroke
				(width 0.15)
				(type solid)
			)
			(fill no)
			(layer "F.Fab")
		)
		(pad "1" smd roundrect
			(at -0.7 0 270)
			(size 0.8 1)
			(layers "F.Cu" "F.Mask" "F.Paste")
			(roundrect_rratio 0.2)
			(net 1 "GND")
			(pintype "passive")
		)
		(pad "2" smd roundrect
			(at 0.7 0 270)
			(size 0.8 1)
			(layers "F.Cu" "F.Mask" "F.Paste")
			(roundrect_rratio 0.2)
			(net 4 "VCC5V0")
			(pintype "passive")
		)
	)
	(footprint "antmicro-footprints:C_0402_1005Metric"
		(layer "F.Cu")
		(at 85.895 92.775 180)
		(descr "Capacitor SMD 0402")
		(tags "capacitor SMD 0402")
		(property "Reference" "C88"
			(at -3.005 -0.325 0)
			(layer "F.SilkS")
			(effects
				(font
					(size 0.7 0.7)
					(thickness 0.15)
				)
				(justify right bottom)
			)
		)
		(property "Value" "C_10u_0402"
			(at 0 1.4 0)
			(layer "F.Fab")
			(effects
				(font
					(size 0.7 0.7)
					(thickness 0.15)
				)
				(justify right bottom)
			)
		)
		(property "Datasheet" "https://www.yageo.com/en/Chart/Download/pdf/CC0402MRX5R5BB106"
			(at 0 0 180)
			(layer "F.Fab")
			(hide yes)
			(effects
				(font
					(size 1.27 1.27)
					(thickness 0.15)
				)
			)
		)
		(property "Description" "SMD Multilayer Ceramic Capacitor, 10 µF, 6.3 V, 0402 [1005 Metric], ± 20%, X5R, CC Series"
			(at 0 0 180)
			(layer "F.Fab")
			(hide yes)
			(effects
				(font
					(size 1.27 1.27)
					(thickness 0.15)
				)
			)
		)
		(property "Author" "Antmicro"
			(at 171.79 185.55 0)
			(layer "F.Fab")
			(hide yes)
			(effects
				(font
					(size 1 1)
					(thickness 0.15)
				)
			)
		)
		(property "Dielectric" ""
			(at 171.79 185.55 0)
			(layer "F.Fab")
			(hide yes)
			(effects
				(font
					(size 1 1)
					(thickness 0.15)
				)
			)
		)
		(property "License" "Apache-2.0"
			(at 171.79 185.55 0)
			(layer "F.Fab")
			(hide yes)
			(effects
				(font
					(size 1 1)
					(thickness 0.15)
				)
			)
		)
		(property "MPN" "CC0402MRX5R5BB106"
			(at 171.79 185.55 0)
			(layer "F.Fab")
			(hide yes)
			(effects
				(font
					(size 1 1)
					(thickness 0.15)
				)
			)
		)
		(property "Manufacturer" "YAGEO"
			(at 171.79 185.55 0)
			(layer "F.Fab")
			(hide yes)
			(effects
				(font
					(size 1 1)
					(thickness 0.15)
				)
			)
		)
		(property "Val" "10u"
			(at 171.79 185.55 0)
			(layer "F.Fab")
			(hide yes)
			(effects
				(font
					(size 1 1)
					(thickness 0.15)
				)
			)
		)
		(property "Voltage" ""
			(at 171.79 185.55 0)
			(layer "F.Fab")
			(hide yes)
			(effects
				(font
					(size 1 1)
					(thickness 0.15)
				)
			)
		)
		(sheetname "/Power supply/")
		(sheetfile "power-supply.kicad_sch")
		(attr smd)
		(fp_rect
			(start -0.925 -0.47)
			(end 0.925 0.47)
			(stroke
				(width 0.05)
				(type default)
			)
			(fill no)
			(layer "F.CrtYd")
		)
		(fp_line
			(start 0.504 0.248)
			(end -0.494 0.248)
			(stroke
				(width 0.15)
				(type solid)
			)
			(layer "F.Fab")
		)
		(fp_line
			(start 0.504 -0.25)
			(end 0.504 0.248)
			(stroke
				(width 0.15)
				(type solid)
			)
			(layer "F.Fab")
		)
		(fp_line
			(start -0.494 0.248)
			(end -0.494 -0.25)
			(stroke
				(width 0.15)
				(type solid)
			)
			(layer "F.Fab")
		)
		(fp_line
			(start -0.494 -0.25)
			(end 0.504 -0.25)
			(stroke
				(width 0.15)
				(type solid)
			)
			(layer "F.Fab")
		)
		(pad "1" smd roundrect
			(at -0.48 0 180)
			(size 0.59 0.64)
			(layers "F.Cu" "F.Mask" "F.Paste")
			(roundrect_rratio 0.25)
			(net 1 "GND")
			(pintype "passive")
		)
		(pad "2" smd roundrect
			(at 0.48 0 180)
			(size 0.59 0.64)
			(layers "F.Cu" "F.Mask" "F.Paste")
			(roundrect_rratio 0.25)
			(net 275 "Net-(C80-Pad2)")
			(pintype "passive")
		)
	)
	(footprint "antmicro-footprints:R_0402_1005Metric"
		(layer "F.Cu")
		(at 90.545 103.925 -90)
		(descr "Resistor SMD 0402")
		(tags "resistor SMD 0402")
		(property "Reference" "R73"
			(at -1.225 -3.355 90)
			(layer "F.SilkS")
			(effects
				(font
					(size 0.7 0.7)
					(thickness 0.15)
				)
				(justify right bottom)
			)
		)
		(property "Value" "R_453k_0402"
			(at 0 1.4 90)
			(layer "F.Fab")
			(effects
				(font
					(size 0.7 0.7)
					(thickness 0.15)
				)
				(justify right bottom)
			)
		)
		(property "Datasheet" "https://www.bourns.com/docs/product-datasheets/cr.pdf"
			(at 0 0 270)
			(layer "F.Fab")
			(hide yes)
			(effects
				(font
					(size 1.27 1.27)
					(thickness 0.15)
				)
			)
		)
		(property "Description" "SMD Chip Resistor"
			(at 0 0 270)
			(layer "F.Fab")
			(hide yes)
			(effects
				(font
					(size 1.27 1.27)
					(thickness 0.15)
				)
			)
		)
		(property "Author" "Antmicro"
			(at -13.38 194.47 0)
			(layer "F.Fab")
			(hide yes)
			(effects
				(font
					(size 1 1)
					(thickness 0.15)
				)
			)
		)
		(property "License" "Apache-2.0"
			(at -13.38 194.47 0)
			(layer "F.Fab")
			(hide yes)
			(effects
				(font
					(size 1 1)
					(thickness 0.15)
				)
			)
		)
		(property "MPN" "CR0402-FX-4533GLF"
			(at -13.38 194.47 0)
			(layer "F.Fab")
			(hide yes)
			(effects
				(font
					(size 1 1)
					(thickness 0.15)
				)
			)
		)
		(property "Manufacturer" "Bourns"
			(at -13.38 194.47 0)
			(layer "F.Fab")
			(hide yes)
			(effects
				(font
					(size 1 1)
					(thickness 0.15)
				)
			)
		)
		(property "Tolerance" "1%"
			(at -13.38 194.47 0)
			(layer "F.Fab")
			(hide yes)
			(effects
				(font
					(size 1 1)
					(thickness 0.15)
				)
			)
		)
		(property "Val" "453k"
			(at -13.38 194.47 0)
			(layer "F.Fab")
			(hide yes)
			(effects
				(font
					(size 1 1)
					(thickness 0.15)
				)
			)
		)
		(sheetname "/Power supply/")
		(sheetfile "power-supply.kicad_sch")
		(attr smd)
		(fp_rect
			(start -0.925 -0.47)
			(end 0.925 0.47)
			(stroke
				(width 0.05)
				(type default)
			)
			(fill no)
			(layer "F.CrtYd")
		)
		(fp_rect
			(start -0.5 -0.25)
			(end 0.5 0.25)
			(stroke
				(width 0.15)
				(type solid)
			)
			(fill no)
			(layer "F.Fab")
		)
		(pad "1" smd roundrect
			(at -0.48 0 270)
			(size 0.59 0.64)
			(layers "F.Cu" "F.Mask" "F.Paste")
			(roundrect_rratio 0.25)
			(net 274 "Net-(C79-Pad2)")
			(pintype "passive")
		)
		(pad "2" smd roundrect
			(at 0.48 0 270)
			(size 0.59 0.64)
			(layers "F.Cu" "F.Mask" "F.Paste")
			(roundrect_rratio 0.25)
			(net 113 "Net-(U10-FB)")
			(pintype "passive")
		)
	)
	(footprint "antmicro-footprints:R_0402_1005Metric"
		(layer "F.Cu")
		(at 89.545 96.575 90)
		(descr "Resistor SMD 0402")
		(tags "resistor SMD 0402")
		(property "Reference" "R76"
			(at 0.775 0.355 90)
			(layer "F.SilkS")
			(effects
				(font
					(size 0.7 0.7)
					(thickness 0.15)
				)
				(justify left bottom)
			)
		)
		(property "Value" "R_100k_0402"
			(at 0 1.4 90)
			(layer "F.Fab")
			(effects
				(font
					(size 0.7 0.7)
					(thickness 0.15)
				)
				(justify left bottom)
			)
		)
		(property "Datasheet" "https://www.bourns.com/docs/product-datasheets/cr.pdf"
			(at 0 0 90)
			(layer "F.Fab")
			(hide yes)
			(effects
				(font
					(size 1.27 1.27)
					(thickness 0.15)
				)
			)
		)
		(property "Description" "SMD Chip Resistor, 100 kohm, ± 1%, 62.5 mW, 0402 [1005 Metric], Thick Film, General Purpose"
			(at 0 0 90)
			(layer "F.Fab")
			(hide yes)
			(effects
				(font
					(size 1.27 1.27)
					(thickness 0.15)
				)
			)
		)
		(property "Author" "Antmicro"
			(at 186.12 7.03 0)
			(layer "F.Fab")
			(hide yes)
			(effects
				(font
					(size 1 1)
					(thickness 0.15)
				)
			)
		)
		(property "License" "Apache-2.0"
			(at 186.12 7.03 0)
			(layer "F.Fab")
			(hide yes)
			(effects
				(font
					(size 1 1)
					(thickness 0.15)
				)
			)
		)
		(property "MPN" "CR0402-FX-1003GLF"
			(at 186.12 7.03 0)
			(layer "F.Fab")
			(hide yes)
			(effects
				(font
					(size 1 1)
					(thickness 0.15)
				)
			)
		)
		(property "Manufacturer" "Bourns"
			(at 186.12 7.03 0)
			(layer "F.Fab")
			(hide yes)
			(effects
				(font
					(size 1 1)
					(thickness 0.15)
				)
			)
		)
		(property "Tolerance" "1%"
			(at 186.12 7.03 0)
			(layer "F.Fab")
			(hide yes)
			(effects
				(font
					(size 1 1)
					(thickness 0.15)
				)
			)
		)
		(property "Val" "100k"
			(at 186.12 7.03 0)
			(layer "F.Fab")
			(hide yes)
			(effects
				(font
					(size 1 1)
					(thickness 0.15)
				)
			)
		)
		(sheetname "/Power supply/")
		(sheetfile "power-supply.kicad_sch")
		(attr smd)
		(fp_rect
			(start -0.925 -0.47)
			(end 0.925 0.47)
			(stroke
				(width 0.05)
				(type default)
			)
			(fill no)
			(layer "F.CrtYd")
		)
		(fp_rect
			(start -0.5 -0.25)
			(end 0.5 0.25)
			(stroke
				(width 0.15)
				(type solid)
			)
			(fill no)
			(layer "F.Fab")
		)
		(pad "1" smd roundrect
			(at -0.48 0 90)
			(size 0.59 0.64)
			(layers "F.Cu" "F.Mask" "F.Paste")
			(roundrect_rratio 0.25)
			(net 117 "Net-(U11-FB)")
			(pintype "passive")
		)
		(pad "2" smd roundrect
			(at 0.48 0 90)
			(size 0.59 0.64)
			(layers "F.Cu" "F.Mask" "F.Paste")
			(roundrect_rratio 0.25)
			(net 1 "GND")
			(pintype "passive")
		)
	)
	(footprint "antmicro-footprints:QFN-8_2x1.5mm"
		(layer "F.Cu")
		(at 86.995 96.775 180)
		(property "Reference" "U11"
			(at 0.305 -2.205 180)
			(layer "F.SilkS")
			(effects
				(font
					(size 0.7 0.7)
					(thickness 0.15)
				)
				(justify left bottom)
			)
		)
		(property "Value" "TPS62823DLCT"
			(at 0 2.2 180)
			(layer "F.Fab")
			(effects
				(font
					(size 0.7 0.7)
					(thickness 0.15)
				)
				(justify left bottom)
			)
		)
		(property "Datasheet" "https://www.ti.com/lit/ds/symlink/tps62823.pdf?ts=1685970309606&ref_url=https%253A%252F%252Fwww.ti.com%252Fproduct%252FTPS62823%252Fpart-details%252FTPS62823DLCT"
			(at 0 0 180)
			(layer "F.Fab")
			(hide yes)
			(effects
				(font
					(size 1.27 1.27)
					(thickness 0.15)
				)
			)
		)
		(property "Description" "DC/DC converter"
			(at 0 0 180)
			(layer "F.Fab")
			(hide yes)
			(effects
				(font
					(size 1.27 1.27)
					(thickness 0.15)
				)
			)
		)
		(property "Author" "Antmicro"
			(at 173.99 193.55 0)
			(layer "F.Fab")
			(hide yes)
			(effects
				(font
					(size 1 1)
					(thickness 0.15)
				)
			)
		)
		(property "License" "Apache-2.0"
			(at 173.99 193.55 0)
			(layer "F.Fab")
			(hide yes)
			(effects
				(font
					(size 1 1)
					(thickness 0.15)
				)
			)
		)
		(property "MPN" "TPS62823DLCT"
			(at 173.99 193.55 0)
			(layer "F.Fab")
			(hide yes)
			(effects
				(font
					(size 1 1)
					(thickness 0.15)
				)
			)
		)
		(property "Manufacturer" "Texas Instruments"
			(at 173.99 193.55 0)
			(layer "F.Fab")
			(hide yes)
			(effects
				(font
					(size 1 1)
					(thickness 0.15)
				)
			)
		)
		(sheetname "/Power supply/")
		(sheetfile "power-supply.kicad_sch")
		(attr smd)
		(fp_line
			(start -0.25 -1.05)
			(end 0.9 -1.05)
			(stroke
				(width 0.15)
				(type solid)
			)
			(layer "F.SilkS")
		)
		(fp_line
			(start -0.9 1.05)
			(end 0.9 1.05)
			(stroke
				(width 0.15)
				(type solid)
			)
			(layer "F.SilkS")
		)
		(fp_circle
			(center -0.9 -1.05)
			(end -0.849 -1.05)
			(stroke
				(width 0.15)
				(type solid)
			)
			(fill yes)
			(layer "F.SilkS")
		)
		(fp_rect
			(start -1.1 -1.25)
			(end 1.1 1.25)
			(stroke
				(width 0.05)
				(type solid)
			)
			(fill no)
			(layer "F.CrtYd")
		)
		(fp_line
			(start 0.998 0.998)
			(end -1 0.998)
			(stroke
				(width 0.15)
				(type solid)
			)
			(layer "F.Fab")
		)
		(fp_line
			(start 0.998 -1)
			(end 0.998 0.998)
			(stroke
				(width 0.15)
				(type solid)
			)
			(layer "F.Fab")
		)
		(fp_line
			(start -0.5 -1)
			(end 0.998 -1)
			(stroke
				(width 0.15)
				(type solid)
			)
			(layer "F.Fab")
		)
		(fp_line
			(start -1 0.998)
			(end -1 -0.5)
			(stroke
				(width 0.15)
				(type solid)
			)
			(layer "F.Fab")
		)
		(fp_line
			(start -1 -0.5)
			(end -0.5 -1)
			(stroke
				(width 0.15)
				(type solid)
			)
			(layer "F.Fab")
		)
		(pad "1" smd rect
			(at -0.677 -0.75 180)
			(size 0.55 0.25)
			(layers "F.Cu" "F.Mask" "F.Paste")
			(net 315 "Net-(U11-EN)")
			(pinfunction "EN")
			(pintype "input")
		)
		(pad "2" smd rect
			(at -0.677 -0.25 180)
			(size 0.55 0.25)
			(layers "F.Cu" "F.Mask" "F.Paste")
			(net 117 "Net-(U11-FB)")
			(pinfunction "FB")
			(pintype "bidirectional")
		)
		(pad "3" smd rect
			(at -0.677 0.248 180)
			(size 0.55 0.25)
			(layers "F.Cu" "F.Mask" "F.Paste")
			(net 1 "GND")
			(pinfunction "AGND")
			(pintype "power_in")
		)
		(pad "4" smd rect
			(at -0.677 0.748 180)
			(size 0.55 0.25)
			(layers "F.Cu" "F.Mask" "F.Paste")
			(net 530 "unconnected-(U11-NC-Pad4)")
			(pinfunction "NC")
			(pintype "no_connect")
		)
		(pad "5" smd rect
			(at 0.675 0.748 180)
			(size 0.55 0.25)
			(layers "F.Cu" "F.Mask" "F.Paste")
			(net 1 "GND")
			(pinfunction "PGND")
			(pintype "power_in")
		)
		(pad "6" smd rect
			(at 0.675 0.248 180)
			(size 0.55 0.25)
			(layers "F.Cu" "F.Mask" "F.Paste")
			(net 288 "Net-(U11-SW)")
			(pinfunction "SW")
			(pintype "bidirectional")
		)
		(pad "7" smd rect
			(at 0.675 -0.25 180)
			(size 0.55 0.25)
			(layers "F.Cu" "F.Mask" "F.Paste")
			(net 4 "VCC5V0")
			(pinfunction "VIN")
			(pintype "power_in")
		)
		(pad "8" smd rect
			(at 0.675 -0.75 180)
			(size 0.55 0.25)
			(layers "F.Cu" "F.Mask" "F.Paste")
			(net 292 "/Power supply/1V8_PG")
			(pinfunction "PG")
			(pintype "output")
		)
	)
	(footprint "antmicro-footprints:C_0402_1005Metric"
		(layer "F.Cu")
		(at 128.996 168.181 -90)
		(descr "Capacitor SMD 0402")
		(tags "capacitor SMD 0402")
		(property "Reference" "C179"
			(at 0.819 -0.404 90)
			(layer "F.SilkS")
			(effects
				(font
					(size 0.7 0.7)
					(thickness 0.15)
				)
				(justify right bottom)
			)
		)
		(property "Value" "C_100n_6V3_0402"
			(at 0 1.4 90)
			(layer "F.Fab")
			(effects
				(font
					(size 0.7 0.7)
					(thickness 0.15)
				)
				(justify right bottom)
			)
		)
		(property "Datasheet" "https://www.passivecomponent.com/wp-content/uploads/datasheet/WTC_MLCC_General_Purpose.pdf"
			(at 0 0 270)
			(layer "F.Fab")
			(hide yes)
			(effects
				(font
					(size 1.27 1.27)
					(thickness 0.15)
				)
			)
		)
		(property "Description" "SMT Multilayer Ceramic Capacitor, 0.1 µF, 6.3 V, 0402 [1005 Metric], ± 10%, X5R, Walsin MLCC"
			(at 0 0 270)
			(layer "F.Fab")
			(hide yes)
			(effects
				(font
					(size 1.27 1.27)
					(thickness 0.15)
				)
			)
		)
		(property "Author" "Antmicro"
			(at -39.185 297.177 0)
			(layer "F.Fab")
			(hide yes)
			(effects
				(font
					(size 1 1)
					(thickness 0.15)
				)
			)
		)
		(property "Dielectric" ""
			(at -39.185 297.177 0)
			(layer "F.Fab")
			(hide yes)
			(effects
				(font
					(size 1 1)
					(thickness 0.15)
				)
			)
		)
		(property "License" "Apache-2.0"
			(at -39.185 297.177 0)
			(layer "F.Fab")
			(hide yes)
			(effects
				(font
					(size 1 1)
					(thickness 0.15)
				)
			)
		)
		(property "MPN" "0402X104K6R3CT"
			(at -39.185 297.177 0)
			(layer "F.Fab")
			(hide yes)
			(effects
				(font
					(size 1 1)
					(thickness 0.15)
				)
			)
		)
		(property "Manufacturer" "Walsin"
			(at -39.185 297.177 0)
			(layer "F.Fab")
			(hide yes)
			(effects
				(font
					(size 1 1)
					(thickness 0.15)
				)
			)
		)
		(property "Public" "False"
			(at -39.185 297.177 0)
			(layer "F.Fab")
			(hide yes)
			(effects
				(font
					(size 1 1)
					(thickness 0.15)
				)
			)
		)
		(property "Val" "100n"
			(at -39.185 297.177 0)
			(layer "F.Fab")
			(hide yes)
			(effects
				(font
					(size 1 1)
					(thickness 0.15)
				)
			)
		)
		(property "Voltage" ""
			(at -39.185 297.177 0)
			(layer "F.Fab")
			(hide yes)
			(effects
				(font
					(size 1 1)
					(thickness 0.15)
				)
			)
		)
		(sheetname "/PCIe-connector/")
		(sheetfile "pcie-conn.kicad_sch")
		(attr smd)
		(fp_rect
			(start -0.925 -0.47)
			(end 0.925 0.47)
			(stroke
				(width 0.05)
				(type default)
			)
			(fill no)
			(layer "F.CrtYd")
		)
		(fp_line
			(start -0.494 0.248)
			(end -0.494 -0.25)
			(stroke
				(width 0.15)
				(type solid)
			)
			(layer "F.Fab")
		)
		(fp_line
			(start 0.504 0.248)
			(end -0.494 0.248)
			(stroke
				(width 0.15)
				(type solid)
			)
			(layer "F.Fab")
		)
		(fp_line
			(start -0.494 -0.25)
			(end 0.504 -0.25)
			(stroke
				(width 0.15)
				(type solid)
			)
			(layer "F.Fab")
		)
		(fp_line
			(start 0.504 -0.25)
			(end 0.504 0.248)
			(stroke
				(width 0.15)
				(type solid)
			)
			(layer "F.Fab")
		)
		(pad "1" smd roundrect
			(at -0.48 0 270)
			(size 0.59 0.64)
			(layers "F.Cu" "F.Mask" "F.Paste")
			(roundrect_rratio 0.25)
			(net 373 "/PCIe-connector/PCIE_HPM_TX2_C_P")
			(pintype "passive")
		)
		(pad "2" smd roundrect
			(at 0.48 0 270)
			(size 0.59 0.64)
			(layers "F.Cu" "F.Mask" "F.Paste")
			(roundrect_rratio 0.25)
			(net 355 "PCIE_HPM_TX[2]_P")
			(pintype "passive")
		)
	)
	(footprint "antmicro-footprints:C_0402_1005Metric"
		(layer "F.Cu")
		(at 130.005 168.181 -90)
		(descr "Capacitor SMD 0402")
		(tags "capacitor SMD 0402")
		(property "Reference" "C181"
			(at 0.819 -0.404 90)
			(layer "F.SilkS")
			(effects
				(font
					(size 0.7 0.7)
					(thickness 0.15)
				)
				(justify right bottom)
			)
		)
		(property "Value" "C_100n_6V3_0402"
			(at 0 1.4 90)
			(layer "F.Fab")
			(effects
				(font
					(size 0.7 0.7)
					(thickness 0.15)
				)
				(justify right bottom)
			)
		)
		(property "Datasheet" "https://www.passivecomponent.com/wp-content/uploads/datasheet/WTC_MLCC_General_Purpose.pdf"
			(at 0 0 270)
			(layer "F.Fab")
			(hide yes)
			(effects
				(font
					(size 1.27 1.27)
					(thickness 0.15)
				)
			)
		)
		(property "Description" "SMT Multilayer Ceramic Capacitor, 0.1 µF, 6.3 V, 0402 [1005 Metric], ± 10%, X5R, Walsin MLCC"
			(at 0 0 270)
			(layer "F.Fab")
			(hide yes)
			(effects
				(font
					(size 1.27 1.27)
					(thickness 0.15)
				)
			)
		)
		(property "Author" "Antmicro"
			(at -38.176 298.186 0)
			(layer "F.Fab")
			(hide yes)
			(effects
				(font
					(size 1 1)
					(thickness 0.15)
				)
			)
		)
		(property "Dielectric" ""
			(at -38.176 298.186 0)
			(layer "F.Fab")
			(hide yes)
			(effects
				(font
					(size 1 1)
					(thickness 0.15)
				)
			)
		)
		(property "License" "Apache-2.0"
			(at -38.176 298.186 0)
			(layer "F.Fab")
			(hide yes)
			(effects
				(font
					(size 1 1)
					(thickness 0.15)
				)
			)
		)
		(property "MPN" "0402X104K6R3CT"
			(at -38.176 298.186 0)
			(layer "F.Fab")
			(hide yes)
			(effects
				(font
					(size 1 1)
					(thickness 0.15)
				)
			)
		)
		(property "Manufacturer" "Walsin"
			(at -38.176 298.186 0)
			(layer "F.Fab")
			(hide yes)
			(effects
				(font
					(size 1 1)
					(thickness 0.15)
				)
			)
		)
		(property "Public" "False"
			(at -38.176 298.186 0)
			(layer "F.Fab")
			(hide yes)
			(effects
				(font
					(size 1 1)
					(thickness 0.15)
				)
			)
		)
		(property "Val" "100n"
			(at -38.176 298.186 0)
			(layer "F.Fab")
			(hide yes)
			(effects
				(font
					(size 1 1)
					(thickness 0.15)
				)
			)
		)
		(property "Voltage" ""
			(at -38.176 298.186 0)
			(layer "F.Fab")
			(hide yes)
			(effects
				(font
					(size 1 1)
					(thickness 0.15)
				)
			)
		)
		(sheetname "/PCIe-connector/")
		(sheetfile "pcie-conn.kicad_sch")
		(attr smd)
		(fp_rect
			(start -0.925 -0.47)
			(end 0.925 0.47)
			(stroke
				(width 0.05)
				(type default)
			)
			(fill no)
			(layer "F.CrtYd")
		)
		(fp_line
			(start -0.494 0.248)
			(end -0.494 -0.25)
			(stroke
				(width 0.15)
				(type solid)
			)
			(layer "F.Fab")
		)
		(fp_line
			(start 0.504 0.248)
			(end -0.494 0.248)
			(stroke
				(width 0.15)
				(type solid)
			)
			(layer "F.Fab")
		)
		(fp_line
			(start -0.494 -0.25)
			(end 0.504 -0.25)
			(stroke
				(width 0.15)
				(type solid)
			)
			(layer "F.Fab")
		)
		(fp_line
			(start 0.504 -0.25)
			(end 0.504 0.248)
			(stroke
				(width 0.15)
				(type solid)
			)
			(layer "F.Fab")
		)
		(pad "1" smd roundrect
			(at -0.48 0 270)
			(size 0.59 0.64)
			(layers "F.Cu" "F.Mask" "F.Paste")
			(roundrect_rratio 0.25)
			(net 375 "/PCIe-connector/PCIE_HPM_TX2_C_N")
			(pintype "passive")
		)
		(pad "2" smd roundrect
			(at 0.48 0 270)
			(size 0.59 0.64)
			(layers "F.Cu" "F.Mask" "F.Paste")
			(roundrect_rratio 0.25)
			(net 357 "PCIE_HPM_TX[2]_N")
			(pintype "passive")
		)
	)
	(footprint "antmicro-footprints:R_0402_1005Metric"
		(layer "F.Cu")
		(at 73.15 97.995 180)
		(descr "Resistor SMD 0402")
		(tags "resistor SMD 0402")
		(property "Reference" "R98"
			(at -1.05 0.495 0)
			(layer "F.SilkS")
			(effects
				(font
					(size 0.7 0.7)
					(thickness 0.15)
				)
				(justify right bottom)
			)
		)
		(property "Value" "R_1k_0402"
			(at 0 1.4 0)
			(layer "F.Fab")
			(effects
				(font
					(size 0.7 0.7)
					(thickness 0.15)
				)
				(justify right bottom)
			)
		)
		(property "Datasheet" "https://www.bourns.com/docs/product-datasheets/cr.pdf"
			(at 0 0 180)
			(layer "F.Fab")
			(hide yes)
			(effects
				(font
					(size 1.27 1.27)
					(thickness 0.15)
				)
			)
		)
		(property "Description" "SMD Chip Resistor, 1 kohm, ± 1%, 63 mW, 0402 [1005 Metric], Thick Film, General Purpose"
			(at 0 0 180)
			(layer "F.Fab")
			(hide yes)
			(effects
				(font
					(size 1.27 1.27)
					(thickness 0.15)
				)
			)
		)
		(property "Author" "Antmicro"
			(at 146.3 195.99 0)
			(layer "F.Fab")
			(hide yes)
			(effects
				(font
					(size 1 1)
					(thickness 0.15)
				)
			)
		)
		(property "License" "Apache-2.0"
			(at 146.3 195.99 0)
			(layer "F.Fab")
			(hide yes)
			(effects
				(font
					(size 1 1)
					(thickness 0.15)
				)
			)
		)
		(property "MPN" "CR0402-FX-1001GLF"
			(at 146.3 195.99 0)
			(layer "F.Fab")
			(hide yes)
			(effects
				(font
					(size 1 1)
					(thickness 0.15)
				)
			)
		)
		(property "Manufacturer" "Bourns"
			(at 146.3 195.99 0)
			(layer "F.Fab")
			(hide yes)
			(effects
				(font
					(size 1 1)
					(thickness 0.15)
				)
			)
		)
		(property "Tolerance" "1%"
			(at 146.3 195.99 0)
			(layer "F.Fab")
			(hide yes)
			(effects
				(font
					(size 1 1)
					(thickness 0.15)
				)
			)
		)
		(property "Val" "1k"
			(at 146.3 195.99 0)
			(layer "F.Fab")
			(hide yes)
			(effects
				(font
					(size 1 1)
					(thickness 0.15)
				)
			)
		)
		(sheetname "/Power supply/")
		(sheetfile "power-supply.kicad_sch")
		(attr smd)
		(fp_rect
			(start -0.925 -0.47)
			(end 0.925 0.47)
			(stroke
				(width 0.05)
				(type default)
			)
			(fill no)
			(layer "F.CrtYd")
		)
		(fp_rect
			(start -0.5 -0.25)
			(end 0.5 0.25)
			(stroke
				(width 0.15)
				(type solid)
			)
			(fill no)
			(layer "F.Fab")
		)
		(pad "1" smd roundrect
			(at -0.48 0 180)
			(size 0.59 0.64)
			(layers "F.Cu" "F.Mask" "F.Paste")
			(roundrect_rratio 0.25)
			(net 224 "Net-(D8-A)")
			(pintype "passive")
		)
		(pad "2" smd roundrect
			(at 0.48 0 180)
			(size 0.59 0.64)
			(layers "F.Cu" "F.Mask" "F.Paste")
			(roundrect_rratio 0.25)
			(net 2 "VCC3V3")
			(pintype "passive")
		)
	)
	(footprint "antmicro-footprints:R_0402_1005Metric"
		(layer "F.Cu")
		(at 73.15 93.931 180)
		(descr "Resistor SMD 0402")
		(tags "resistor SMD 0402")
		(property "Reference" "R97"
			(at -1.05 0.531 0)
			(layer "F.SilkS")
			(effects
				(font
					(size 0.7 0.7)
					(thickness 0.15)
				)
				(justify right bottom)
			)
		)
		(property "Value" "R_1k_0402"
			(at 0 1.4 0)
			(layer "F.Fab")
			(effects
				(font
					(size 0.7 0.7)
					(thickness 0.15)
				)
				(justify right bottom)
			)
		)
		(property "Datasheet" "https://www.bourns.com/docs/product-datasheets/cr.pdf"
			(at 0 0 180)
			(layer "F.Fab")
			(hide yes)
			(effects
				(font
					(size 1.27 1.27)
					(thickness 0.15)
				)
			)
		)
		(property "Description" "SMD Chip Resistor, 1 kohm, ± 1%, 63 mW, 0402 [1005 Metric], Thick Film, General Purpose"
			(at 0 0 180)
			(layer "F.Fab")
			(hide yes)
			(effects
				(font
					(size 1.27 1.27)
					(thickness 0.15)
				)
			)
		)
		(property "Author" "Antmicro"
			(at 146.3 187.862 0)
			(layer "F.Fab")
			(hide yes)
			(effects
				(font
					(size 1 1)
					(thickness 0.15)
				)
			)
		)
		(property "License" "Apache-2.0"
			(at 146.3 187.862 0)
			(layer "F.Fab")
			(hide yes)
			(effects
				(font
					(size 1 1)
					(thickness 0.15)
				)
			)
		)
		(property "MPN" "CR0402-FX-1001GLF"
			(at 146.3 187.862 0)
			(layer "F.Fab")
			(hide yes)
			(effects
				(font
					(size 1 1)
					(thickness 0.15)
				)
			)
		)
		(property "Manufacturer" "Bourns"
			(at 146.3 187.862 0)
			(layer "F.Fab")
			(hide yes)
			(effects
				(font
					(size 1 1)
					(thickness 0.15)
				)
			)
		)
		(property "Tolerance" "1%"
			(at 146.3 187.862 0)
			(layer "F.Fab")
			(hide yes)
			(effects
				(font
					(size 1 1)
					(thickness 0.15)
				)
			)
		)
		(property "Val" "1k"
			(at 146.3 187.862 0)
			(layer "F.Fab")
			(hide yes)
			(effects
				(font
					(size 1 1)
					(thickness 0.15)
				)
			)
		)
		(sheetname "/Power supply/")
		(sheetfile "power-supply.kicad_sch")
		(attr smd)
		(fp_rect
			(start -0.925 -0.47)
			(end 0.925 0.47)
			(stroke
				(width 0.05)
				(type default)
			)
			(fill no)
			(layer "F.CrtYd")
		)
		(fp_rect
			(start -0.5 -0.25)
			(end 0.5 0.25)
			(stroke
				(width 0.15)
				(type solid)
			)
			(fill no)
			(layer "F.Fab")
		)
		(pad "1" smd roundrect
			(at -0.48 0 180)
			(size 0.59 0.64)
			(layers "F.Cu" "F.Mask" "F.Paste")
			(roundrect_rratio 0.25)
			(net 219 "Net-(D7-A)")
			(pintype "passive")
		)
		(pad "2" smd roundrect
			(at 0.48 0 180)
			(size 0.59 0.64)
			(layers "F.Cu" "F.Mask" "F.Paste")
			(roundrect_rratio 0.25)
			(net 2 "VCC3V3")
			(pintype "passive")
		)
	)
	(footprint "antmicro-footprints:R_0402_1005Metric"
		(layer "F.Cu")
		(at 73.15 95.963 180)
		(descr "Resistor SMD 0402")
		(tags "resistor SMD 0402")
		(property "Reference" "R96"
			(at -1.05 0.495 0)
			(layer "F.SilkS")
			(effects
				(font
					(size 0.7 0.7)
					(thickness 0.15)
				)
				(justify right bottom)
			)
		)
		(property "Value" "R_1k_0402"
			(at 0 1.4 0)
			(layer "F.Fab")
			(effects
				(font
					(size 0.7 0.7)
					(thickness 0.15)
				)
				(justify right bottom)
			)
		)
		(property "Datasheet" "https://www.bourns.com/docs/product-datasheets/cr.pdf"
			(at 0 0 180)
			(layer "F.Fab")
			(hide yes)
			(effects
				(font
					(size 1.27 1.27)
					(thickness 0.15)
				)
			)
		)
		(property "Description" "SMD Chip Resistor, 1 kohm, ± 1%, 63 mW, 0402 [1005 Metric], Thick Film, General Purpose"
			(at 0 0 180)
			(layer "F.Fab")
			(hide yes)
			(effects
				(font
					(size 1.27 1.27)
					(thickness 0.15)
				)
			)
		)
		(property "Author" "Antmicro"
			(at 146.3 191.926 0)
			(layer "F.Fab")
			(hide yes)
			(effects
				(font
					(size 1 1)
					(thickness 0.15)
				)
			)
		)
		(property "License" "Apache-2.0"
			(at 146.3 191.926 0)
			(layer "F.Fab")
			(hide yes)
			(effects
				(font
					(size 1 1)
					(thickness 0.15)
				)
			)
		)
		(property "MPN" "CR0402-FX-1001GLF"
			(at 146.3 191.926 0)
			(layer "F.Fab")
			(hide yes)
			(effects
				(font
					(size 1 1)
					(thickness 0.15)
				)
			)
		)
		(property "Manufacturer" "Bourns"
			(at 146.3 191.926 0)
			(layer "F.Fab")
			(hide yes)
			(effects
				(font
					(size 1 1)
					(thickness 0.15)
				)
			)
		)
		(property "Tolerance" "1%"
			(at 146.3 191.926 0)
			(layer "F.Fab")
			(hide yes)
			(effects
				(font
					(size 1 1)
					(thickness 0.15)
				)
			)
		)
		(property "Val" "1k"
			(at 146.3 191.926 0)
			(layer "F.Fab")
			(hide yes)
			(effects
				(font
					(size 1 1)
					(thickness 0.15)
				)
			)
		)
		(sheetname "/Power supply/")
		(sheetfile "power-supply.kicad_sch")
		(attr smd)
		(fp_rect
			(start -0.925 -0.47)
			(end 0.925 0.47)
			(stroke
				(width 0.05)
				(type default)
			)
			(fill no)
			(layer "F.CrtYd")
		)
		(fp_rect
			(start -0.5 -0.25)
			(end 0.5 0.25)
			(stroke
				(width 0.15)
				(type solid)
			)
			(fill no)
			(layer "F.Fab")
		)
		(pad "1" smd roundrect
			(at -0.48 0 180)
			(size 0.59 0.64)
			(layers "F.Cu" "F.Mask" "F.Paste")
			(roundrect_rratio 0.25)
			(net 217 "Net-(D6-A)")
			(pintype "passive")
		)
		(pad "2" smd roundrect
			(at 0.48 0 180)
			(size 0.59 0.64)
			(layers "F.Cu" "F.Mask" "F.Paste")
			(roundrect_rratio 0.25)
			(net 2 "VCC3V3")
			(pintype "passive")
		)
	)
	(footprint "antmicro-footprints:R_0402_1005Metric"
		(layer "F.Cu")
		(at 73.15 91.9 180)
		(descr "Resistor SMD 0402")
		(tags "resistor SMD 0402")
		(property "Reference" "R94"
			(at -1.05 0.495 0)
			(layer "F.SilkS")
			(effects
				(font
					(size 0.7 0.7)
					(thickness 0.15)
				)
				(justify right bottom)
			)
		)
		(property "Value" "R_1k_0402"
			(at 0 1.4 0)
			(layer "F.Fab")
			(effects
				(font
					(size 0.7 0.7)
					(thickness 0.15)
				)
				(justify right bottom)
			)
		)
		(property "Datasheet" "https://www.bourns.com/docs/product-datasheets/cr.pdf"
			(at 0 0 180)
			(layer "F.Fab")
			(hide yes)
			(effects
				(font
					(size 1.27 1.27)
					(thickness 0.15)
				)
			)
		)
		(property "Description" "SMD Chip Resistor, 1 kohm, ± 1%, 63 mW, 0402 [1005 Metric], Thick Film, General Purpose"
			(at 0 0 180)
			(layer "F.Fab")
			(hide yes)
			(effects
				(font
					(size 1.27 1.27)
					(thickness 0.15)
				)
			)
		)
		(property "Author" "Antmicro"
			(at 146.3 183.8 0)
			(layer "F.Fab")
			(hide yes)
			(effects
				(font
					(size 1 1)
					(thickness 0.15)
				)
			)
		)
		(property "License" "Apache-2.0"
			(at 146.3 183.8 0)
			(layer "F.Fab")
			(hide yes)
			(effects
				(font
					(size 1 1)
					(thickness 0.15)
				)
			)
		)
		(property "MPN" "CR0402-FX-1001GLF"
			(at 146.3 183.8 0)
			(layer "F.Fab")
			(hide yes)
			(effects
				(font
					(size 1 1)
					(thickness 0.15)
				)
			)
		)
		(property "Manufacturer" "Bourns"
			(at 146.3 183.8 0)
			(layer "F.Fab")
			(hide yes)
			(effects
				(font
					(size 1 1)
					(thickness 0.15)
				)
			)
		)
		(property "Tolerance" "1%"
			(at 146.3 183.8 0)
			(layer "F.Fab")
			(hide yes)
			(effects
				(font
					(size 1 1)
					(thickness 0.15)
				)
			)
		)
		(property "Val" "1k"
			(at 146.3 183.8 0)
			(layer "F.Fab")
			(hide yes)
			(effects
				(font
					(size 1 1)
					(thickness 0.15)
				)
			)
		)
		(sheetname "/Power supply/")
		(sheetfile "power-supply.kicad_sch")
		(attr smd)
		(fp_rect
			(start -0.925 -0.47)
			(end 0.925 0.47)
			(stroke
				(width 0.05)
				(type default)
			)
			(fill no)
			(layer "F.CrtYd")
		)
		(fp_rect
			(start -0.5 -0.25)
			(end 0.5 0.25)
			(stroke
				(width 0.15)
				(type solid)
			)
			(fill no)
			(layer "F.Fab")
		)
		(pad "1" smd roundrect
			(at -0.48 0 180)
			(size 0.59 0.64)
			(layers "F.Cu" "F.Mask" "F.Paste")
			(roundrect_rratio 0.25)
			(net 208 "Net-(D4-A)")
			(pintype "passive")
		)
		(pad "2" smd roundrect
			(at 0.48 0 180)
			(size 0.59 0.64)
			(layers "F.Cu" "F.Mask" "F.Paste")
			(roundrect_rratio 0.25)
			(net 2 "VCC3V3")
			(pintype "passive")
		)
	)
	(footprint "antmicro-footprints:PinHeader_1x3_P2.54mm_Drill1.1mm"
		(layer "F.Cu")
		(at 144.565 107.186 -90)
		(property "Reference" "J13"
			(at -1.6 -1.8 270)
			(layer "F.SilkS")
			(effects
				(font
					(size 0.7 0.7)
					(thickness 0.15)
				)
				(justify left bottom)
			)
		)
		(property "Value" "PinHeader_1x3_P2.54mm_Drill1.1mm"
			(at -1.6 2.7 270)
			(layer "F.Fab")
			(effects
				(font
					(size 0.7 0.7)
					(thickness 0.15)
				)
				(justify left bottom)
			)
		)
		(property "Datasheet" "https://katalog.we-online.de/em/datasheet/6130xx11121.pdf"
			(at 0 0 270)
			(layer "F.Fab")
			(hide yes)
			(effects
				(font
					(size 1.27 1.27)
					(thickness 0.15)
				)
			)
		)
		(property "Description" "Pin Header, Vertical, Board-to-Board, 2.54 mm, 1 Rows, 3 Contacts, Through Hole Straight, WR-PHD"
			(at 0 0 270)
			(layer "F.Fab")
			(hide yes)
			(effects
				(font
					(size 1.27 1.27)
					(thickness 0.15)
				)
			)
		)
		(property "Author" "Antmicro"
			(at 37.379 251.751 0)
			(layer "F.Fab")
			(hide yes)
			(effects
				(font
					(size 1 1)
					(thickness 0.15)
				)
			)
		)
		(property "License" "Apache-2.0"
			(at 37.379 251.751 0)
			(layer "F.Fab")
			(hide yes)
			(effects
				(font
					(size 1 1)
					(thickness 0.15)
				)
			)
		)
		(property "MPN" "61300311121"
			(at 37.379 251.751 0)
			(layer "F.Fab")
			(hide yes)
			(effects
				(font
					(size 1 1)
					(thickness 0.15)
				)
			)
		)
		(property "Manufacturer" "Würth Elektronik"
			(at 37.379 251.751 0)
			(layer "F.Fab")
			(hide yes)
			(effects
				(font
					(size 1 1)
					(thickness 0.15)
				)
			)
		)
		(property "VSD_class" "IO Header"
			(at 37.379 251.751 0)
			(layer "F.Fab")
			(hide yes)
			(effects
				(font
					(size 1 1)
					(thickness 0.15)
				)
			)
		)
		(sheetname "/FPGA banks 34-35 & CFG/")
		(sheetfile "fpga-banks-34-25-cfg.kicad_sch")
		(attr through_hole)
		(fp_line
			(start -1.401 1.398)
			(end -0.902 1.398)
			(stroke
				(width 0.15)
				(type solid)
			)
			(layer "F.SilkS")
		)
		(fp_line
			(start -1.401 1.398)
			(end -1.401 0.9)
			(stroke
				(width 0.15)
				(type solid)
			)
			(layer "F.SilkS")
		)
		(fp_line
			(start 6.499 1.398)
			(end 5.999 1.398)
			(stroke
				(width 0.15)
				(type solid)
			)
			(layer "F.SilkS")
		)
		(fp_line
			(start 6.499 1.398)
			(end 6.499 0.9)
			(stroke
				(width 0.15)
				(type solid)
			)
			(layer "F.SilkS")
		)
		(fp_line
			(start -1.401 -1.401)
			(end -1.401 -0.902)
			(stroke
				(width 0.15)
				(type solid)
			)
			(layer "F.SilkS")
		)
		(fp_line
			(start -1.401 -1.401)
			(end -0.902 -1.401)
			(stroke
				(width 0.15)
				(type solid)
			)
			(layer "F.SilkS")
		)
		(fp_line
			(start 6.499 -1.401)
			(end 6.499 -0.902)
			(stroke
				(width 0.15)
				(type solid)
			)
			(layer "F.SilkS")
		)
		(fp_line
			(start 6.499 -1.401)
			(end 5.999 -1.401)
			(stroke
				(width 0.15)
				(type solid)
			)
			(layer "F.SilkS")
		)
		(fp_line
			(start -1.52 1.5)
			(end 6.58 1.5)
			(stroke
				(width 0.05)
				(type solid)
			)
			(layer "F.CrtYd")
		)
		(fp_line
			(start -1.52 -1.52)
			(end -1.52 1.5)
			(stroke
				(width 0.05)
				(type solid)
			)
			(layer "F.CrtYd")
		)
		(fp_line
			(start -1.52 -1.52)
			(end 6.58 -1.52)
			(stroke
				(width 0.05)
				(type solid)
			)
			(layer "F.CrtYd")
		)
		(fp_line
			(start 6.58 -1.52)
			(end 6.58 1.5)
			(stroke
				(width 0.05)
				(type solid)
			)
			(layer "F.CrtYd")
		)
		(fp_line
			(start -1.27 1.269)
			(end 6.349 1.269)
			(stroke
				(width 0.15)
				(type solid)
			)
			(layer "F.Fab")
		)
		(fp_line
			(start -1.27 -1.27)
			(end -1.27 1.269)
			(stroke
				(width 0.15)
				(type solid)
			)
			(layer "F.Fab")
		)
		(fp_line
			(start -1.27 -1.27)
			(end 6.349 -1.27)
			(stroke
				(width 0.15)
				(type solid)
			)
			(layer "F.Fab")
		)
		(fp_line
			(start 6.349 -1.27)
			(end 6.349 1.269)
			(stroke
				(width 0.15)
				(type solid)
			)
			(layer "F.Fab")
		)
		(pad "1" thru_hole rect
			(at 0 0 270)
			(size 1.7 1.7)
			(drill 1.1)
			(layers "*.Cu" "*.Mask")
			(remove_unused_layers no)
			(net 2 "VCC3V3")
			(pintype "passive")
		)
		(pad "2" thru_hole circle
			(at 2.539 0 270)
			(size 1.7 1.7)
			(drill 1.1)
			(layers "*.Cu" "*.Mask")
			(remove_unused_layers no)
			(net 259 "/FPGA banks 34-35 & CFG/MODE2")
			(pintype "passive")
		)
		(pad "3" thru_hole circle
			(at 5.078 0 270)
			(size 1.7 1.7)
			(drill 1.1)
			(layers "*.Cu" "*.Mask")
			(remove_unused_layers no)
			(net 1 "GND")
			(pintype "passive")
		)
	)
	(footprint "antmicro-footprints:R_0402_1005Metric"
		(layer "F.Cu")
		(at 138.625 107.06 -90)
		(descr "Resistor SMD 0402")
		(tags "resistor SMD 0402")
		(property "Reference" "R81"
			(at 0.84 -0.375 90)
			(layer "F.SilkS")
			(effects
				(font
					(size 0.7 0.7)
					(thickness 0.15)
				)
				(justify right bottom)
			)
		)
		(property "Value" "R_0R_0402"
			(at 0 1.4 90)
			(layer "F.Fab")
			(effects
				(font
					(size 0.7 0.7)
					(thickness 0.15)
				)
				(justify right bottom)
			)
		)
		(property "Datasheet" "https://industrial.panasonic.com/cdbs/www-data/pdf/RDA0000/AOA0000C301.pdf"
			(at 0 0 270)
			(layer "F.Fab")
			(hide yes)
			(effects
				(font
					(size 1.27 1.27)
					(thickness 0.15)
				)
			)
		)
		(property "Description" "SMD Chip Resistor, Jumper, 0 ohm, 100 mW, 0402 [1005 Metric], Thick Film, General Purpose"
			(at 0 0 270)
			(layer "F.Fab")
			(hide yes)
			(effects
				(font
					(size 1.27 1.27)
					(thickness 0.15)
				)
			)
		)
		(property "Author" "Antmicro"
			(at 31.565 245.685 0)
			(layer "F.Fab")
			(hide yes)
			(effects
				(font
					(size 1 1)
					(thickness 0.15)
				)
			)
		)
		(property "Current" "1A"
			(at 31.565 245.685 0)
			(layer "F.Fab")
			(hide yes)
			(effects
				(font
					(size 1 1)
					(thickness 0.15)
				)
			)
		)
		(property "License" "Apache-2.0"
			(at 31.565 245.685 0)
			(layer "F.Fab")
			(hide yes)
			(effects
				(font
					(size 1 1)
					(thickness 0.15)
				)
			)
		)
		(property "MPN" "ERJ2GE0R00X"
			(at 31.565 245.685 0)
			(layer "F.Fab")
			(hide yes)
			(effects
				(font
					(size 1 1)
					(thickness 0.15)
				)
			)
		)
		(property "Manufacturer" "Panasonic"
			(at 31.565 245.685 0)
			(layer "F.Fab")
			(hide yes)
			(effects
				(font
					(size 1 1)
					(thickness 0.15)
				)
			)
		)
		(property "Tolerance" "~"
			(at 31.565 245.685 0)
			(layer "F.Fab")
			(hide yes)
			(effects
				(font
					(size 1 1)
					(thickness 0.15)
				)
			)
		)
		(property "Val" "0R"
			(at 31.565 245.685 0)
			(layer "F.Fab")
			(hide yes)
			(effects
				(font
					(size 1 1)
					(thickness 0.15)
				)
			)
		)
		(sheetname "/FPGA banks 34-35 & CFG/")
		(sheetfile "fpga-banks-34-25-cfg.kicad_sch")
		(attr smd)
		(fp_rect
			(start -0.925 -0.47)
			(end 0.925 0.47)
			(stroke
				(width 0.05)
				(type default)
			)
			(fill no)
			(layer "F.CrtYd")
		)
		(fp_rect
			(start -0.5 -0.25)
			(end 0.5 0.25)
			(stroke
				(width 0.15)
				(type solid)
			)
			(fill no)
			(layer "F.Fab")
		)
		(pad "1" smd roundrect
			(at -0.48 0 270)
			(size 0.59 0.64)
			(layers "F.Cu" "F.Mask" "F.Paste")
			(roundrect_rratio 0.25)
			(net 2 "VCC3V3")
			(pintype "passive")
		)
		(pad "2" smd roundrect
			(at 0.48 0 270)
			(size 0.59 0.64)
			(layers "F.Cu" "F.Mask" "F.Paste")
			(roundrect_rratio 0.25)
			(net 267 "/FPGA banks 34-35 & CFG/MODE0")
			(pintype "passive")
		)
	)
	(footprint "antmicro-footprints:R_0402_1005Metric"
		(layer "F.Cu")
		(at 137.625 107.06 -90)
		(descr "Resistor SMD 0402")
		(tags "resistor SMD 0402")
		(property "Reference" "R82"
			(at 0.84 -0.375 90)
			(layer "F.SilkS")
			(effects
				(font
					(size 0.7 0.7)
					(thickness 0.15)
				)
				(justify right bottom)
			)
		)
		(property "Value" "R_0R_0402"
			(at 0 1.4 90)
			(layer "F.Fab")
			(effects
				(font
					(size 0.7 0.7)
					(thickness 0.15)
				)
				(justify right bottom)
			)
		)
		(property "Datasheet" "https://industrial.panasonic.com/cdbs/www-data/pdf/RDA0000/AOA0000C301.pdf"
			(at 0 0 270)
			(layer "F.Fab")
			(hide yes)
			(effects
				(font
					(size 1.27 1.27)
					(thickness 0.15)
				)
			)
		)
		(property "Description" "SMD Chip Resistor, Jumper, 0 ohm, 100 mW, 0402 [1005 Metric], Thick Film, General Purpose"
			(at 0 0 270)
			(layer "F.Fab")
			(hide yes)
			(effects
				(font
					(size 1.27 1.27)
					(thickness 0.15)
				)
			)
		)
		(property "Author" "Antmicro"
			(at 30.565 244.685 0)
			(layer "F.Fab")
			(hide yes)
			(effects
				(font
					(size 1 1)
					(thickness 0.15)
				)
			)
		)
		(property "Current" "1A"
			(at 30.565 244.685 0)
			(layer "F.Fab")
			(hide yes)
			(effects
				(font
					(size 1 1)
					(thickness 0.15)
				)
			)
		)
		(property "License" "Apache-2.0"
			(at 30.565 244.685 0)
			(layer "F.Fab")
			(hide yes)
			(effects
				(font
					(size 1 1)
					(thickness 0.15)
				)
			)
		)
		(property "MPN" "ERJ2GE0R00X"
			(at 30.565 244.685 0)
			(layer "F.Fab")
			(hide yes)
			(effects
				(font
					(size 1 1)
					(thickness 0.15)
				)
			)
		)
		(property "Manufacturer" "Panasonic"
			(at 30.565 244.685 0)
			(layer "F.Fab")
			(hide yes)
			(effects
				(font
					(size 1 1)
					(thickness 0.15)
				)
			)
		)
		(property "Tolerance" "~"
			(at 30.565 244.685 0)
			(layer "F.Fab")
			(hide yes)
			(effects
				(font
					(size 1 1)
					(thickness 0.15)
				)
			)
		)
		(property "Val" "0R"
			(at 30.565 244.685 0)
			(layer "F.Fab")
			(hide yes)
			(effects
				(font
					(size 1 1)
					(thickness 0.15)
				)
			)
		)
		(sheetname "/FPGA banks 34-35 & CFG/")
		(sheetfile "fpga-banks-34-25-cfg.kicad_sch")
		(attr smd exclude_from_pos_files exclude_from_bom dnp)
		(fp_rect
			(start -0.925 -0.47)
			(end 0.925 0.47)
			(stroke
				(width 0.05)
				(type default)
			)
			(fill no)
			(layer "F.CrtYd")
		)
		(fp_rect
			(start -0.5 -0.25)
			(end 0.5 0.25)
			(stroke
				(width 0.15)
				(type solid)
			)
			(fill no)
			(layer "F.Fab")
		)
		(pad "1" smd roundrect
			(at -0.48 0 270)
			(size 0.59 0.64)
			(layers "F.Cu" "F.Mask" "F.Paste")
			(roundrect_rratio 0.25)
			(net 1 "GND")
			(pintype "passive")
		)
		(pad "2" smd roundrect
			(at 0.48 0 270)
			(size 0.59 0.64)
			(layers "F.Cu" "F.Mask" "F.Paste")
			(roundrect_rratio 0.25)
			(net 267 "/FPGA banks 34-35 & CFG/MODE0")
			(pintype "passive")
		)
	)
	(footprint "antmicro-footprints:R_0402_1005Metric"
		(layer "F.Cu")
		(at 139.625 107.06 -90)
		(descr "Resistor SMD 0402")
		(tags "resistor SMD 0402")
		(property "Reference" "R83"
			(at 0.84 -0.375 90)
			(layer "F.SilkS")
			(effects
				(font
					(size 0.7 0.7)
					(thickness 0.15)
				)
				(justify right bottom)
			)
		)
		(property "Value" "R_0R_0402"
			(at 0 1.4 90)
			(layer "F.Fab")
			(effects
				(font
					(size 0.7 0.7)
					(thickness 0.15)
				)
				(justify right bottom)
			)
		)
		(property "Datasheet" "https://industrial.panasonic.com/cdbs/www-data/pdf/RDA0000/AOA0000C301.pdf"
			(at 0 0 270)
			(layer "F.Fab")
			(hide yes)
			(effects
				(font
					(size 1.27 1.27)
					(thickness 0.15)
				)
			)
		)
		(property "Description" "SMD Chip Resistor, Jumper, 0 ohm, 100 mW, 0402 [1005 Metric], Thick Film, General Purpose"
			(at 0 0 270)
			(layer "F.Fab")
			(hide yes)
			(effects
				(font
					(size 1.27 1.27)
					(thickness 0.15)
				)
			)
		)
		(property "Author" "Antmicro"
			(at 32.565 246.685 0)
			(layer "F.Fab")
			(hide yes)
			(effects
				(font
					(size 1 1)
					(thickness 0.15)
				)
			)
		)
		(property "Current" "1A"
			(at 32.565 246.685 0)
			(layer "F.Fab")
			(hide yes)
			(effects
				(font
					(size 1 1)
					(thickness 0.15)
				)
			)
		)
		(property "License" "Apache-2.0"
			(at 32.565 246.685 0)
			(layer "F.Fab")
			(hide yes)
			(effects
				(font
					(size 1 1)
					(thickness 0.15)
				)
			)
		)
		(property "MPN" "ERJ2GE0R00X"
			(at 32.565 246.685 0)
			(layer "F.Fab")
			(hide yes)
			(effects
				(font
					(size 1 1)
					(thickness 0.15)
				)
			)
		)
		(property "Manufacturer" "Panasonic"
			(at 32.565 246.685 0)
			(layer "F.Fab")
			(hide yes)
			(effects
				(font
					(size 1 1)
					(thickness 0.15)
				)
			)
		)
		(property "Tolerance" "~"
			(at 32.565 246.685 0)
			(layer "F.Fab")
			(hide yes)
			(effects
				(font
					(size 1 1)
					(thickness 0.15)
				)
			)
		)
		(property "Val" "0R"
			(at 32.565 246.685 0)
			(layer "F.Fab")
			(hide yes)
			(effects
				(font
					(size 1 1)
					(thickness 0.15)
				)
			)
		)
		(sheetname "/FPGA banks 34-35 & CFG/")
		(sheetfile "fpga-banks-34-25-cfg.kicad_sch")
		(attr smd exclude_from_pos_files exclude_from_bom dnp)
		(fp_rect
			(start -0.925 -0.47)
			(end 0.925 0.47)
			(stroke
				(width 0.05)
				(type default)
			)
			(fill no)
			(layer "F.CrtYd")
		)
		(fp_rect
			(start -0.5 -0.25)
			(end 0.5 0.25)
			(stroke
				(width 0.15)
				(type solid)
			)
			(fill no)
			(layer "F.Fab")
		)
		(pad "1" smd roundrect
			(at -0.48 0 270)
			(size 0.59 0.64)
			(layers "F.Cu" "F.Mask" "F.Paste")
			(roundrect_rratio 0.25)
			(net 2 "VCC3V3")
			(pintype "passive")
		)
		(pad "2" smd roundrect
			(at 0.48 0 270)
			(size 0.59 0.64)
			(layers "F.Cu" "F.Mask" "F.Paste")
			(roundrect_rratio 0.25)
			(net 268 "/FPGA banks 34-35 & CFG/MODE1")
			(pintype "passive")
		)
	)
	(footprint "antmicro-footprints:R_0402_1005Metric"
		(layer "F.Cu")
		(at 140.625 107.06 -90)
		(descr "Resistor SMD 0402")
		(tags "resistor SMD 0402")
		(property "Reference" "R84"
			(at 0.84 -0.375 90)
			(layer "F.SilkS")
			(effects
				(font
					(size 0.7 0.7)
					(thickness 0.15)
				)
				(justify right bottom)
			)
		)
		(property "Value" "R_0R_0402"
			(at 0 1.4 90)
			(layer "F.Fab")
			(effects
				(font
					(size 0.7 0.7)
					(thickness 0.15)
				)
				(justify right bottom)
			)
		)
		(property "Datasheet" "https://industrial.panasonic.com/cdbs/www-data/pdf/RDA0000/AOA0000C301.pdf"
			(at 0 0 270)
			(layer "F.Fab")
			(hide yes)
			(effects
				(font
					(size 1.27 1.27)
					(thickness 0.15)
				)
			)
		)
		(property "Description" "SMD Chip Resistor, Jumper, 0 ohm, 100 mW, 0402 [1005 Metric], Thick Film, General Purpose"
			(at 0 0 270)
			(layer "F.Fab")
			(hide yes)
			(effects
				(font
					(size 1.27 1.27)
					(thickness 0.15)
				)
			)
		)
		(property "Author" "Antmicro"
			(at 33.565 247.685 0)
			(layer "F.Fab")
			(hide yes)
			(effects
				(font
					(size 1 1)
					(thickness 0.15)
				)
			)
		)
		(property "Current" "1A"
			(at 33.565 247.685 0)
			(layer "F.Fab")
			(hide yes)
			(effects
				(font
					(size 1 1)
					(thickness 0.15)
				)
			)
		)
		(property "License" "Apache-2.0"
			(at 33.565 247.685 0)
			(layer "F.Fab")
			(hide yes)
			(effects
				(font
					(size 1 1)
					(thickness 0.15)
				)
			)
		)
		(property "MPN" "ERJ2GE0R00X"
			(at 33.565 247.685 0)
			(layer "F.Fab")
			(hide yes)
			(effects
				(font
					(size 1 1)
					(thickness 0.15)
				)
			)
		)
		(property "Manufacturer" "Panasonic"
			(at 33.565 247.685 0)
			(layer "F.Fab")
			(hide yes)
			(effects
				(font
					(size 1 1)
					(thickness 0.15)
				)
			)
		)
		(property "Tolerance" "~"
			(at 33.565 247.685 0)
			(layer "F.Fab")
			(hide yes)
			(effects
				(font
					(size 1 1)
					(thickness 0.15)
				)
			)
		)
		(property "Val" "0R"
			(at 33.565 247.685 0)
			(layer "F.Fab")
			(hide yes)
			(effects
				(font
					(size 1 1)
					(thickness 0.15)
				)
			)
		)
		(property "DNP" ""
			(at 0 0 270)
			(unlocked yes)
			(layer "F.Fab")
			(hide yes)
			(effects
				(font
					(size 1 1)
					(thickness 0.15)
				)
			)
		)
		(sheetname "/FPGA banks 34-35 & CFG/")
		(sheetfile "fpga-banks-34-25-cfg.kicad_sch")
		(attr smd)
		(fp_rect
			(start -0.925 -0.47)
			(end 0.925 0.47)
			(stroke
				(width 0.05)
				(type default)
			)
			(fill no)
			(layer "F.CrtYd")
		)
		(fp_rect
			(start -0.5 -0.25)
			(end 0.5 0.25)
			(stroke
				(width 0.15)
				(type solid)
			)
			(fill no)
			(layer "F.Fab")
		)
		(pad "1" smd roundrect
			(at -0.48 0 270)
			(size 0.59 0.64)
			(layers "F.Cu" "F.Mask" "F.Paste")
			(roundrect_rratio 0.25)
			(net 1 "GND")
			(pintype "passive")
		)
		(pad "2" smd roundrect
			(at 0.48 0 270)
			(size 0.59 0.64)
			(layers "F.Cu" "F.Mask" "F.Paste")
			(roundrect_rratio 0.25)
			(net 268 "/FPGA banks 34-35 & CFG/MODE1")
			(pintype "passive")
		)
	)
	(footprint "antmicro-footprints:SW_KMR211NGLFS_SMD"
		(layer "F.Cu")
		(at 65.025 92.385 -90)
		(property "Reference" "PROG_B1"
			(at -2.385 2.025 90)
			(layer "F.SilkS")
			(effects
				(font
					(size 0.7 0.7)
					(thickness 0.15)
				)
				(justify right bottom)
			)
		)
		(property "Value" "SW_KMR211NGLFS_SMD"
			(at -3 3 90)
			(layer "F.Fab")
			(effects
				(font
					(size 0.7 0.7)
					(thickness 0.15)
				)
				(justify right bottom)
			)
		)
		(property "Datasheet" "http://www.farnell.com/datasheets/2631211.pdf"
			(at 0 0 270)
			(layer "F.Fab")
			(hide yes)
			(effects
				(font
					(size 1.27 1.27)
					(thickness 0.15)
				)
			)
		)
		(property "Description" "Tactile Switch, KMR 2 Series, Top Actuated, Surface Mount, Oval Button, 120 gf, 50mA at 32VDC"
			(at 0 0 270)
			(layer "F.Fab")
			(hide yes)
			(effects
				(font
					(size 1.27 1.27)
					(thickness 0.15)
				)
			)
		)
		(property "Author" "Antmicro"
			(at -27.36 157.41 0)
			(layer "F.Fab")
			(hide yes)
			(effects
				(font
					(size 1 1)
					(thickness 0.15)
				)
			)
		)
		(property "License" "Apache-2.0"
			(at -27.36 157.41 0)
			(layer "F.Fab")
			(hide yes)
			(effects
				(font
					(size 1 1)
					(thickness 0.15)
				)
			)
		)
		(property "MPN" "KMR211NGLFS"
			(at -27.36 157.41 0)
			(layer "F.Fab")
			(hide yes)
			(effects
				(font
					(size 1 1)
					(thickness 0.15)
				)
			)
		)
		(property "Manufacturer" "C&K"
			(at -27.36 157.41 0)
			(layer "F.Fab")
			(hide yes)
			(effects
				(font
					(size 1 1)
					(thickness 0.15)
				)
			)
		)
		(sheetname "/FPGA banks 34-35 & CFG/")
		(sheetfile "fpga-banks-34-25-cfg.kicad_sch")
		(attr smd)
		(fp_line
			(start -2.1 1.601)
			(end -2.1 1.48)
			(stroke
				(width 0.15)
				(type solid)
			)
			(layer "F.SilkS")
		)
		(fp_line
			(start 2.101 1.601)
			(end -2.1 1.601)
			(stroke
				(width 0.15)
				(type solid)
			)
			(layer "F.SilkS")
		)
		(fp_line
			(start 2.101 1.601)
			(end 2.101 1.48)
			(stroke
				(width 0.15)
				(type solid)
			)
			(layer "F.SilkS")
		)
		(fp_line
			(start 2.101 -1.58)
			(end 2.101 -1.459)
			(stroke
				(width 0.15)
				(type solid)
			)
			(layer "F.SilkS")
		)
		(fp_line
			(start -2.1 -1.6)
			(end -2.1 -1.499)
			(stroke
				(width 0.15)
				(type solid)
			)
			(layer "F.SilkS")
		)
		(fp_line
			(start 2.101 -1.6)
			(end -2.1 -1.6)
			(stroke
				(width 0.15)
				(type solid)
			)
			(layer "F.SilkS")
		)
		(fp_rect
			(start 2.751 1.75)
			(end -2.748 -1.749)
			(stroke
				(width 0.05)
				(type solid)
			)
			(fill no)
			(layer "F.CrtYd")
		)
		(fp_line
			(start -2.1 1.601)
			(end 2.101 1.601)
			(stroke
				(width 0.15)
				(type solid)
			)
			(layer "F.Fab")
		)
		(fp_line
			(start 2.101 1.601)
			(end 2.101 -1.6)
			(stroke
				(width 0.15)
				(type solid)
			)
			(layer "F.Fab")
		)
		(fp_line
			(start 0.25 0.802)
			(end -0.248 0.802)
			(stroke
				(width 0.15)
				(type solid)
			)
			(layer "F.Fab")
		)
		(fp_line
			(start -0.248 -0.8)
			(end 0.25 -0.8)
			(stroke
				(width 0.15)
				(type solid)
			)
			(layer "F.Fab")
		)
		(fp_line
			(start -2.1 -1.6)
			(end -2.1 1.601)
			(stroke
				(width 0.15)
				(type solid)
			)
			(layer "F.Fab")
		)
		(fp_line
			(start 2.101 -1.6)
			(end -2.1 -1.6)
			(stroke
				(width 0.15)
				(type solid)
			)
			(layer "F.Fab")
		)
		(fp_arc
			(start -0.248 0.802)
			(mid -1.050001 0.001)
			(end -0.248 -0.8)
			(stroke
				(width 0.15)
				(type solid)
			)
			(layer "F.Fab")
		)
		(fp_arc
			(start 0.25 -0.8)
			(mid 1.051001 0.001)
			(end 0.25 0.802)
			(stroke
				(width 0.15)
				(type solid)
			)
			(layer "F.Fab")
		)
		(pad "1" smd rect
			(at -2.048 -0.8 90)
			(size 0.9 1)
			(layers "F.Cu" "F.Mask" "F.Paste")
			(net 221 "PROGRAM")
			(pinfunction "1")
			(pintype "passive")
		)
		(pad "2" smd rect
			(at 2.05 -0.8 90)
			(size 0.9 1)
			(layers "F.Cu" "F.Mask" "F.Paste")
			(net 221 "PROGRAM")
			(pinfunction "2")
			(pintype "passive")
		)
		(pad "3" smd rect
			(at -2.048 0.802 90)
			(size 0.9 1)
			(layers "F.Cu" "F.Mask" "F.Paste")
			(net 1 "GND")
			(pinfunction "3")
			(pintype "passive")
		)
		(pad "4" smd rect
			(at 2.05 0.802 90)
			(size 0.9 1)
			(layers "F.Cu" "F.Mask" "F.Paste")
			(net 1 "GND")
			(pinfunction "4")
			(pintype "passive")
		)
	)
	(footprint "antmicro-footprints:C_0402_1005Metric"
		(layer "F.Cu")
		(at 99.375 159.775 90)
		(descr "Capacitor SMD 0402")
		(tags "capacitor SMD 0402")
		(property "Reference" "C46"
			(at -1.2 -1.6 90)
			(layer "F.SilkS")
			(effects
				(font
					(size 0.7 0.7)
					(thickness 0.15)
				)
				(justify left bottom)
			)
		)
		(property "Value" "C_100n_6V3_0402"
			(at 0 1.4 90)
			(layer "F.Fab")
			(effects
				(font
					(size 0.7 0.7)
					(thickness 0.15)
				)
				(justify left bottom)
			)
		)
		(property "Datasheet" "https://www.passivecomponent.com/wp-content/uploads/datasheet/WTC_MLCC_General_Purpose.pdf"
			(at 0 0 90)
			(layer "F.Fab")
			(hide yes)
			(effects
				(font
					(size 1.27 1.27)
					(thickness 0.15)
				)
			)
		)
		(property "Description" "SMT Multilayer Ceramic Capacitor, 0.1 µF, 6.3 V, 0402 [1005 Metric], ± 10%, X5R, Walsin MLCC"
			(at 0 0 90)
			(layer "F.Fab")
			(hide yes)
			(effects
				(font
					(size 1.27 1.27)
					(thickness 0.15)
				)
			)
		)
		(property "Author" "Antmicro"
			(at 259.15 60.4 0)
			(layer "F.Fab")
			(hide yes)
			(effects
				(font
					(size 1 1)
					(thickness 0.15)
				)
			)
		)
		(property "Dielectric" ""
			(at 259.15 60.4 0)
			(layer "F.Fab")
			(hide yes)
			(effects
				(font
					(size 1 1)
					(thickness 0.15)
				)
			)
		)
		(property "License" "Apache-2.0"
			(at 259.15 60.4 0)
			(layer "F.Fab")
			(hide yes)
			(effects
				(font
					(size 1 1)
					(thickness 0.15)
				)
			)
		)
		(property "MPN" "0402X104K6R3CT"
			(at 259.15 60.4 0)
			(layer "F.Fab")
			(hide yes)
			(effects
				(font
					(size 1 1)
					(thickness 0.15)
				)
			)
		)
		(property "Manufacturer" "Walsin"
			(at 259.15 60.4 0)
			(layer "F.Fab")
			(hide yes)
			(effects
				(font
					(size 1 1)
					(thickness 0.15)
				)
			)
		)
		(property "Public" "False"
			(at 259.15 60.4 0)
			(layer "F.Fab")
			(hide yes)
			(effects
				(font
					(size 1 1)
					(thickness 0.15)
				)
			)
		)
		(property "Val" "100n"
			(at 259.15 60.4 0)
			(layer "F.Fab")
			(hide yes)
			(effects
				(font
					(size 1 1)
					(thickness 0.15)
				)
			)
		)
		(property "Voltage" ""
			(at 259.15 60.4 0)
			(layer "F.Fab")
			(hide yes)
			(effects
				(font
					(size 1 1)
					(thickness 0.15)
				)
			)
		)
		(sheetname "/DDR3/")
		(sheetfile "ddr3.kicad_sch")
		(attr smd)
		(fp_rect
			(start -0.925 -0.47)
			(end 0.925 0.47)
			(stroke
				(width 0.05)
				(type default)
			)
			(fill no)
			(layer "F.CrtYd")
		)
		(fp_line
			(start 0.504 -0.25)
			(end 0.504 0.248)
			(stroke
				(width 0.15)
				(type solid)
			)
			(layer "F.Fab")
		)
		(fp_line
			(start -0.494 -0.25)
			(end 0.504 -0.25)
			(stroke
				(width 0.15)
				(type solid)
			)
			(layer "F.Fab")
		)
		(fp_line
			(start 0.504 0.248)
			(end -0.494 0.248)
			(stroke
				(width 0.15)
				(type solid)
			)
			(layer "F.Fab")
		)
		(fp_line
			(start -0.494 0.248)
			(end -0.494 -0.25)
			(stroke
				(width 0.15)
				(type solid)
			)
			(layer "F.Fab")
		)
		(pad "1" smd roundrect
			(at -0.48 0 90)
			(size 0.59 0.64)
			(layers "F.Cu" "F.Mask" "F.Paste")
			(roundrect_rratio 0.25)
			(net 1 "GND")
			(pintype "passive")
		)
		(pad "2" smd roundrect
			(at 0.48 0 90)
			(size 0.59 0.64)
			(layers "F.Cu" "F.Mask" "F.Paste")
			(roundrect_rratio 0.25)
			(net 3 "VCC1V35")
			(pintype "passive")
		)
	)
	(footprint "antmicro-footprints:C_Pol_EIA-D"
		(layer "F.Cu")
		(at 74.075 80.075 180)
		(property "Reference" "C150"
			(at 3.65 1.875 0)
			(layer "F.SilkS")
			(effects
				(font
					(size 0.7 0.7)
					(thickness 0.15)
				)
				(justify right bottom)
			)
		)
		(property "Value" "C_Pol_330u_6.3V_KEMET-T520-D"
			(at 0 3.6 0)
			(layer "F.Fab")
			(effects
				(font
					(size 0.7 0.7)
					(thickness 0.15)
				)
				(justify right bottom)
			)
		)
		(property "Datasheet" "https://www.kemet.com/en/us/capacitors/product/T520D337M006ATE045.html"
			(at 0 0 180)
			(layer "F.Fab")
			(hide yes)
			(effects
				(font
					(size 1.27 1.27)
					(thickness 0.15)
				)
			)
		)
		(property "Description" "Tantalum Polymer Capacitor, KO-CAP®, 330 µF, ± 20%, 6.3 V, D, 0.045 ohm, 2917 [7343 Metric]"
			(at 0 0 180)
			(layer "F.Fab")
			(hide yes)
			(effects
				(font
					(size 1.27 1.27)
					(thickness 0.15)
				)
			)
		)
		(property "Author" "Antmicro"
			(at 148.15 160.15 0)
			(layer "F.Fab")
			(hide yes)
			(effects
				(font
					(size 1 1)
					(thickness 0.15)
				)
			)
		)
		(property "Dielectric" "template_dielectric"
			(at 148.15 160.15 0)
			(layer "F.Fab")
			(hide yes)
			(effects
				(font
					(size 1 1)
					(thickness 0.15)
				)
			)
		)
		(property "License" "Apache-2.0"
			(at 148.15 160.15 0)
			(layer "F.Fab")
			(hide yes)
			(effects
				(font
					(size 1 1)
					(thickness 0.15)
				)
			)
		)
		(property "MPN" "T520D337M006ATE045"
			(at 148.15 160.15 0)
			(layer "F.Fab")
			(hide yes)
			(effects
				(font
					(size 1 1)
					(thickness 0.15)
				)
			)
		)
		(property "Manufacturer" "KEMET"
			(at 148.15 160.15 0)
			(layer "F.Fab")
			(hide yes)
			(effects
				(font
					(size 1 1)
					(thickness 0.15)
				)
			)
		)
		(property "Val" "330u"
			(at 148.15 160.15 0)
			(layer "F.Fab")
			(hide yes)
			(effects
				(font
					(size 1 1)
					(thickness 0.15)
				)
			)
		)
		(property "Voltage" "6.3V"
			(at 148.15 160.15 0)
			(layer "F.Fab")
			(hide yes)
			(effects
				(font
					(size 1 1)
					(thickness 0.15)
				)
			)
		)
		(property "DNP" ""
			(at 0 0 180)
			(unlocked yes)
			(layer "F.Fab")
			(hide yes)
			(effects
				(font
					(size 1 1)
					(thickness 0.15)
				)
			)
		)
		(sheetname "/FPGA power supply/")
		(sheetfile "fpga-power-supply.kicad_sch")
		(attr smd)
		(fp_line
			(start 3.6 2.2)
			(end -3.58 2.2)
			(stroke
				(width 0.15)
				(type solid)
			)
			(layer "F.SilkS")
		)
		(fp_line
			(start 3.6 1.6)
			(end 3.6 2.2)
			(stroke
				(width 0.15)
				(type solid)
			)
			(layer "F.SilkS")
		)
		(fp_line
			(start 3.6 -2.2)
			(end 3.6 -1.6)
			(stroke
				(width 0.15)
				(type solid)
			)
			(layer "F.SilkS")
		)
		(fp_line
			(start -3.58 2.2)
			(end -3.58 1.6)
			(stroke
				(width 0.15)
				(type solid)
			)
			(layer "F.SilkS")
		)
		(fp_line
			(start -3.58 -1.6)
			(end -3.58 -2.2)
			(stroke
				(width 0.15)
				(type solid)
			)
			(layer "F.SilkS")
		)
		(fp_line
			(start -3.58 -2.2)
			(end 3.6 -2.2)
			(stroke
				(width 0.15)
				(type solid)
			)
			(layer "F.SilkS")
		)
		(fp_line
			(start -4.1 -2.025)
			(end -4.1 -1.625)
			(stroke
				(width 0.12)
				(type solid)
			)
			(layer "F.SilkS")
		)
		(fp_line
			(start -4.3 -1.825)
			(end -3.9 -1.825)
			(stroke
				(width 0.12)
				(type solid)
			)
			(layer "F.SilkS")
		)
		(fp_line
			(start 4.505 1.51)
			(end 3.77 1.51)
			(stroke
				(width 0.05)
				(type solid)
			)
			(layer "F.CrtYd")
		)
		(fp_line
			(start 4.505 -1.51)
			(end 4.505 1.5)
			(stroke
				(width 0.05)
				(type solid)
			)
			(layer "F.CrtYd")
		)
		(fp_line
			(start 3.77 2.4)
			(end -3.77 2.4)
			(stroke
				(width 0.05)
				(type solid)
			)
			(layer "F.CrtYd")
		)
		(fp_line
			(start 3.77 1.51)
			(end 3.77 2.4)
			(stroke
				(width 0.05)
				(type solid)
			)
			(layer "F.CrtYd")
		)
		(fp_line
			(start 3.77 -1.51)
			(end 4.505 -1.51)
			(stroke
				(width 0.05)
				(type solid)
			)
			(layer "F.CrtYd")
		)
		(fp_line
			(start 3.77 -2.4)
			(end 3.77 -1.51)
			(stroke
				(width 0.05)
				(type solid)
			)
			(layer "F.CrtYd")
		)
		(fp_line
			(start -3.77 2.4)
			(end -3.77 1.51)
			(stroke
				(width 0.05)
				(type solid)
			)
			(layer "F.CrtYd")
		)
		(fp_line
			(start -3.77 1.51)
			(end -4.505 1.51)
			(stroke
				(width 0.05)
				(type solid)
			)
			(layer "F.CrtYd")
		)
		(fp_line
			(start -3.775 -1.5)
			(end -4.505 -1.5)
			(stroke
				(width 0.05)
				(type solid)
			)
			(layer "F.CrtYd")
		)
		(fp_line
			(start -3.775 -2.4)
			(end 3.77 -2.4)
			(stroke
				(width 0.05)
				(type solid)
			)
			(layer "F.CrtYd")
		)
		(fp_line
			(start -3.775 -2.4)
			(end -3.775 -1.5)
			(stroke
				(width 0.05)
				(type solid)
			)
			(layer "F.CrtYd")
		)
		(fp_line
			(start -4.505 1.51)
			(end -4.505 -1.5)
			(stroke
				(width 0.05)
				(type solid)
			)
			(layer "F.CrtYd")
		)
		(fp_rect
			(start -3.65 -2.15)
			(end 3.65 2.15)
			(stroke
				(width 0.15)
				(type solid)
			)
			(fill no)
			(layer "F.Fab")
		)
		(pad "1" smd roundrect
			(at -3.1 0 180)
			(size 2.31 2.52)
			(layers "F.Cu" "F.Mask" "F.Paste")
			(roundrect_rratio 0.1)
			(net 6 "VCC1V0")
			(pintype "passive")
		)
		(pad "2" smd roundrect
			(at 3.1 0 180)
			(size 2.31 2.52)
			(layers "F.Cu" "F.Mask" "F.Paste")
			(roundrect_rratio 0.1)
			(net 1 "GND")
			(pintype "passive")
		)
	)
	(footprint "antmicro-footprints:C_0402_1005Metric"
		(layer "F.Cu")
		(at 85.895 79.425 180)
		(descr "Capacitor SMD 0402")
		(tags "capacitor SMD 0402")
		(property "Reference" "C85"
			(at -5.705 -0.375 0)
			(layer "F.SilkS")
			(effects
				(font
					(size 0.7 0.7)
					(thickness 0.15)
				)
				(justify right bottom)
			)
		)
		(property "Value" "C_10u_0402"
			(at 0 1.4 0)
			(layer "F.Fab")
			(effects
				(font
					(size 0.7 0.7)
					(thickness 0.15)
				)
				(justify right bottom)
			)
		)
		(property "Datasheet" "https://www.yageo.com/en/Chart/Download/pdf/CC0402MRX5R5BB106"
			(at 0 0 180)
			(layer "F.Fab")
			(hide yes)
			(effects
				(font
					(size 1.27 1.27)
					(thickness 0.15)
				)
			)
		)
		(property "Description" "SMD Multilayer Ceramic Capacitor, 10 µF, 6.3 V, 0402 [1005 Metric], ± 20%, X5R, CC Series"
			(at 0 0 180)
			(layer "F.Fab")
			(hide yes)
			(effects
				(font
					(size 1.27 1.27)
					(thickness 0.15)
				)
			)
		)
		(property "Author" "Antmicro"
			(at 171.79 158.85 0)
			(layer "F.Fab")
			(hide yes)
			(effects
				(font
					(size 1 1)
					(thickness 0.15)
				)
			)
		)
		(property "Dielectric" ""
			(at 171.79 158.85 0)
			(layer "F.Fab")
			(hide yes)
			(effects
				(font
					(size 1 1)
					(thickness 0.15)
				)
			)
		)
		(property "License" "Apache-2.0"
			(at 171.79 158.85 0)
			(layer "F.Fab")
			(hide yes)
			(effects
				(font
					(size 1 1)
					(thickness 0.15)
				)
			)
		)
		(property "MPN" "CC0402MRX5R5BB106"
			(at 171.79 158.85 0)
			(layer "F.Fab")
			(hide yes)
			(effects
				(font
					(size 1 1)
					(thickness 0.15)
				)
			)
		)
		(property "Manufacturer" "YAGEO"
			(at 171.79 158.85 0)
			(layer "F.Fab")
			(hide yes)
			(effects
				(font
					(size 1 1)
					(thickness 0.15)
				)
			)
		)
		(property "Val" "10u"
			(at 171.79 158.85 0)
			(layer "F.Fab")
			(hide yes)
			(effects
				(font
					(size 1 1)
					(thickness 0.15)
				)
			)
		)
		(property "Voltage" ""
			(at 171.79 158.85 0)
			(layer "F.Fab")
			(hide yes)
			(effects
				(font
					(size 1 1)
					(thickness 0.15)
				)
			)
		)
		(sheetname "/Power supply/")
		(sheetfile "power-supply.kicad_sch")
		(attr smd)
		(fp_rect
			(start -0.925 -0.47)
			(end 0.925 0.47)
			(stroke
				(width 0.05)
				(type default)
			)
			(fill no)
			(layer "F.CrtYd")
		)
		(fp_line
			(start 0.504 0.248)
			(end -0.494 0.248)
			(stroke
				(width 0.15)
				(type solid)
			)
			(layer "F.Fab")
		)
		(fp_line
			(start 0.504 -0.25)
			(end 0.504 0.248)
			(stroke
				(width 0.15)
				(type solid)
			)
			(layer "F.Fab")
		)
		(fp_line
			(start -0.494 0.248)
			(end -0.494 -0.25)
			(stroke
				(width 0.15)
				(type solid)
			)
			(layer "F.Fab")
		)
		(fp_line
			(start -0.494 -0.25)
			(end 0.504 -0.25)
			(stroke
				(width 0.15)
				(type solid)
			)
			(layer "F.Fab")
		)
		(pad "1" smd roundrect
			(at -0.48 0 180)
			(size 0.59 0.64)
			(layers "F.Cu" "F.Mask" "F.Paste")
			(roundrect_rratio 0.25)
			(net 1 "GND")
			(pintype "passive")
		)
		(pad "2" smd roundrect
			(at 0.48 0 180)
			(size 0.59 0.64)
			(layers "F.Cu" "F.Mask" "F.Paste")
			(roundrect_rratio 0.25)
			(net 276 "Net-(C81-Pad2)")
			(pintype "passive")
		)
	)
	(footprint "antmicro-footprints:R_0402_1005Metric"
		(layer "F.Cu")
		(at 89.549 81.827 90)
		(descr "Resistor SMD 0402")
		(tags "resistor SMD 0402")
		(property "Reference" "R78"
			(at -1.073 3.351 90)
			(layer "F.SilkS")
			(effects
				(font
					(size 0.7 0.7)
					(thickness 0.15)
				)
				(justify left bottom)
			)
		)
		(property "Value" "R_100k_0402"
			(at 0 1.4 90)
			(layer "F.Fab")
			(effects
				(font
					(size 0.7 0.7)
					(thickness 0.15)
				)
				(justify left bottom)
			)
		)
		(property "Datasheet" "https://www.bourns.com/docs/product-datasheets/cr.pdf"
			(at 0 0 90)
			(layer "F.Fab")
			(hide yes)
			(effects
				(font
					(size 1.27 1.27)
					(thickness 0.15)
				)
			)
		)
		(property "Description" "SMD Chip Resistor, 100 kohm, ± 1%, 62.5 mW, 0402 [1005 Metric], Thick Film, General Purpose"
			(at 0 0 90)
			(layer "F.Fab")
			(hide yes)
			(effects
				(font
					(size 1.27 1.27)
					(thickness 0.15)
				)
			)
		)
		(property "Author" "Antmicro"
			(at 171.376 -7.722 0)
			(layer "F.Fab")
			(hide yes)
			(effects
				(font
					(size 1 1)
					(thickness 0.15)
				)
			)
		)
		(property "License" "Apache-2.0"
			(at 171.376 -7.722 0)
			(layer "F.Fab")
			(hide yes)
			(effects
				(font
					(size 1 1)
					(thickness 0.15)
				)
			)
		)
		(property "MPN" "CR0402-FX-1003GLF"
			(at 171.376 -7.722 0)
			(layer "F.Fab")
			(hide yes)
			(effects
				(font
					(size 1 1)
					(thickness 0.15)
				)
			)
		)
		(property "Manufacturer" "Bourns"
			(at 171.376 -7.722 0)
			(layer "F.Fab")
			(hide yes)
			(effects
				(font
					(size 1 1)
					(thickness 0.15)
				)
			)
		)
		(property "Tolerance" "1%"
			(at 171.376 -7.722 0)
			(layer "F.Fab")
			(hide yes)
			(effects
				(font
					(size 1 1)
					(thickness 0.15)
				)
			)
		)
		(property "Val" "100k"
			(at 171.376 -7.722 0)
			(layer "F.Fab")
			(hide yes)
			(effects
				(font
					(size 1 1)
					(thickness 0.15)
				)
			)
		)
		(sheetname "/Power supply/")
		(sheetfile "power-supply.kicad_sch")
		(attr smd)
		(fp_rect
			(start -0.925 -0.47)
			(end 0.925 0.47)
			(stroke
				(width 0.05)
				(type default)
			)
			(fill no)
			(layer "F.CrtYd")
		)
		(fp_rect
			(start -0.5 -0.25)
			(end 0.5 0.25)
			(stroke
				(width 0.15)
				(type solid)
			)
			(fill no)
			(layer "F.Fab")
		)
		(pad "1" smd roundrect
			(at -0.48 0 90)
			(size 0.59 0.64)
			(layers "F.Cu" "F.Mask" "F.Paste")
			(roundrect_rratio 0.25)
			(net 195 "Net-(U12-FB)")
			(pintype "passive")
		)
		(pad "2" smd roundrect
			(at 0.48 0 90)
			(size 0.59 0.64)
			(layers "F.Cu" "F.Mask" "F.Paste")
			(roundrect_rratio 0.25)
			(net 1 "GND")
			(pintype "passive")
		)
	)
	(footprint "antmicro-footprints:QFN-8_2x1.5mm"
		(layer "F.Cu")
		(at 86.995 82.025 180)
		(property "Reference" "U12"
			(at 0.305 -2.205 180)
			(layer "F.SilkS")
			(effects
				(font
					(size 0.7 0.7)
					(thickness 0.15)
				)
				(justify left bottom)
			)
		)
		(property "Value" "TPS62823DLCT"
			(at 0 2.2 180)
			(layer "F.Fab")
			(effects
				(font
					(size 0.7 0.7)
					(thickness 0.15)
				)
				(justify left bottom)
			)
		)
		(property "Datasheet" "https://www.ti.com/lit/ds/symlink/tps62823.pdf?ts=1685970309606&ref_url=https%253A%252F%252Fwww.ti.com%252Fproduct%252FTPS62823%252Fpart-details%252FTPS62823DLCT"
			(at 0 0 180)
			(layer "F.Fab")
			(hide yes)
			(effects
				(font
					(size 1.27 1.27)
					(thickness 0.15)
				)
			)
		)
		(property "Description" "DC/DC converter"
			(at 0 0 180)
			(layer "F.Fab")
			(hide yes)
			(effects
				(font
					(size 1.27 1.27)
					(thickness 0.15)
				)
			)
		)
		(property "Author" "Antmicro"
			(at 173.99 164.05 0)
			(layer "F.Fab")
			(hide yes)
			(effects
				(font
					(size 1 1)
					(thickness 0.15)
				)
			)
		)
		(property "License" "Apache-2.0"
			(at 173.99 164.05 0)
			(layer "F.Fab")
			(hide yes)
			(effects
				(font
					(size 1 1)
					(thickness 0.15)
				)
			)
		)
		(property "MPN" "TPS62823DLCT"
			(at 173.99 164.05 0)
			(layer "F.Fab")
			(hide yes)
			(effects
				(font
					(size 1 1)
					(thickness 0.15)
				)
			)
		)
		(property "Manufacturer" "Texas Instruments"
			(at 173.99 164.05 0)
			(layer "F.Fab")
			(hide yes)
			(effects
				(font
					(size 1 1)
					(thickness 0.15)
				)
			)
		)
		(sheetname "/Power supply/")
		(sheetfile "power-supply.kicad_sch")
		(attr smd)
		(fp_line
			(start -0.25 -1.05)
			(end 0.9 -1.05)
			(stroke
				(width 0.15)
				(type solid)
			)
			(layer "F.SilkS")
		)
		(fp_line
			(start -0.9 1.05)
			(end 0.9 1.05)
			(stroke
				(width 0.15)
				(type solid)
			)
			(layer "F.SilkS")
		)
		(fp_circle
			(center -0.9 -1.05)
			(end -0.849 -1.05)
			(stroke
				(width 0.15)
				(type solid)
			)
			(fill yes)
			(layer "F.SilkS")
		)
		(fp_rect
			(start -1.1 -1.25)
			(end 1.1 1.25)
			(stroke
				(width 0.05)
				(type solid)
			)
			(fill no)
			(layer "F.CrtYd")
		)
		(fp_line
			(start 0.998 0.998)
			(end -1 0.998)
			(stroke
				(width 0.15)
				(type solid)
			)
			(layer "F.Fab")
		)
		(fp_line
			(start 0.998 -1)
			(end 0.998 0.998)
			(stroke
				(width 0.15)
				(type solid)
			)
			(layer "F.Fab")
		)
		(fp_line
			(start -0.5 -1)
			(end 0.998 -1)
			(stroke
				(width 0.15)
				(type solid)
			)
			(layer "F.Fab")
		)
		(fp_line
			(start -1 0.998)
			(end -1 -0.5)
			(stroke
				(width 0.15)
				(type solid)
			)
			(layer "F.Fab")
		)
		(fp_line
			(start -1 -0.5)
			(end -0.5 -1)
			(stroke
				(width 0.15)
				(type solid)
			)
			(layer "F.Fab")
		)
		(pad "1" smd rect
			(at -0.677 -0.75 180)
			(size 0.55 0.25)
			(layers "F.Cu" "F.Mask" "F.Paste")
			(net 319 "Net-(U12-EN)")
			(pinfunction "EN")
			(pintype "input")
		)
		(pad "2" smd rect
			(at -0.677 -0.25 180)
			(size 0.55 0.25)
			(layers "F.Cu" "F.Mask" "F.Paste")
			(net 195 "Net-(U12-FB)")
			(pinfunction "FB")
			(pintype "bidirectional")
		)
		(pad "3" smd rect
			(at -0.677 0.248 180)
			(size 0.55 0.25)
			(layers "F.Cu" "F.Mask" "F.Paste")
			(net 1 "GND")
			(pinfunction "AGND")
			(pintype "power_in")
		)
		(pad "4" smd rect
			(at -0.677 0.748 180)
			(size 0.55 0.25)
			(layers "F.Cu" "F.Mask" "F.Paste")
			(net 531 "unconnected-(U12-NC-Pad4)")
			(pinfunction "NC")
			(pintype "no_connect")
		)
		(pad "5" smd rect
			(at 0.675 0.748 180)
			(size 0.55 0.25)
			(layers "F.Cu" "F.Mask" "F.Paste")
			(net 1 "GND")
			(pinfunction "PGND")
			(pintype "power_in")
		)
		(pad "6" smd rect
			(at 0.675 0.248 180)
			(size 0.55 0.25)
			(layers "F.Cu" "F.Mask" "F.Paste")
			(net 289 "Net-(U12-SW)")
			(pinfunction "SW")
			(pintype "bidirectional")
		)
		(pad "7" smd rect
			(at 0.675 -0.25 180)
			(size 0.55 0.25)
			(layers "F.Cu" "F.Mask" "F.Paste")
			(net 4 "VCC5V0")
			(pinfunction "VIN")
			(pintype "power_in")
		)
		(pad "8" smd rect
			(at 0.675 -0.75 180)
			(size 0.55 0.25)
			(layers "F.Cu" "F.Mask" "F.Paste")
			(net 538 "1V0_PG")
			(pinfunction "PG")
			(pintype "output")
		)
	)
	(footprint "antmicro-footprints:C_0402_1005Metric"
		(layer "F.Cu")
		(at 91.545 81.825 90)
		(descr "Capacitor SMD 0402")
		(tags "capacitor SMD 0402")
		(property "Reference" "C81"
			(at -1.075 2.355 90)
			(layer "F.SilkS")
			(effects
				(font
					(size 0.7 0.7)
					(thickness 0.15)
				)
				(justify left bottom)
			)
		)
		(property "Value" "C_120p_0402"
			(at 0 1.4 90)
			(layer "F.Fab")
			(effects
				(font
					(size 0.7 0.7)
					(thickness 0.15)
				)
				(justify left bottom)
			)
		)
		(property "Datasheet" "https://www.kemet.com/en/us/capacitors/product/C0402C121J5GACTU.html"
			(at 0 0 90)
			(layer "F.Fab")
			(hide yes)
			(effects
				(font
					(size 1.27 1.27)
					(thickness 0.15)
				)
			)
		)
		(property "Description" "120 pF ±2% 100V Ceramic Capacitor C0G, NP0 0402 (1005 Metric)"
			(at 0 0 90)
			(layer "F.Fab")
			(hide yes)
			(effects
				(font
					(size 1.27 1.27)
					(thickness 0.15)
				)
			)
		)
		(property "Author" "Antmicro"
			(at 173.37 -9.72 0)
			(layer "F.Fab")
			(hide yes)
			(effects
				(font
					(size 1 1)
					(thickness 0.15)
				)
			)
		)
		(property "Dielectric" "C0G"
			(at 173.37 -9.72 0)
			(layer "F.Fab")
			(hide yes)
			(effects
				(font
					(size 1 1)
					(thickness 0.15)
				)
			)
		)
		(property "License" "Apache-2.0"
			(at 173.37 -9.72 0)
			(layer "F.Fab")
			(hide yes)
			(effects
				(font
					(size 1 1)
					(thickness 0.15)
				)
			)
		)
		(property "MPN" "C0402C121J5GACTU"
			(at 173.37 -9.72 0)
			(layer "F.Fab")
			(hide yes)
			(effects
				(font
					(size 1 1)
					(thickness 0.15)
				)
			)
		)
		(property "Manufacturer" "KEMET"
			(at 173.37 -9.72 0)
			(layer "F.Fab")
			(hide yes)
			(effects
				(font
					(size 1 1)
					(thickness 0.15)
				)
			)
		)
		(property "Val" "120p"
			(at 173.37 -9.72 0)
			(layer "F.Fab")
			(hide yes)
			(effects
				(font
					(size 1 1)
					(thickness 0.15)
				)
			)
		)
		(property "Voltage" "100V"
			(at 173.37 -9.72 0)
			(layer "F.Fab")
			(hide yes)
			(effects
				(font
					(size 1 1)
					(thickness 0.15)
				)
			)
		)
		(sheetname "/Power supply/")
		(sheetfile "power-supply.kicad_sch")
		(attr smd)
		(fp_rect
			(start -0.925 -0.47)
			(end 0.925 0.47)
			(stroke
				(width 0.05)
				(type default)
			)
			(fill no)
			(layer "F.CrtYd")
		)
		(fp_line
			(start 0.504 -0.25)
			(end 0.504 0.248)
			(stroke
				(width 0.15)
				(type solid)
			)
			(layer "F.Fab")
		)
		(fp_line
			(start -0.494 -0.25)
			(end 0.504 -0.25)
			(stroke
				(width 0.15)
				(type solid)
			)
			(layer "F.Fab")
		)
		(fp_line
			(start 0.504 0.248)
			(end -0.494 0.248)
			(stroke
				(width 0.15)
				(type solid)
			)
			(layer "F.Fab")
		)
		(fp_line
			(start -0.494 0.248)
			(end -0.494 -0.25)
			(stroke
				(width 0.15)
				(type solid)
			)
			(layer "F.Fab")
		)
		(pad "1" smd roundrect
			(at -0.48 0 90)
			(size 0.59 0.64)
			(layers "F.Cu" "F.Mask" "F.Paste")
			(roundrect_rratio 0.25)
			(net 195 "Net-(U12-FB)")
			(pintype "passive")
		)
		(pad "2" smd roundrect
			(at 0.48 0 90)
			(size 0.59 0.64)
			(layers "F.Cu" "F.Mask" "F.Paste")
			(roundrect_rratio 0.25)
			(net 276 "Net-(C81-Pad2)")
			(pintype "passive")
		)
	)
	(footprint "antmicro-footprints:C_0603_1608Metric"
		(layer "F.Cu")
		(at 85.075 81.8 -90)
		(descr "Capacitor SMD 0603")
		(tags "capacitor 0603")
		(property "Reference" "C77"
			(at 2.2 0.575 270)
			(layer "F.SilkS")
			(effects
				(font
					(size 0.7 0.7)
					(thickness 0.15)
				)
				(justify left bottom)
			)
		)
		(property "Value" "C_10u_0603"
			(at 0 1.6 270)
			(layer "F.Fab")
			(effects
				(font
					(size 0.7 0.7)
					(thickness 0.15)
				)
				(justify left bottom)
			)
		)
		(property "Datasheet" "https://www.murata.com/products/productdetail?partno=GRM188R61A106KE69%23"
			(at 0 0 270)
			(layer "F.Fab")
			(hide yes)
			(effects
				(font
					(size 1.27 1.27)
					(thickness 0.15)
				)
			)
		)
		(property "Description" "SMD Multilayer Ceramic Capacitor, 10 µF, 10 V, 0603 [1608 Metric], ± 10%, X5R, GRM Series"
			(at 0 0 270)
			(layer "F.Fab")
			(hide yes)
			(effects
				(font
					(size 1.27 1.27)
					(thickness 0.15)
				)
			)
		)
		(property "Author" "Antmicro"
			(at 3.275 166.875 0)
			(layer "F.Fab")
			(hide yes)
			(effects
				(font
					(size 1 1)
					(thickness 0.15)
				)
			)
		)
		(property "Dielectric" "template_dielectric"
			(at 3.275 166.875 0)
			(layer "F.Fab")
			(hide yes)
			(effects
				(font
					(size 1 1)
					(thickness 0.15)
				)
			)
		)
		(property "License" "Apache-2.0"
			(at 3.275 166.875 0)
			(layer "F.Fab")
			(hide yes)
			(effects
				(font
					(size 1 1)
					(thickness 0.15)
				)
			)
		)
		(property "MPN" "GRM188R61A106KE69D"
			(at 3.275 166.875 0)
			(layer "F.Fab")
			(hide yes)
			(effects
				(font
					(size 1 1)
					(thickness 0.15)
				)
			)
		)
		(property "Manufacturer" "Murata"
			(at 3.275 166.875 0)
			(layer "F.Fab")
			(hide yes)
			(effects
				(font
					(size 1 1)
					(thickness 0.15)
				)
			)
		)
		(property "Val" "10u"
			(at 3.275 166.875 0)
			(layer "F.Fab")
			(hide yes)
			(effects
				(font
					(size 1 1)
					(thickness 0.15)
				)
			)
		)
		(property "Voltage" ""
			(at 3.275 166.875 0)
			(layer "F.Fab")
			(hide yes)
			(effects
				(font
					(size 1 1)
					(thickness 0.15)
				)
			)
		)
		(sheetname "/Power supply/")
		(sheetfile "power-supply.kicad_sch")
		(attr smd)
		(fp_line
			(start -0.15 0.4)
			(end 0.15 0.4)
			(stroke
				(width 0.15)
				(type solid)
			)
			(layer "F.SilkS")
		)
		(fp_line
			(start -0.15 -0.4)
			(end 0.15 -0.4)
			(stroke
				(width 0.15)
				(type solid)
			)
			(layer "F.SilkS")
		)
		(fp_rect
			(start -1.25 -0.65)
			(end 1.25 0.65)
			(stroke
				(width 0.05)
				(type solid)
			)
			(fill no)
			(layer "F.CrtYd")
		)
		(fp_rect
			(start -0.8 -0.4)
			(end 0.8 0.4)
			(stroke
				(width 0.15)
				(type solid)
			)
			(fill no)
			(layer "F.Fab")
		)
		(pad "1" smd roundrect
			(at -0.7 0 270)
			(size 0.8 1)
			(layers "F.Cu" "F.Mask" "F.Paste")
			(roundrect_rratio 0.2)
			(net 1 "GND")
			(pintype "passive")
		)
		(pad "2" smd roundrect
			(at 0.7 0 270)
			(size 0.8 1)
			(layers "F.Cu" "F.Mask" "F.Paste")
			(roundrect_rratio 0.2)
			(net 4 "VCC5V0")
			(pintype "passive")
		)
	)
	(footprint "antmicro-footprints:C_0402_1005Metric"
		(layer "F.Cu")
		(at 85.905 85.385 180)
		(descr "Capacitor SMD 0402")
		(tags "capacitor SMD 0402")
		(property "Reference" "C90"
			(at -2.995 -0.315 0)
			(layer "F.SilkS")
			(effects
				(font
					(size 0.7 0.7)
					(thickness 0.15)
				)
				(justify right bottom)
			)
		)
		(property "Value" "C_10u_0402"
			(at 0 1.4 0)
			(layer "F.Fab")
			(effects
				(font
					(size 0.7 0.7)
					(thickness 0.15)
				)
				(justify right bottom)
			)
		)
		(property "Datasheet" "https://www.yageo.com/en/Chart/Download/pdf/CC0402MRX5R5BB106"
			(at 0 0 180)
			(layer "F.Fab")
			(hide yes)
			(effects
				(font
					(size 1.27 1.27)
					(thickness 0.15)
				)
			)
		)
		(property "Description" "SMD Multilayer Ceramic Capacitor, 10 µF, 6.3 V, 0402 [1005 Metric], ± 20%, X5R, CC Series"
			(at 0 0 180)
			(layer "F.Fab")
			(hide yes)
			(effects
				(font
					(size 1.27 1.27)
					(thickness 0.15)
				)
			)
		)
		(property "Author" "Antmicro"
			(at 171.81 170.77 0)
			(layer "F.Fab")
			(hide yes)
			(effects
				(font
					(size 1 1)
					(thickness 0.15)
				)
			)
		)
		(property "Dielectric" ""
			(at 171.81 170.77 0)
			(layer "F.Fab")
			(hide yes)
			(effects
				(font
					(size 1 1)
					(thickness 0.15)
				)
			)
		)
		(property "License" "Apache-2.0"
			(at 171.81 170.77 0)
			(layer "F.Fab")
			(hide yes)
			(effects
				(font
					(size 1 1)
					(thickness 0.15)
				)
			)
		)
		(property "MPN" "CC0402MRX5R5BB106"
			(at 171.81 170.77 0)
			(layer "F.Fab")
			(hide yes)
			(effects
				(font
					(size 1 1)
					(thickness 0.15)
				)
			)
		)
		(property "Manufacturer" "YAGEO"
			(at 171.81 170.77 0)
			(layer "F.Fab")
			(hide yes)
			(effects
				(font
					(size 1 1)
					(thickness 0.15)
				)
			)
		)
		(property "Val" "10u"
			(at 171.81 170.77 0)
			(layer "F.Fab")
			(hide yes)
			(effects
				(font
					(size 1 1)
					(thickness 0.15)
				)
			)
		)
		(property "Voltage" ""
			(at 171.81 170.77 0)
			(layer "F.Fab")
			(hide yes)
			(effects
				(font
					(size 1 1)
					(thickness 0.15)
				)
			)
		)
		(sheetname "/Power supply/")
		(sheetfile "power-supply.kicad_sch")
		(attr smd)
		(fp_rect
			(start -0.925 -0.47)
			(end 0.925 0.47)
			(stroke
				(width 0.05)
				(type default)
			)
			(fill no)
			(layer "F.CrtYd")
		)
		(fp_line
			(start 0.504 0.248)
			(end -0.494 0.248)
			(stroke
				(width 0.15)
				(type solid)
			)
			(layer "F.Fab")
		)
		(fp_line
			(start 0.504 -0.25)
			(end 0.504 0.248)
			(stroke
				(width 0.15)
				(type solid)
			)
			(layer "F.Fab")
		)
		(fp_line
			(start -0.494 0.248)
			(end -0.494 -0.25)
			(stroke
				(width 0.15)
				(type solid)
			)
			(layer "F.Fab")
		)
		(fp_line
			(start -0.494 -0.25)
			(end 0.504 -0.25)
			(stroke
				(width 0.15)
				(type solid)
			)
			(layer "F.Fab")
		)
		(pad "1" smd roundrect
			(at -0.48 0 180)
			(size 0.59 0.64)
			(layers "F.Cu" "F.Mask" "F.Paste")
			(roundrect_rratio 0.25)
			(net 1 "GND")
			(pintype "passive")
		)
		(pad "2" smd roundrect
			(at 0.48 0 180)
			(size 0.59 0.64)
			(layers "F.Cu" "F.Mask" "F.Paste")
			(roundrect_rratio 0.25)
			(net 277 "Net-(C82-Pad2)")
			(pintype "passive")
		)
	)
	(footprint "antmicro-footprints:C_0603_1608Metric"
		(layer "F.Cu")
		(at 85.175 89.175 -90)
		(descr "Capacitor SMD 0603")
		(tags "capacitor 0603")
		(property "Reference" "C78"
			(at 2.025 0.575 270)
			(layer "F.SilkS")
			(effects
				(font
					(size 0.7 0.7)
					(thickness 0.15)
				)
				(justify left bottom)
			)
		)
		(property "Value" "C_10u_0603"
			(at 0 1.6 270)
			(layer "F.Fab")
			(effects
				(font
					(size 0.7 0.7)
					(thickness 0.15)
				)
				(justify left bottom)
			)
		)
		(property "Datasheet" "https://www.murata.com/products/productdetail?partno=GRM188R61A106KE69%23"
			(at 0 0 270)
			(layer "F.Fab")
			(hide yes)
			(effects
				(font
					(size 1.27 1.27)
					(thickness 0.15)
				)
			)
		)
		(property "Description" "SMD Multilayer Ceramic Capacitor, 10 µF, 10 V, 0603 [1608 Metric], ± 10%, X5R, GRM Series"
			(at 0 0 270)
			(layer "F.Fab")
			(hide yes)
			(effects
				(font
					(size 1.27 1.27)
					(thickness 0.15)
				)
			)
		)
		(property "Author" "Antmicro"
			(at -4 174.35 0)
			(layer "F.Fab")
			(hide yes)
			(effects
				(font
					(size 1 1)
					(thickness 0.15)
				)
			)
		)
		(property "Dielectric" "template_dielectric"
			(at -4 174.35 0)
			(layer "F.Fab")
			(hide yes)
			(effects
				(font
					(size 1 1)
					(thickness 0.15)
				)
			)
		)
		(property "License" "Apache-2.0"
			(at -4 174.35 0)
			(layer "F.Fab")
			(hide yes)
			(effects
				(font
					(size 1 1)
					(thickness 0.15)
				)
			)
		)
		(property "MPN" "GRM188R61A106KE69D"
			(at -4 174.35 0)
			(layer "F.Fab")
			(hide yes)
			(effects
				(font
					(size 1 1)
					(thickness 0.15)
				)
			)
		)
		(property "Manufacturer" "Murata"
			(at -4 174.35 0)
			(layer "F.Fab")
			(hide yes)
			(effects
				(font
					(size 1 1)
					(thickness 0.15)
				)
			)
		)
		(property "Val" "10u"
			(at -4 174.35 0)
			(layer "F.Fab")
			(hide yes)
			(effects
				(font
					(size 1 1)
					(thickness 0.15)
				)
			)
		)
		(property "Voltage" ""
			(at -4 174.35 0)
			(layer "F.Fab")
			(hide yes)
			(effects
				(font
					(size 1 1)
					(thickness 0.15)
				)
			)
		)
		(sheetname "/Power supply/")
		(sheetfile "power-supply.kicad_sch")
		(attr smd)
		(fp_line
			(start -0.15 0.4)
			(end 0.15 0.4)
			(stroke
				(width 0.15)
				(type solid)
			)
			(layer "F.SilkS")
		)
		(fp_line
			(start -0.15 -0.4)
			(end 0.15 -0.4)
			(stroke
				(width 0.15)
				(type solid)
			)
			(layer "F.SilkS")
		)
		(fp_rect
			(start -1.25 -0.65)
			(end 1.25 0.65)
			(stroke
				(width 0.05)
				(type solid)
			)
			(fill no)
			(layer "F.CrtYd")
		)
		(fp_rect
			(start -0.8 -0.4)
			(end 0.8 0.4)
			(stroke
				(width 0.15)
				(type solid)
			)
			(fill no)
			(layer "F.Fab")
		)
		(pad "1" smd roundrect
			(at -0.7 0 270)
			(size 0.8 1)
			(layers "F.Cu" "F.Mask" "F.Paste")
			(roundrect_rratio 0.2)
			(net 1 "GND")
			(pintype "passive")
		)
		(pad "2" smd roundrect
			(at 0.7 0 270)
			(size 0.8 1)
			(layers "F.Cu" "F.Mask" "F.Paste")
			(roundrect_rratio 0.2)
			(net 4 "VCC5V0")
			(pintype "passive")
		)
	)
	(footprint "antmicro-footprints:QFN-8_2x1.5mm"
		(layer "F.Cu")
		(at 87.005 89.435 180)
		(property "Reference" "U13"
			(at 0.265 -2.265 180)
			(layer "F.SilkS")
			(effects
				(font
					(size 0.7 0.7)
					(thickness 0.15)
				)
				(justify left bottom)
			)
		)
		(property "Value" "TPS62823DLCT"
			(at 0 2.2 180)
			(layer "F.Fab")
			(effects
				(font
					(size 0.7 0.7)
					(thickness 0.15)
				)
				(justify left bottom)
			)
		)
		(property "Datasheet" "https://www.ti.com/lit/ds/symlink/tps62823.pdf?ts=1685970309606&ref_url=https%253A%252F%252Fwww.ti.com%252Fproduct%252FTPS62823%252Fpart-details%252FTPS62823DLCT"
			(at 0 0 180)
			(layer "F.Fab")
			(hide yes)
			(effects
				(font
					(size 1.27 1.27)
					(thickness 0.15)
				)
			)
		)
		(property "Description" "DC/DC converter"
			(at 0 0 180)
			(layer "F.Fab")
			(hide yes)
			(effects
				(font
					(size 1.27 1.27)
					(thickness 0.15)
				)
			)
		)
		(property "Author" "Antmicro"
			(at 174.01 178.87 0)
			(layer "F.Fab")
			(hide yes)
			(effects
				(font
					(size 1 1)
					(thickness 0.15)
				)
			)
		)
		(property "License" "Apache-2.0"
			(at 174.01 178.87 0)
			(layer "F.Fab")
			(hide yes)
			(effects
				(font
					(size 1 1)
					(thickness 0.15)
				)
			)
		)
		(property "MPN" "TPS62823DLCT"
			(at 174.01 178.87 0)
			(layer "F.Fab")
			(hide yes)
			(effects
				(font
					(size 1 1)
					(thickness 0.15)
				)
			)
		)
		(property "Manufacturer" "Texas Instruments"
			(at 174.01 178.87 0)
			(layer "F.Fab")
			(hide yes)
			(effects
				(font
					(size 1 1)
					(thickness 0.15)
				)
			)
		)
		(sheetname "/Power supply/")
		(sheetfile "power-supply.kicad_sch")
		(attr smd)
		(fp_line
			(start -0.25 -1.05)
			(end 0.9 -1.05)
			(stroke
				(width 0.15)
				(type solid)
			)
			(layer "F.SilkS")
		)
		(fp_line
			(start -0.9 1.05)
			(end 0.9 1.05)
			(stroke
				(width 0.15)
				(type solid)
			)
			(layer "F.SilkS")
		)
		(fp_circle
			(center -0.9 -1.05)
			(end -0.849 -1.05)
			(stroke
				(width 0.15)
				(type solid)
			)
			(fill yes)
			(layer "F.SilkS")
		)
		(fp_rect
			(start -1.1 -1.25)
			(end 1.1 1.25)
			(stroke
				(width 0.05)
				(type solid)
			)
			(fill no)
			(layer "F.CrtYd")
		)
		(fp_line
			(start 0.998 0.998)
			(end -1 0.998)
			(stroke
				(width 0.15)
				(type solid)
			)
			(layer "F.Fab")
		)
		(fp_line
			(start 0.998 -1)
			(end 0.998 0.998)
			(stroke
				(width 0.15)
				(type solid)
			)
			(layer "F.Fab")
		)
		(fp_line
			(start -0.5 -1)
			(end 0.998 -1)
			(stroke
				(width 0.15)
				(type solid)
			)
			(layer "F.Fab")
		)
		(fp_line
			(start -1 0.998)
			(end -1 -0.5)
			(stroke
				(width 0.15)
				(type solid)
			)
			(layer "F.Fab")
		)
		(fp_line
			(start -1 -0.5)
			(end -0.5 -1)
			(stroke
				(width 0.15)
				(type solid)
			)
			(layer "F.Fab")
		)
		(pad "1" smd rect
			(at -0.677 -0.75 180)
			(size 0.55 0.25)
			(layers "F.Cu" "F.Mask" "F.Paste")
			(net 343 "Net-(U13-EN)")
			(pinfunction "EN")
			(pintype "input")
		)
		(pad "2" smd rect
			(at -0.677 -0.25 180)
			(size 0.55 0.25)
			(layers "F.Cu" "F.Mask" "F.Paste")
			(net 196 "Net-(U13-FB)")
			(pinfunction "FB")
			(pintype "bidirectional")
		)
		(pad "3" smd rect
			(at -0.677 0.248 180)
			(size 0.55 0.25)
			(layers "F.Cu" "F.Mask" "F.Paste")
			(net 1 "GND")
			(pinfunction "AGND")
			(pintype "power_in")
		)
		(pad "4" smd rect
			(at -0.677 0.748 180)
			(size 0.55 0.25)
			(layers "F.Cu" "F.Mask" "F.Paste")
			(net 532 "unconnected-(U13-NC-Pad4)")
			(pinfunction "NC")
			(pintype "no_connect")
		)
		(pad "5" smd rect
			(at 0.675 0.748 180)
			(size 0.55 0.25)
			(layers "F.Cu" "F.Mask" "F.Paste")
			(net 1 "GND")
			(pinfunction "PGND")
			(pintype "power_in")
		)
		(pad "6" smd rect
			(at 0.675 0.248 180)
			(size 0.55 0.25)
			(layers "F.Cu" "F.Mask" "F.Paste")
			(net 290 "Net-(U13-SW)")
			(pinfunction "SW")
			(pintype "bidirectional")
		)
		(pad "7" smd rect
			(at 0.675 -0.25 180)
			(size 0.55 0.25)
			(layers "F.Cu" "F.Mask" "F.Paste")
			(net 4 "VCC5V0")
			(pinfunction "VIN")
			(pintype "power_in")
		)
		(pad "8" smd rect
			(at 0.675 -0.75 180)
			(size 0.55 0.25)
			(layers "F.Cu" "F.Mask" "F.Paste")
			(net 293 "/Power supply/1V35_PG")
			(pinfunction "PG")
			(pintype "output")
		)
	)
	(footprint "antmicro-footprints:R_0402_1005Metric"
		(layer "F.Cu")
		(at 90.555 89.235 -90)
		(descr "Resistor SMD 0402")
		(tags "resistor SMD 0402")
		(property "Reference" "R79"
			(at -2.935 -0.345 90)
			(layer "F.SilkS")
			(effects
				(font
					(size 0.7 0.7)
					(thickness 0.15)
				)
				(justify right bottom)
			)
		)
		(property "Value" "R_124k_0402"
			(at 0 1.4 90)
			(layer "F.Fab")
			(effects
				(font
					(size 0.7 0.7)
					(thickness 0.15)
				)
				(justify right bottom)
			)
		)
		(property "Datasheet" "https://www.bourns.com/docs/product-datasheets/cr.pdf"
			(at 0 0 270)
			(layer "F.Fab")
			(hide yes)
			(effects
				(font
					(size 1.27 1.27)
					(thickness 0.15)
				)
			)
		)
		(property "Description" "SMD Chip Resistor, 124 kohm, ± 1%, 100 mW, 0402 [1005 Metric], Thick Film, Precision"
			(at 0 0 270)
			(layer "F.Fab")
			(hide yes)
			(effects
				(font
					(size 1.27 1.27)
					(thickness 0.15)
				)
			)
		)
		(property "Author" "Antmicro"
			(at 1.32 179.79 0)
			(layer "F.Fab")
			(hide yes)
			(effects
				(font
					(size 1 1)
					(thickness 0.15)
				)
			)
		)
		(property "License" "Apache-2.0"
			(at 1.32 179.79 0)
			(layer "F.Fab")
			(hide yes)
			(effects
				(font
					(size 1 1)
					(thickness 0.15)
				)
			)
		)
		(property "MPN" "CR0402-FX-1243GLF"
			(at 1.32 179.79 0)
			(layer "F.Fab")
			(hide yes)
			(effects
				(font
					(size 1 1)
					(thickness 0.15)
				)
			)
		)
		(property "Manufacturer" "Bourns"
			(at 1.32 179.79 0)
			(layer "F.Fab")
			(hide yes)
			(effects
				(font
					(size 1 1)
					(thickness 0.15)
				)
			)
		)
		(property "Tolerance" "1%"
			(at 1.32 179.79 0)
			(layer "F.Fab")
			(hide yes)
			(effects
				(font
					(size 1 1)
					(thickness 0.15)
				)
			)
		)
		(property "Val" "124k"
			(at 1.32 179.79 0)
			(layer "F.Fab")
			(hide yes)
			(effects
				(font
					(size 1 1)
					(thickness 0.15)
				)
			)
		)
		(sheetname "/Power supply/")
		(sheetfile "power-supply.kicad_sch")
		(attr smd)
		(fp_rect
			(start -0.925 -0.47)
			(end 0.925 0.47)
			(stroke
				(width 0.05)
				(type default)
			)
			(fill no)
			(layer "F.CrtYd")
		)
		(fp_rect
			(start -0.5 -0.25)
			(end 0.5 0.25)
			(stroke
				(width 0.15)
				(type solid)
			)
			(fill no)
			(layer "F.Fab")
		)
		(pad "1" smd roundrect
			(at -0.48 0 270)
			(size 0.59 0.64)
			(layers "F.Cu" "F.Mask" "F.Paste")
			(roundrect_rratio 0.25)
			(net 277 "Net-(C82-Pad2)")
			(pintype "passive")
		)
		(pad "2" smd roundrect
			(at 0.48 0 270)
			(size 0.59 0.64)
			(layers "F.Cu" "F.Mask" "F.Paste")
			(roundrect_rratio 0.25)
			(net 196 "Net-(U13-FB)")
			(pintype "passive")
		)
	)
	(footprint "antmicro-footprints:C_0402_1005Metric"
		(layer "F.Cu")
		(at 91.555 89.235 90)
		(descr "Capacitor SMD 0402")
		(tags "capacitor SMD 0402")
		(property "Reference" "C82"
			(at 0.835 0.345 90)
			(layer "F.SilkS")
			(effects
				(font
					(size 0.7 0.7)
					(thickness 0.15)
				)
				(justify left bottom)
			)
		)
		(property "Value" "C_120p_0402"
			(at 0 1.4 90)
			(layer "F.Fab")
			(effects
				(font
					(size 0.7 0.7)
					(thickness 0.15)
				)
				(justify left bottom)
			)
		)
		(property "Datasheet" "https://www.kemet.com/en/us/capacitors/product/C0402C121J5GACTU.html"
			(at 0 0 90)
			(layer "F.Fab")
			(hide yes)
			(effects
				(font
					(size 1.27 1.27)
					(thickness 0.15)
				)
			)
		)
		(property "Description" "120 pF ±2% 100V Ceramic Capacitor C0G, NP0 0402 (1005 Metric)"
			(at 0 0 90)
			(layer "F.Fab")
			(hide yes)
			(effects
				(font
					(size 1.27 1.27)
					(thickness 0.15)
				)
			)
		)
		(property "Author" "Antmicro"
			(at 180.79 -2.32 0)
			(layer "F.Fab")
			(hide yes)
			(effects
				(font
					(size 1 1)
					(thickness 0.15)
				)
			)
		)
		(property "Dielectric" "C0G"
			(at 180.79 -2.32 0)
			(layer "F.Fab")
			(hide yes)
			(effects
				(font
					(size 1 1)
					(thickness 0.15)
				)
			)
		)
		(property "License" "Apache-2.0"
			(at 180.79 -2.32 0)
			(layer "F.Fab")
			(hide yes)
			(effects
				(font
					(size 1 1)
					(thickness 0.15)
				)
			)
		)
		(property "MPN" "C0402C121J5GACTU"
			(at 180.79 -2.32 0)
			(layer "F.Fab")
			(hide yes)
			(effects
				(font
					(size 1 1)
					(thickness 0.15)
				)
			)
		)
		(property "Manufacturer" "KEMET"
			(at 180.79 -2.32 0)
			(layer "F.Fab")
			(hide yes)
			(effects
				(font
					(size 1 1)
					(thickness 0.15)
				)
			)
		)
		(property "Val" "120p"
			(at 180.79 -2.32 0)
			(layer "F.Fab")
			(hide yes)
			(effects
				(font
					(size 1 1)
					(thickness 0.15)
				)
			)
		)
		(property "Voltage" "100V"
			(at 180.79 -2.32 0)
			(layer "F.Fab")
			(hide yes)
			(effects
				(font
					(size 1 1)
					(thickness 0.15)
				)
			)
		)
		(sheetname "/Power supply/")
		(sheetfile "power-supply.kicad_sch")
		(attr smd)
		(fp_rect
			(start -0.925 -0.47)
			(end 0.925 0.47)
			(stroke
				(width 0.05)
				(type default)
			)
			(fill no)
			(layer "F.CrtYd")
		)
		(fp_line
			(start 0.504 -0.25)
			(end 0.504 0.248)
			(stroke
				(width 0.15)
				(type solid)
			)
			(layer "F.Fab")
		)
		(fp_line
			(start -0.494 -0.25)
			(end 0.504 -0.25)
			(stroke
				(width 0.15)
				(type solid)
			)
			(layer "F.Fab")
		)
		(fp_line
			(start 0.504 0.248)
			(end -0.494 0.248)
			(stroke
				(width 0.15)
				(type solid)
			)
			(layer "F.Fab")
		)
		(fp_line
			(start -0.494 0.248)
			(end -0.494 -0.25)
			(stroke
				(width 0.15)
				(type solid)
			)
			(layer "F.Fab")
		)
		(pad "1" smd roundrect
			(at -0.48 0 90)
			(size 0.59 0.64)
			(layers "F.Cu" "F.Mask" "F.Paste")
			(roundrect_rratio 0.25)
			(net 196 "Net-(U13-FB)")
			(pintype "passive")
		)
		(pad "2" smd roundrect
			(at 0.48 0 90)
			(size 0.59 0.64)
			(layers "F.Cu" "F.Mask" "F.Paste")
			(roundrect_rratio 0.25)
			(net 277 "Net-(C82-Pad2)")
			(pintype "passive")
		)
	)
	(footprint "antmicro-footprints:R_0402_1005Metric"
		(layer "F.Cu")
		(at 89.555 89.235 90)
		(descr "Resistor SMD 0402")
		(tags "resistor SMD 0402")
		(property "Reference" "R80"
			(at 0.735 0.345 90)
			(layer "F.SilkS")
			(effects
				(font
					(size 0.7 0.7)
					(thickness 0.15)
				)
				(justify left bottom)
			)
		)
		(property "Value" "R_100k_0402"
			(at 0 1.4 90)
			(layer "F.Fab")
			(effects
				(font
					(size 0.7 0.7)
					(thickness 0.15)
				)
				(justify left bottom)
			)
		)
		(property "Datasheet" "https://www.bourns.com/docs/product-datasheets/cr.pdf"
			(at 0 0 90)
			(layer "F.Fab")
			(hide yes)
			(effects
				(font
					(size 1.27 1.27)
					(thickness 0.15)
				)
			)
		)
		(property "Description" "SMD Chip Resistor, 100 kohm, ± 1%, 62.5 mW, 0402 [1005 Metric], Thick Film, General Purpose"
			(at 0 0 90)
			(layer "F.Fab")
			(hide yes)
			(effects
				(font
					(size 1.27 1.27)
					(thickness 0.15)
				)
			)
		)
		(property "Author" "Antmicro"
			(at 178.79 -0.32 0)
			(layer "F.Fab")
			(hide yes)
			(effects
				(font
					(size 1 1)
					(thickness 0.15)
				)
			)
		)
		(property "License" "Apache-2.0"
			(at 178.79 -0.32 0)
			(layer "F.Fab")
			(hide yes)
			(effects
				(font
					(size 1 1)
					(thickness 0.15)
				)
			)
		)
		(property "MPN" "CR0402-FX-1003GLF"
			(at 178.79 -0.32 0)
			(layer "F.Fab")
			(hide yes)
			(effects
				(font
					(size 1 1)
					(thickness 0.15)
				)
			)
		)
		(property "Manufacturer" "Bourns"
			(at 178.79 -0.32 0)
			(layer "F.Fab")
			(hide yes)
			(effects
				(font
					(size 1 1)
					(thickness 0.15)
				)
			)
		)
		(property "Tolerance" "1%"
			(at 178.79 -0.32 0)
			(layer "F.Fab")
			(hide yes)
			(effects
				(font
					(size 1 1)
					(thickness 0.15)
				)
			)
		)
		(property "Val" "100k"
			(at 178.79 -0.32 0)
			(layer "F.Fab")
			(hide yes)
			(effects
				(font
					(size 1 1)
					(thickness 0.15)
				)
			)
		)
		(sheetname "/Power supply/")
		(sheetfile "power-supply.kicad_sch")
		(attr smd)
		(fp_rect
			(start -0.925 -0.47)
			(end 0.925 0.47)
			(stroke
				(width 0.05)
				(type default)
			)
			(fill no)
			(layer "F.CrtYd")
		)
		(fp_rect
			(start -0.5 -0.25)
			(end 0.5 0.25)
			(stroke
				(width 0.15)
				(type solid)
			)
			(fill no)
			(layer "F.Fab")
		)
		(pad "1" smd roundrect
			(at -0.48 0 90)
			(size 0.59 0.64)
			(layers "F.Cu" "F.Mask" "F.Paste")
			(roundrect_rratio 0.25)
			(net 196 "Net-(U13-FB)")
			(pintype "passive")
		)
		(pad "2" smd roundrect
			(at 0.48 0 90)
			(size 0.59 0.64)
			(layers "F.Cu" "F.Mask" "F.Paste")
			(roundrect_rratio 0.25)
			(net 1 "GND")
			(pintype "passive")
		)
	)
	(footprint "antmicro-footprints:VSSOP-8_3x3mm_P0.65mm"
		(layer "F.Cu")
		(at 69.716 92.801143 -90)
		(property "Reference" "U9"
			(at -0.791143 1.976 90)
			(layer "F.SilkS")
			(effects
				(font
					(size 0.7 0.7)
					(thickness 0.15)
				)
				(justify right bottom)
			)
		)
		(property "Value" "LM3881"
			(at -2.15 3.971 90)
			(layer "F.Fab")
			(effects
				(font
					(size 0.7 0.7)
					(thickness 0.15)
				)
				(justify right bottom)
			)
		)
		(property "Datasheet" "http://www.ti.com/lit/ds/symlink/lm3881.pdf"
			(at 0 0 270)
			(layer "F.Fab")
			(hide yes)
			(effects
				(font
					(size 1.27 1.27)
					(thickness 0.15)
				)
			)
		)
		(property "Description" "Power Sequencer, 3-Monitors, 2.7V-5.5Vin,VSSOP-8"
			(at 0 0 270)
			(layer "F.Fab")
			(hide yes)
			(effects
				(font
					(size 1.27 1.27)
					(thickness 0.15)
				)
			)
		)
		(property "Author" "Antmicro"
			(at -23.085143 162.517143 0)
			(layer "F.Fab")
			(hide yes)
			(effects
				(font
					(size 1 1)
					(thickness 0.15)
				)
			)
		)
		(property "License" "Apache-2.0"
			(at -23.085143 162.517143 0)
			(layer "F.Fab")
			(hide yes)
			(effects
				(font
					(size 1 1)
					(thickness 0.15)
				)
			)
		)
		(property "MPN" "LM3881MME/NOPB"
			(at -23.085143 162.517143 0)
			(layer "F.Fab")
			(hide yes)
			(effects
				(font
					(size 1 1)
					(thickness 0.15)
				)
			)
		)
		(property "Manufacturer" "Texas Instruments"
			(at -23.085143 162.517143 0)
			(layer "F.Fab")
			(hide yes)
			(effects
				(font
					(size 1 1)
					(thickness 0.15)
				)
			)
		)
		(sheetname "/Power supply/")
		(sheetfile "power-supply.kicad_sch")
		(attr smd)
		(fp_line
			(start -1.496 1.625)
			(end 1.554 1.625)
			(stroke
				(width 0.12)
				(type solid)
			)
			(layer "F.SilkS")
		)
		(fp_line
			(start -1.6 -1.625)
			(end 1.554 -1.625)
			(stroke
				(width 0.12)
				(type solid)
			)
			(layer "F.SilkS")
		)
		(fp_circle
			(center -2.1 -1.438)
			(end -2.05 -1.438)
			(stroke
				(width 0.12)
				(type solid)
			)
			(fill yes)
			(layer "F.SilkS")
		)
		(fp_rect
			(start -3 -1.838)
			(end 3 1.862)
			(stroke
				(width 0.05)
				(type solid)
			)
			(fill no)
			(layer "F.CrtYd")
		)
		(fp_line
			(start -1.497 1.5)
			(end -1.497 -1.502)
			(stroke
				(width 0.15)
				(type solid)
			)
			(layer "F.Fab")
		)
		(fp_line
			(start 1.504 1.5)
			(end -1.497 1.5)
			(stroke
				(width 0.15)
				(type solid)
			)
			(layer "F.Fab")
		)
		(fp_line
			(start -1.497 -1.502)
			(end 1.504 -1.502)
			(stroke
				(width 0.15)
				(type solid)
			)
			(layer "F.Fab")
		)
		(fp_line
			(start 1.504 -1.502)
			(end 1.504 1.5)
			(stroke
				(width 0.15)
				(type solid)
			)
			(layer "F.Fab")
		)
		(pad "1" smd rect
			(at -2.096 -0.975 270)
			(size 1.556504 0.457986)
			(layers "F.Cu" "F.Mask" "F.Paste")
			(net 4 "VCC5V0")
			(pinfunction "VCC")
			(pintype "power_in")
		)
		(pad "2" smd roundrect
			(at -2.096 -0.326 270)
			(size 1.556504 0.457986)
			(layers "F.Cu" "F.Mask" "F.Paste")
			(roundrect_rratio 0.5)
			(net 573 "/Power supply/5V0_PG")
			(pinfunction "EN")
			(pintype "passive")
		)
		(pad "3" smd roundrect
			(at -2.096 0.325 270)
			(size 1.556504 0.457986)
			(layers "F.Cu" "F.Mask" "F.Paste")
			(roundrect_rratio 0.5)
			(net 1 "GND")
			(pinfunction "GND")
			(pintype "power_in")
		)
		(pad "4" smd roundrect
			(at -2.096 0.974 270)
			(size 1.556504 0.457986)
			(layers "F.Cu" "F.Mask" "F.Paste")
			(roundrect_rratio 0.5)
			(net 4 "VCC5V0")
			(pinfunction "INV")
			(pintype "input")
		)
		(pad "5" smd roundrect
			(at 2.105 0.974 270)
			(size 1.556504 0.457986)
			(layers "F.Cu" "F.Mask" "F.Paste")
			(roundrect_rratio 0.5)
			(net 103 "Net-(U9-TADJ)")
			(pinfunction "TADJ")
			(pintype "passive")
		)
		(pad "6" smd roundrect
			(at 2.105 0.325 270)
			(size 1.556504 0.457986)
			(layers "F.Cu" "F.Mask" "F.Paste")
			(roundrect_rratio 0.5)
			(net 297 "/Power supply/VCCIO_EN")
			(pinfunction "FLAG3")
			(pintype "open_collector")
		)
		(pad "7" smd roundrect
			(at 2.105 -0.326 270)
			(size 1.556504 0.457986)
			(layers "F.Cu" "F.Mask" "F.Paste")
			(roundrect_rratio 0.5)
			(net 296 "/Power supply/VCCAUX_EN")
			(pinfunction "FLAG2")
			(pintype "open_collector")
		)
		(pad "8" smd roundrect
			(at 2.105 -0.975 270)
			(size 1.556504 0.457986)
			(layers "F.Cu" "F.Mask" "F.Paste")
			(roundrect_rratio 0.5)
			(net 295 "/Power supply/VCCINT_EN")
			(pinfunction "FLAG1")
			(pintype "open_collector")
		)
	)
	(footprint "antmicro-footprints:C_0402_1005Metric"
		(layer "F.Cu")
		(at 94.674 140.075 -90)
		(descr "Capacitor SMD 0402")
		(tags "capacitor SMD 0402")
		(property "Reference" "C49"
			(at -2.975 -0.326 90)
			(layer "F.SilkS")
			(effects
				(font
					(size 0.7 0.7)
					(thickness 0.15)
				)
				(justify right bottom)
			)
		)
		(property "Value" "C_470n_0402"
			(at 0 1.4 90)
			(layer "F.Fab")
			(effects
				(font
					(size 0.7 0.7)
					(thickness 0.15)
				)
				(justify right bottom)
			)
		)
		(property "Datasheet" "https://product.tdk.com/en/search/capacitor/ceramic/mlcc/info?part_no=C1005X5R1E474M050BB"
			(at 0 0 270)
			(layer "F.Fab")
			(hide yes)
			(effects
				(font
					(size 1.27 1.27)
					(thickness 0.15)
				)
			)
		)
		(property "Description" "SMD Multilayer Ceramic Capacitor, 0.47 µF, 25 V, 0402 [1005 Metric], ± 20%, X5R, C"
			(at 0 0 270)
			(layer "F.Fab")
			(hide yes)
			(effects
				(font
					(size 1.27 1.27)
					(thickness 0.15)
				)
			)
		)
		(property "Author" "Antmicro"
			(at -45.401 234.749 0)
			(layer "F.Fab")
			(hide yes)
			(effects
				(font
					(size 1 1)
					(thickness 0.15)
				)
			)
		)
		(property "Dielectric" ""
			(at -45.401 234.749 0)
			(layer "F.Fab")
			(hide yes)
			(effects
				(font
					(size 1 1)
					(thickness 0.15)
				)
			)
		)
		(property "License" "Apache-2.0"
			(at -45.401 234.749 0)
			(layer "F.Fab")
			(hide yes)
			(effects
				(font
					(size 1 1)
					(thickness 0.15)
				)
			)
		)
		(property "MPN" "C1005X5R1E474M050BB"
			(at -45.401 234.749 0)
			(layer "F.Fab")
			(hide yes)
			(effects
				(font
					(size 1 1)
					(thickness 0.15)
				)
			)
		)
		(property "Manufacturer" "TDK"
			(at -45.401 234.749 0)
			(layer "F.Fab")
			(hide yes)
			(effects
				(font
					(size 1 1)
					(thickness 0.15)
				)
			)
		)
		(property "Val" "470n"
			(at -45.401 234.749 0)
			(layer "F.Fab")
			(hide yes)
			(effects
				(font
					(size 1 1)
					(thickness 0.15)
				)
			)
		)
		(property "Voltage" ""
			(at -45.401 234.749 0)
			(layer "F.Fab")
			(hide yes)
			(effects
				(font
					(size 1 1)
					(thickness 0.15)
				)
			)
		)
		(sheetname "/DDR3/")
		(sheetfile "ddr3.kicad_sch")
		(attr smd)
		(fp_rect
			(start -0.925 -0.47)
			(end 0.925 0.47)
			(stroke
				(width 0.05)
				(type default)
			)
			(fill no)
			(layer "F.CrtYd")
		)
		(fp_line
			(start -0.494 0.248)
			(end -0.494 -0.25)
			(stroke
				(width 0.15)
				(type solid)
			)
			(layer "F.Fab")
		)
		(fp_line
			(start 0.504 0.248)
			(end -0.494 0.248)
			(stroke
				(width 0.15)
				(type solid)
			)
			(layer "F.Fab")
		)
		(fp_line
			(start -0.494 -0.25)
			(end 0.504 -0.25)
			(stroke
				(width 0.15)
				(type solid)
			)
			(layer "F.Fab")
		)
		(fp_line
			(start 0.504 -0.25)
			(end 0.504 0.248)
			(stroke
				(width 0.15)
				(type solid)
			)
			(layer "F.Fab")
		)
		(pad "1" smd roundrect
			(at -0.48 0 270)
			(size 0.59 0.64)
			(layers "F.Cu" "F.Mask" "F.Paste")
			(roundrect_rratio 0.25)
			(net 1 "GND")
			(pintype "passive")
		)
		(pad "2" smd roundrect
			(at 0.48 0 270)
			(size 0.59 0.64)
			(layers "F.Cu" "F.Mask" "F.Paste")
			(roundrect_rratio 0.25)
			(net 3 "VCC1V35")
			(pintype "passive")
		)
	)
	(footprint "antmicro-footprints:C_0402_1005Metric"
		(layer "F.Cu")
		(at 100.175 157.475)
		(descr "Capacitor SMD 0402")
		(tags "capacitor SMD 0402")
		(property "Reference" "C1"
			(at -2.275 0.325 0)
			(layer "F.SilkS")
			(effects
				(font
					(size 0.7 0.7)
					(thickness 0.15)
				)
				(justify left bottom)
			)
		)
		(property "Value" "C_1n_0402"
			(at 0 1.4 0)
			(layer "F.Fab")
			(effects
				(font
					(size 0.7 0.7)
					(thickness 0.15)
				)
				(justify left bottom)
			)
		)
		(property "Datasheet" "https://www.murata.com/products/productdetail?partno=GRM1555C1H102JA01%23"
			(at 0 0 0)
			(layer "F.Fab")
			(hide yes)
			(effects
				(font
					(size 1.27 1.27)
					(thickness 0.15)
				)
			)
		)
		(property "Description" "SMD Multilayer Ceramic Capacitor, 1000 pF, 50 V, 0402 [1005 Metric], ± 5%, C0G / NP0, GRM Series"
			(at 0 0 0)
			(layer "F.Fab")
			(hide yes)
			(effects
				(font
					(size 1.27 1.27)
					(thickness 0.15)
				)
			)
		)
		(property "Author" "Antmicro"
			(at 0 0 0)
			(layer "F.Fab")
			(hide yes)
			(effects
				(font
					(size 1 1)
					(thickness 0.15)
				)
			)
		)
		(property "Dielectric" "C0G"
			(at 0 0 0)
			(layer "F.Fab")
			(hide yes)
			(effects
				(font
					(size 1 1)
					(thickness 0.15)
				)
			)
		)
		(property "License" "Apache-2.0"
			(at 0 0 0)
			(layer "F.Fab")
			(hide yes)
			(effects
				(font
					(size 1 1)
					(thickness 0.15)
				)
			)
		)
		(property "MPN" "GRM1555C1H102JA01D"
			(at 0 0 0)
			(layer "F.Fab")
			(hide yes)
			(effects
				(font
					(size 1 1)
					(thickness 0.15)
				)
			)
		)
		(property "Manufacturer" "Murata"
			(at 0 0 0)
			(layer "F.Fab")
			(hide yes)
			(effects
				(font
					(size 1 1)
					(thickness 0.15)
				)
			)
		)
		(property "Val" "1n"
			(at 0 0 0)
			(layer "F.Fab")
			(hide yes)
			(effects
				(font
					(size 1 1)
					(thickness 0.15)
				)
			)
		)
		(property "Voltage" "50V"
			(at 0 0 0)
			(layer "F.Fab")
			(hide yes)
			(effects
				(font
					(size 1 1)
					(thickness 0.15)
				)
			)
		)
		(sheetname "/DDR3/")
		(sheetfile "ddr3.kicad_sch")
		(attr smd)
		(fp_rect
			(start -0.925 -0.47)
			(end 0.925 0.47)
			(stroke
				(width 0.05)
				(type default)
			)
			(fill no)
			(layer "F.CrtYd")
		)
		(fp_line
			(start -0.494 -0.25)
			(end 0.504 -0.25)
			(stroke
				(width 0.15)
				(type solid)
			)
			(layer "F.Fab")
		)
		(fp_line
			(start -0.494 0.248)
			(end -0.494 -0.25)
			(stroke
				(width 0.15)
				(type solid)
			)
			(layer "F.Fab")
		)
		(fp_line
			(start 0.504 -0.25)
			(end 0.504 0.248)
			(stroke
				(width 0.15)
				(type solid)
			)
			(layer "F.Fab")
		)
		(fp_line
			(start 0.504 0.248)
			(end -0.494 0.248)
			(stroke
				(width 0.15)
				(type solid)
			)
			(layer "F.Fab")
		)
		(pad "1" smd roundrect
			(at -0.48 0)
			(size 0.59 0.64)
			(layers "F.Cu" "F.Mask" "F.Paste")
			(roundrect_rratio 0.25)
			(net 1 "GND")
			(pintype "passive")
		)
		(pad "2" smd roundrect
			(at 0.48 0)
			(size 0.59 0.64)
			(layers "F.Cu" "F.Mask" "F.Paste")
			(roundrect_rratio 0.25)
			(net 9 "Net-(U8-REFIN)")
			(pintype "passive")
		)
	)
	(footprint "antmicro-footprints:LED_0603_1608Metric_G"
		(layer "F.Cu")
		(at 67.466 86.265 180)
		(descr "LED SMD 0603 Green")
		(tags "LED SMD 0603 Green")
		(property "Reference" "D9"
			(at -2.834 -0.435 0)
			(layer "F.SilkS")
			(effects
				(font
					(size 0.7 0.7)
					(thickness 0.15)
				)
				(justify right bottom)
			)
		)
		(property "Value" "LED_G_0603_LG_L29K-G2J1-24-Z"
			(at 0 1.6 0)
			(layer "F.Fab")
			(effects
				(font
					(size 0.7 0.7)
					(thickness 0.15)
				)
				(justify right bottom)
			)
		)
		(property "Datasheet" "https://look.ams-osram.com/m/19ee86b3ae0ee95b/original/LG-L29K.pdf"
			(at 0 0 180)
			(layer "F.Fab")
			(hide yes)
			(effects
				(font
					(size 1.27 1.27)
					(thickness 0.15)
				)
			)
		)
		(property "Description" "LED, Green, SMD, 0603, 20 mA, 1.7 V, 570 nm"
			(at 0 0 180)
			(layer "F.Fab")
			(hide yes)
			(effects
				(font
					(size 1.27 1.27)
					(thickness 0.15)
				)
			)
		)
		(property "Author" "Antmicro"
			(at 134.932 172.53 0)
			(layer "F.Fab")
			(hide yes)
			(effects
				(font
					(size 1 1)
					(thickness 0.15)
				)
			)
		)
		(property "Color" "Green"
			(at 134.932 172.53 0)
			(layer "F.Fab")
			(hide yes)
			(effects
				(font
					(size 1 1)
					(thickness 0.15)
				)
			)
		)
		(property "License" "Apache-2.0"
			(at 134.932 172.53 0)
			(layer "F.Fab")
			(hide yes)
			(effects
				(font
					(size 1 1)
					(thickness 0.15)
				)
			)
		)
		(property "MPN" "LG L29K-G2J1-24-Z"
			(at 134.932 172.53 0)
			(layer "F.Fab")
			(hide yes)
			(effects
				(font
					(size 1 1)
					(thickness 0.15)
				)
			)
		)
		(property "Manufacturer" "OSRAM"
			(at 134.932 172.53 0)
			(layer "F.Fab")
			(hide yes)
			(effects
				(font
					(size 1 1)
					(thickness 0.15)
				)
			)
		)
		(sheetname "/FPGA banks 34-35 & CFG/")
		(sheetfile "fpga-banks-34-25-cfg.kicad_sch")
		(attr smd)
		(fp_line
			(start 0.22 0.35)
			(end -0.22 0.35)
			(stroke
				(width 0.15)
				(type solid)
			)
			(layer "F.SilkS")
		)
		(fp_line
			(start 0.22 -0.35)
			(end -0.22 -0.35)
			(stroke
				(width 0.15)
				(type solid)
			)
			(layer "F.SilkS")
		)
		(fp_line
			(start 0.105328 0.201008)
			(end 0.105328 -0.198992)
			(stroke
				(width 0.1)
				(type solid)
			)
			(layer "F.SilkS")
		)
		(fp_line
			(start 0.105328 0.201008)
			(end -0.094672 0.001008)
			(stroke
				(width 0.1)
				(type solid)
			)
			(layer "F.SilkS")
		)
		(fp_line
			(start 0.105328 0.001008)
			(end 0.24 0.001)
			(stroke
				(width 0.1)
				(type solid)
			)
			(layer "F.SilkS")
		)
		(fp_line
			(start -0.094672 0.201008)
			(end -0.094672 -0.198992)
			(stroke
				(width 0.1)
				(type solid)
			)
			(layer "F.SilkS")
		)
		(fp_line
			(start -0.094672 0.001008)
			(end 0.105328 -0.198992)
			(stroke
				(width 0.1)
				(type solid)
			)
			(layer "F.SilkS")
		)
		(fp_line
			(start -0.094672 0.001008)
			(end -0.24 0.001008)
			(stroke
				(width 0.1)
				(type solid)
			)
			(layer "F.SilkS")
		)
		(fp_line
			(start -1.18 -0.319)
			(end -1.18 0.321)
			(stroke
				(width 0.15)
				(type solid)
			)
			(layer "F.SilkS")
		)
		(fp_rect
			(start 1.25 0.65)
			(end -1.25 -0.65)
			(stroke
				(width 0.05)
				(type solid)
			)
			(fill no)
			(layer "F.CrtYd")
		)
		(fp_line
			(start 0.599 0)
			(end 0.201 0)
			(stroke
				(width 0.15)
				(type solid)
			)
			(layer "F.Fab")
		)
		(fp_line
			(start 0.201 0.2)
			(end 0.201 0)
			(stroke
				(width 0.15)
				(type solid)
			)
			(layer "F.Fab")
		)
		(fp_line
			(start 0.201 0)
			(end 0.201 -0.202)
			(stroke
				(width 0.15)
				(type solid)
			)
			(layer "F.Fab")
		)
		(fp_line
			(start 0.201 -0.202)
			(end -0.101 0)
			(stroke
				(width 0.15)
				(type solid)
			)
			(layer "F.Fab")
		)
		(fp_line
			(start -0.101 0)
			(end 0.201 0.2)
			(stroke
				(width 0.15)
				(type solid)
			)
			(layer "F.Fab")
		)
		(fp_line
			(start -0.199 0.2)
			(end -0.199 0.1)
			(stroke
				(width 0.15)
				(type solid)
			)
			(layer "F.Fab")
		)
		(fp_line
			(start -0.199 0)
			(end -0.597 0)
			(stroke
				(width 0.15)
				(type solid)
			)
			(layer "F.Fab")
		)
		(fp_line
			(start -0.199 -0.202)
			(end -0.199 0.1)
			(stroke
				(width 0.15)
				(type solid)
			)
			(layer "F.Fab")
		)
		(fp_rect
			(start 0.848 0.4)
			(end -0.85 -0.402)
			(stroke
				(width 0.15)
				(type solid)
			)
			(fill no)
			(layer "F.Fab")
		)
		(pad "1" smd roundrect
			(at -0.7 0)
			(size 0.8 1)
			(layers "F.Cu" "F.Mask" "F.Paste")
			(roundrect_rratio 0.2)
			(net 225 "Net-(D9-C)")
			(pinfunction "C")
			(pintype "passive")
		)
		(pad "2" smd roundrect
			(at 0.7 0)
			(size 0.8 1)
			(layers "F.Cu" "F.Mask" "F.Paste")
			(roundrect_rratio 0.2)
			(net 279 "Net-(D9-A)")
			(pinfunction "A")
			(pintype "passive")
		)
	)
	(footprint "antmicro-footprints:R_0402_1005Metric"
		(layer "F.Cu")
		(at 74.74 162.06 -90)
		(descr "Resistor SMD 0402")
		(tags "resistor SMD 0402")
		(property "Reference" "R45"
			(at -2.16 -8.36 90)
			(layer "F.SilkS")
			(effects
				(font
					(size 0.7 0.7)
					(thickness 0.15)
				)
				(justify right bottom)
			)
		)
		(property "Value" "R_357k_0402"
			(at 0 1.4 90)
			(layer "F.Fab")
			(effects
				(font
					(size 0.7 0.7)
					(thickness 0.15)
				)
				(justify right bottom)
			)
		)
		(property "Datasheet" "https://www.bourns.com/docs/product-datasheets/cr.pdf"
			(at 0 0 270)
			(layer "F.Fab")
			(hide yes)
			(effects
				(font
					(size 1.27 1.27)
					(thickness 0.15)
				)
			)
		)
		(property "Description" "SMD Chip Resistor"
			(at 0 0 270)
			(layer "F.Fab")
			(hide yes)
			(effects
				(font
					(size 1.27 1.27)
					(thickness 0.15)
				)
			)
		)
		(property "Author" "Antmicro"
			(at -87.32 236.8 0)
			(layer "F.Fab")
			(hide yes)
			(effects
				(font
					(size 1 1)
					(thickness 0.15)
				)
			)
		)
		(property "License" "Apache-2.0"
			(at -87.32 236.8 0)
			(layer "F.Fab")
			(hide yes)
			(effects
				(font
					(size 1 1)
					(thickness 0.15)
				)
			)
		)
		(property "MPN" "CR0402-FX-3573GLF"
			(at -87.32 236.8 0)
			(layer "F.Fab")
			(hide yes)
			(effects
				(font
					(size 1 1)
					(thickness 0.15)
				)
			)
		)
		(property "Manufacturer" "Bourns"
			(at -87.32 236.8 0)
			(layer "F.Fab")
			(hide yes)
			(effects
				(font
					(size 1 1)
					(thickness 0.15)
				)
			)
		)
		(property "Tolerance" "1%"
			(at -87.32 236.8 0)
			(layer "F.Fab")
			(hide yes)
			(effects
				(font
					(size 1 1)
					(thickness 0.15)
				)
			)
		)
		(property "Val" "357k"
			(at -87.32 236.8 0)
			(layer "F.Fab")
			(hide yes)
			(effects
				(font
					(size 1 1)
					(thickness 0.15)
				)
			)
		)
		(sheetname "/Interfaces/")
		(sheetfile "interfaces.kicad_sch")
		(attr smd)
		(fp_rect
			(start -0.925 -0.47)
			(end 0.925 0.47)
			(stroke
				(width 0.05)
				(type default)
			)
			(fill no)
			(layer "F.CrtYd")
		)
		(fp_rect
			(start -0.5 -0.25)
			(end 0.5 0.25)
			(stroke
				(width 0.15)
				(type solid)
			)
			(fill no)
			(layer "F.Fab")
		)
		(pad "1" smd roundrect
			(at -0.48 0 270)
			(size 0.59 0.64)
			(layers "F.Cu" "F.Mask" "F.Paste")
			(roundrect_rratio 0.25)
			(net 2 "VCC3V3")
			(pintype "passive")
		)
		(pad "2" smd roundrect
			(at 0.48 0 270)
			(size 0.59 0.64)
			(layers "F.Cu" "F.Mask" "F.Paste")
			(roundrect_rratio 0.25)
			(net 168 "I3C[0]_SDA_3V3")
			(pintype "passive")
		)
	)
	(footprint "antmicro-footprints:R_0402_1005Metric"
		(layer "F.Cu")
		(at 73.74 162.06 -90)
		(descr "Resistor SMD 0402")
		(tags "resistor SMD 0402")
		(property "Reference" "R46"
			(at -2.16 -8.36 90)
			(layer "F.SilkS")
			(effects
				(font
					(size 0.7 0.7)
					(thickness 0.15)
				)
				(justify right bottom)
			)
		)
		(property "Value" "R_357k_0402"
			(at 0 1.4 90)
			(layer "F.Fab")
			(effects
				(font
					(size 0.7 0.7)
					(thickness 0.15)
				)
				(justify right bottom)
			)
		)
		(property "Datasheet" "https://www.bourns.com/docs/product-datasheets/cr.pdf"
			(at 0 0 270)
			(layer "F.Fab")
			(hide yes)
			(effects
				(font
					(size 1.27 1.27)
					(thickness 0.15)
				)
			)
		)
		(property "Description" "SMD Chip Resistor"
			(at 0 0 270)
			(layer "F.Fab")
			(hide yes)
			(effects
				(font
					(size 1.27 1.27)
					(thickness 0.15)
				)
			)
		)
		(property "Author" "Antmicro"
			(at -88.32 235.8 0)
			(layer "F.Fab")
			(hide yes)
			(effects
				(font
					(size 1 1)
					(thickness 0.15)
				)
			)
		)
		(property "License" "Apache-2.0"
			(at -88.32 235.8 0)
			(layer "F.Fab")
			(hide yes)
			(effects
				(font
					(size 1 1)
					(thickness 0.15)
				)
			)
		)
		(property "MPN" "CR0402-FX-3573GLF"
			(at -88.32 235.8 0)
			(layer "F.Fab")
			(hide yes)
			(effects
				(font
					(size 1 1)
					(thickness 0.15)
				)
			)
		)
		(property "Manufacturer" "Bourns"
			(at -88.32 235.8 0)
			(layer "F.Fab")
			(hide yes)
			(effects
				(font
					(size 1 1)
					(thickness 0.15)
				)
			)
		)
		(property "Tolerance" "1%"
			(at -88.32 235.8 0)
			(layer "F.Fab")
			(hide yes)
			(effects
				(font
					(size 1 1)
					(thickness 0.15)
				)
			)
		)
		(property "Val" "357k"
			(at -88.32 235.8 0)
			(layer "F.Fab")
			(hide yes)
			(effects
				(font
					(size 1 1)
					(thickness 0.15)
				)
			)
		)
		(sheetname "/Interfaces/")
		(sheetfile "interfaces.kicad_sch")
		(attr smd)
		(fp_rect
			(start -0.925 -0.47)
			(end 0.925 0.47)
			(stroke
				(width 0.05)
				(type default)
			)
			(fill no)
			(layer "F.CrtYd")
		)
		(fp_rect
			(start -0.5 -0.25)
			(end 0.5 0.25)
			(stroke
				(width 0.15)
				(type solid)
			)
			(fill no)
			(layer "F.Fab")
		)
		(pad "1" smd roundrect
			(at -0.48 0 270)
			(size 0.59 0.64)
			(layers "F.Cu" "F.Mask" "F.Paste")
			(roundrect_rratio 0.25)
			(net 2 "VCC3V3")
			(pintype "passive")
		)
		(pad "2" smd roundrect
			(at 0.48 0 270)
			(size 0.59 0.64)
			(layers "F.Cu" "F.Mask" "F.Paste")
			(roundrect_rratio 0.25)
			(net 169 "I3C[0]_SCL_3V3")
			(pintype "passive")
		)
	)
	(footprint "antmicro-footprints:R_0402_1005Metric"
		(layer "F.Cu")
		(at 78.74 162.06 -90)
		(descr "Resistor SMD 0402")
		(tags "resistor SMD 0402")
		(property "Reference" "R49"
			(at -2.16 -8.36 90)
			(layer "F.SilkS")
			(effects
				(font
					(size 0.7 0.7)
					(thickness 0.15)
				)
				(justify right bottom)
			)
		)
		(property "Value" "R_357k_0402"
			(at 0 1.4 90)
			(layer "F.Fab")
			(effects
				(font
					(size 0.7 0.7)
					(thickness 0.15)
				)
				(justify right bottom)
			)
		)
		(property "Datasheet" "https://www.bourns.com/docs/product-datasheets/cr.pdf"
			(at 0 0 270)
			(layer "F.Fab")
			(hide yes)
			(effects
				(font
					(size 1.27 1.27)
					(thickness 0.15)
				)
			)
		)
		(property "Description" "SMD Chip Resistor"
			(at 0 0 270)
			(layer "F.Fab")
			(hide yes)
			(effects
				(font
					(size 1.27 1.27)
					(thickness 0.15)
				)
			)
		)
		(property "Author" "Antmicro"
			(at -83.32 240.8 0)
			(layer "F.Fab")
			(hide yes)
			(effects
				(font
					(size 1 1)
					(thickness 0.15)
				)
			)
		)
		(property "License" "Apache-2.0"
			(at -83.32 240.8 0)
			(layer "F.Fab")
			(hide yes)
			(effects
				(font
					(size 1 1)
					(thickness 0.15)
				)
			)
		)
		(property "MPN" "CR0402-FX-3573GLF"
			(at -83.32 240.8 0)
			(layer "F.Fab")
			(hide yes)
			(effects
				(font
					(size 1 1)
					(thickness 0.15)
				)
			)
		)
		(property "Manufacturer" "Bourns"
			(at -83.32 240.8 0)
			(layer "F.Fab")
			(hide yes)
			(effects
				(font
					(size 1 1)
					(thickness 0.15)
				)
			)
		)
		(property "Tolerance" "1%"
			(at -83.32 240.8 0)
			(layer "F.Fab")
			(hide yes)
			(effects
				(font
					(size 1 1)
					(thickness 0.15)
				)
			)
		)
		(property "Val" "357k"
			(at -83.32 240.8 0)
			(layer "F.Fab")
			(hide yes)
			(effects
				(font
					(size 1 1)
					(thickness 0.15)
				)
			)
		)
		(sheetname "/Interfaces/")
		(sheetfile "interfaces.kicad_sch")
		(attr smd)
		(fp_rect
			(start -0.925 -0.47)
			(end 0.925 0.47)
			(stroke
				(width 0.05)
				(type default)
			)
			(fill no)
			(layer "F.CrtYd")
		)
		(fp_rect
			(start -0.5 -0.25)
			(end 0.5 0.25)
			(stroke
				(width 0.15)
				(type solid)
			)
			(fill no)
			(layer "F.Fab")
		)
		(pad "1" smd roundrect
			(at -0.48 0 270)
			(size 0.59 0.64)
			(layers "F.Cu" "F.Mask" "F.Paste")
			(roundrect_rratio 0.25)
			(net 2 "VCC3V3")
			(pintype "passive")
		)
		(pad "2" smd roundrect
			(at 0.48 0 270)
			(size 0.59 0.64)
			(layers "F.Cu" "F.Mask" "F.Paste")
			(roundrect_rratio 0.25)
			(net 172 "I3C[2]_SDA_3V3")
			(pintype "passive")
		)
	)
	(footprint "antmicro-footprints:R_0402_1005Metric"
		(layer "F.Cu")
		(at 77.74 162.06 -90)
		(descr "Resistor SMD 0402")
		(tags "resistor SMD 0402")
		(property "Reference" "R50"
			(at -2.16 -8.36 90)
			(layer "F.SilkS")
			(effects
				(font
					(size 0.7 0.7)
					(thickness 0.15)
				)
				(justify right bottom)
			)
		)
		(property "Value" "R_357k_0402"
			(at 0 1.4 90)
			(layer "F.Fab")
			(effects
				(font
					(size 0.7 0.7)
					(thickness 0.15)
				)
				(justify right bottom)
			)
		)
		(property "Datasheet" "https://www.bourns.com/docs/product-datasheets/cr.pdf"
			(at 0 0 270)
			(layer "F.Fab")
			(hide yes)
			(effects
				(font
					(size 1.27 1.27)
					(thickness 0.15)
				)
			)
		)
		(property "Description" "SMD Chip Resistor"
			(at 0 0 270)
			(layer "F.Fab")
			(hide yes)
			(effects
				(font
					(size 1.27 1.27)
					(thickness 0.15)
				)
			)
		)
		(property "Author" "Antmicro"
			(at -84.32 239.8 0)
			(layer "F.Fab")
			(hide yes)
			(effects
				(font
					(size 1 1)
					(thickness 0.15)
				)
			)
		)
		(property "License" "Apache-2.0"
			(at -84.32 239.8 0)
			(layer "F.Fab")
			(hide yes)
			(effects
				(font
					(size 1 1)
					(thickness 0.15)
				)
			)
		)
		(property "MPN" "CR0402-FX-3573GLF"
			(at -84.32 239.8 0)
			(layer "F.Fab")
			(hide yes)
			(effects
				(font
					(size 1 1)
					(thickness 0.15)
				)
			)
		)
		(property "Manufacturer" "Bourns"
			(at -84.32 239.8 0)
			(layer "F.Fab")
			(hide yes)
			(effects
				(font
					(size 1 1)
					(thickness 0.15)
				)
			)
		)
		(property "Tolerance" "1%"
			(at -84.32 239.8 0)
			(layer "F.Fab")
			(hide yes)
			(effects
				(font
					(size 1 1)
					(thickness 0.15)
				)
			)
		)
		(property "Val" "357k"
			(at -84.32 239.8 0)
			(layer "F.Fab")
			(hide yes)
			(effects
				(font
					(size 1 1)
					(thickness 0.15)
				)
			)
		)
		(sheetname "/Interfaces/")
		(sheetfile "interfaces.kicad_sch")
		(attr smd)
		(fp_rect
			(start -0.925 -0.47)
			(end 0.925 0.47)
			(stroke
				(width 0.05)
				(type default)
			)
			(fill no)
			(layer "F.CrtYd")
		)
		(fp_rect
			(start -0.5 -0.25)
			(end 0.5 0.25)
			(stroke
				(width 0.15)
				(type solid)
			)
			(fill no)
			(layer "F.Fab")
		)
		(pad "1" smd roundrect
			(at -0.48 0 270)
			(size 0.59 0.64)
			(layers "F.Cu" "F.Mask" "F.Paste")
			(roundrect_rratio 0.25)
			(net 2 "VCC3V3")
			(pintype "passive")
		)
		(pad "2" smd roundrect
			(at 0.48 0 270)
			(size 0.59 0.64)
			(layers "F.Cu" "F.Mask" "F.Paste")
			(roundrect_rratio 0.25)
			(net 173 "I3C[2]_SCL_3V3")
			(pintype "passive")
		)
	)
	(footprint "antmicro-footprints:R_0402_1005Metric"
		(layer "F.Cu")
		(at 80.74 162.06 -90)
		(descr "Resistor SMD 0402")
		(tags "resistor SMD 0402")
		(property "Reference" "R51"
			(at -2.16 -8.36 90)
			(layer "F.SilkS")
			(effects
				(font
					(size 0.7 0.7)
					(thickness 0.15)
				)
				(justify right bottom)
			)
		)
		(property "Value" "R_357k_0402"
			(at 0 1.4 90)
			(layer "F.Fab")
			(effects
				(font
					(size 0.7 0.7)
					(thickness 0.15)
				)
				(justify right bottom)
			)
		)
		(property "Datasheet" "https://www.bourns.com/docs/product-datasheets/cr.pdf"
			(at 0 0 270)
			(layer "F.Fab")
			(hide yes)
			(effects
				(font
					(size 1.27 1.27)
					(thickness 0.15)
				)
			)
		)
		(property "Description" "SMD Chip Resistor"
			(at 0 0 270)
			(layer "F.Fab")
			(hide yes)
			(effects
				(font
					(size 1.27 1.27)
					(thickness 0.15)
				)
			)
		)
		(property "Author" "Antmicro"
			(at -81.32 242.8 0)
			(layer "F.Fab")
			(hide yes)
			(effects
				(font
					(size 1 1)
					(thickness 0.15)
				)
			)
		)
		(property "License" "Apache-2.0"
			(at -81.32 242.8 0)
			(layer "F.Fab")
			(hide yes)
			(effects
				(font
					(size 1 1)
					(thickness 0.15)
				)
			)
		)
		(property "MPN" "CR0402-FX-3573GLF"
			(at -81.32 242.8 0)
			(layer "F.Fab")
			(hide yes)
			(effects
				(font
					(size 1 1)
					(thickness 0.15)
				)
			)
		)
		(property "Manufacturer" "Bourns"
			(at -81.32 242.8 0)
			(layer "F.Fab")
			(hide yes)
			(effects
				(font
					(size 1 1)
					(thickness 0.15)
				)
			)
		)
		(property "Tolerance" "1%"
			(at -81.32 242.8 0)
			(layer "F.Fab")
			(hide yes)
			(effects
				(font
					(size 1 1)
					(thickness 0.15)
				)
			)
		)
		(property "Val" "357k"
			(at -81.32 242.8 0)
			(layer "F.Fab")
			(hide yes)
			(effects
				(font
					(size 1 1)
					(thickness 0.15)
				)
			)
		)
		(sheetname "/Interfaces/")
		(sheetfile "interfaces.kicad_sch")
		(attr smd)
		(fp_rect
			(start -0.925 -0.47)
			(end 0.925 0.47)
			(stroke
				(width 0.05)
				(type default)
			)
			(fill no)
			(layer "F.CrtYd")
		)
		(fp_rect
			(start -0.5 -0.25)
			(end 0.5 0.25)
			(stroke
				(width 0.15)
				(type solid)
			)
			(fill no)
			(layer "F.Fab")
		)
		(pad "1" smd roundrect
			(at -0.48 0 270)
			(size 0.59 0.64)
			(layers "F.Cu" "F.Mask" "F.Paste")
			(roundrect_rratio 0.25)
			(net 2 "VCC3V3")
			(pintype "passive")
		)
		(pad "2" smd roundrect
			(at 0.48 0 270)
			(size 0.59 0.64)
			(layers "F.Cu" "F.Mask" "F.Paste")
			(roundrect_rratio 0.25)
			(net 174 "I3C[3]_SDA_3V3")
			(pintype "passive")
		)
	)
	(footprint "antmicro-footprints:R_0402_1005Metric"
		(layer "F.Cu")
		(at 79.74 162.06 -90)
		(descr "Resistor SMD 0402")
		(tags "resistor SMD 0402")
		(property "Reference" "R52"
			(at -2.16 -8.36 90)
			(layer "F.SilkS")
			(effects
				(font
					(size 0.7 0.7)
					(thickness 0.15)
				)
				(justify right bottom)
			)
		)
		(property "Value" "R_357k_0402"
			(at 0 1.4 90)
			(layer "F.Fab")
			(effects
				(font
					(size 0.7 0.7)
					(thickness 0.15)
				)
				(justify right bottom)
			)
		)
		(property "Datasheet" "https://www.bourns.com/docs/product-datasheets/cr.pdf"
			(at 0 0 270)
			(layer "F.Fab")
			(hide yes)
			(effects
				(font
					(size 1.27 1.27)
					(thickness 0.15)
				)
			)
		)
		(property "Description" "SMD Chip Resistor"
			(at 0 0 270)
			(layer "F.Fab")
			(hide yes)
			(effects
				(font
					(size 1.27 1.27)
					(thickness 0.15)
				)
			)
		)
		(property "Author" "Antmicro"
			(at -82.32 241.8 0)
			(layer "F.Fab")
			(hide yes)
			(effects
				(font
					(size 1 1)
					(thickness 0.15)
				)
			)
		)
		(property "License" "Apache-2.0"
			(at -82.32 241.8 0)
			(layer "F.Fab")
			(hide yes)
			(effects
				(font
					(size 1 1)
					(thickness 0.15)
				)
			)
		)
		(property "MPN" "CR0402-FX-3573GLF"
			(at -82.32 241.8 0)
			(layer "F.Fab")
			(hide yes)
			(effects
				(font
					(size 1 1)
					(thickness 0.15)
				)
			)
		)
		(property "Manufacturer" "Bourns"
			(at -82.32 241.8 0)
			(layer "F.Fab")
			(hide yes)
			(effects
				(font
					(size 1 1)
					(thickness 0.15)
				)
			)
		)
		(property "Tolerance" "1%"
			(at -82.32 241.8 0)
			(layer "F.Fab")
			(hide yes)
			(effects
				(font
					(size 1 1)
					(thickness 0.15)
				)
			)
		)
		(property "Val" "357k"
			(at -82.32 241.8 0)
			(layer "F.Fab")
			(hide yes)
			(effects
				(font
					(size 1 1)
					(thickness 0.15)
				)
			)
		)
		(sheetname "/Interfaces/")
		(sheetfile "interfaces.kicad_sch")
		(attr smd)
		(fp_rect
			(start -0.925 -0.47)
			(end 0.925 0.47)
			(stroke
				(width 0.05)
				(type default)
			)
			(fill no)
			(layer "F.CrtYd")
		)
		(fp_rect
			(start -0.5 -0.25)
			(end 0.5 0.25)
			(stroke
				(width 0.15)
				(type solid)
			)
			(fill no)
			(layer "F.Fab")
		)
		(pad "1" smd roundrect
			(at -0.48 0 270)
			(size 0.59 0.64)
			(layers "F.Cu" "F.Mask" "F.Paste")
			(roundrect_rratio 0.25)
			(net 2 "VCC3V3")
			(pintype "passive")
		)
		(pad "2" smd roundrect
			(at 0.48 0 270)
			(size 0.59 0.64)
			(layers "F.Cu" "F.Mask" "F.Paste")
			(roundrect_rratio 0.25)
			(net 175 "I3C[3]_SCL_3V3")
			(pintype "passive")
		)
	)
	(footprint "antmicro-footprints:R_0402_1005Metric"
		(layer "F.Cu")
		(at 90.545 81.825 -90)
		(descr "Resistor SMD 0402")
		(tags "resistor SMD 0402")
		(property "Reference" "R77"
			(at -1.125 -4.455 90)
			(layer "F.SilkS")
			(effects
				(font
					(size 0.7 0.7)
					(thickness 0.15)
				)
				(justify right bottom)
			)
		)
		(property "Value" "R_66k5_0402"
			(at 0 1.4 90)
			(layer "F.Fab")
			(effects
				(font
					(size 0.7 0.7)
					(thickness 0.15)
				)
				(justify right bottom)
			)
		)
		(property "Datasheet" "https://www.bourns.com/docs/product-datasheets/cr.pdf"
			(at 0 0 270)
			(layer "F.Fab")
			(hide yes)
			(effects
				(font
					(size 1.27 1.27)
					(thickness 0.15)
				)
			)
		)
		(property "Description" "SMD Chip Resistor"
			(at 0 0 270)
			(layer "F.Fab")
			(hide yes)
			(effects
				(font
					(size 1.27 1.27)
					(thickness 0.15)
				)
			)
		)
		(property "Author" "Antmicro"
			(at 8.72 172.37 0)
			(layer "F.Fab")
			(hide yes)
			(effects
				(font
					(size 1 1)
					(thickness 0.15)
				)
			)
		)
		(property "License" "Apache-2.0"
			(at 8.72 172.37 0)
			(layer "F.Fab")
			(hide yes)
			(effects
				(font
					(size 1 1)
					(thickness 0.15)
				)
			)
		)
		(property "MPN" "CR0402-FX-6652GLF"
			(at 8.72 172.37 0)
			(layer "F.Fab")
			(hide yes)
			(effects
				(font
					(size 1 1)
					(thickness 0.15)
				)
			)
		)
		(property "Manufacturer" "Bourns"
			(at 8.72 172.37 0)
			(layer "F.Fab")
			(hide yes)
			(effects
				(font
					(size 1 1)
					(thickness 0.15)
				)
			)
		)
		(property "Tolerance" "1%"
			(at 8.72 172.37 0)
			(layer "F.Fab")
			(hide yes)
			(effects
				(font
					(size 1 1)
					(thickness 0.15)
				)
			)
		)
		(property "Val" "66k5"
			(at 8.72 172.37 0)
			(layer "F.Fab")
			(hide yes)
			(effects
				(font
					(size 1 1)
					(thickness 0.15)
				)
			)
		)
		(sheetname "/Power supply/")
		(sheetfile "power-supply.kicad_sch")
		(attr smd)
		(fp_rect
			(start -0.925 -0.47)
			(end 0.925 0.47)
			(stroke
				(width 0.05)
				(type default)
			)
			(fill no)
			(layer "F.CrtYd")
		)
		(fp_rect
			(start -0.5 -0.25)
			(end 0.5 0.25)
			(stroke
				(width 0.15)
				(type solid)
			)
			(fill no)
			(layer "F.Fab")
		)
		(pad "1" smd roundrect
			(at -0.48 0 270)
			(size 0.59 0.64)
			(layers "F.Cu" "F.Mask" "F.Paste")
			(roundrect_rratio 0.25)
			(net 276 "Net-(C81-Pad2)")
			(pintype "passive")
		)
		(pad "2" smd roundrect
			(at 0.48 0 270)
			(size 0.59 0.64)
			(layers "F.Cu" "F.Mask" "F.Paste")
			(roundrect_rratio 0.25)
			(net 195 "Net-(U12-FB)")
			(pintype "passive")
		)
	)
	(footprint "antmicro-footprints:R_0402_1005Metric"
		(layer "F.Cu")
		(at 110.474 166.675 90)
		(descr "Resistor SMD 0402")
		(tags "resistor SMD 0402")
		(property "Reference" "R136"
			(at -3.725 0.426 90)
			(layer "F.SilkS")
			(effects
				(font
					(size 0.7 0.7)
					(thickness 0.15)
				)
				(justify left bottom)
			)
		)
		(property "Value" "R_0R_0402"
			(at 0 1.4 90)
			(layer "F.Fab")
			(effects
				(font
					(size 0.7 0.7)
					(thickness 0.15)
				)
				(justify left bottom)
			)
		)
		(property "Datasheet" "https://industrial.panasonic.com/cdbs/www-data/pdf/RDA0000/AOA0000C301.pdf"
			(at 0 0 90)
			(layer "F.Fab")
			(hide yes)
			(effects
				(font
					(size 1.27 1.27)
					(thickness 0.15)
				)
			)
		)
		(property "Description" "SMD Chip Resistor, Jumper, 0 ohm, 100 mW, 0402 [1005 Metric], Thick Film, General Purpose"
			(at 0 0 90)
			(layer "F.Fab")
			(hide yes)
			(effects
				(font
					(size 1.27 1.27)
					(thickness 0.15)
				)
			)
		)
		(property "Author" "Antmicro"
			(at 277.149 56.201 0)
			(layer "F.Fab")
			(hide yes)
			(effects
				(font
					(size 1 1)
					(thickness 0.15)
				)
			)
		)
		(property "Current" "1A"
			(at 277.149 56.201 0)
			(layer "F.Fab")
			(hide yes)
			(effects
				(font
					(size 1 1)
					(thickness 0.15)
				)
			)
		)
		(property "License" "Apache-2.0"
			(at 277.149 56.201 0)
			(layer "F.Fab")
			(hide yes)
			(effects
				(font
					(size 1 1)
					(thickness 0.15)
				)
			)
		)
		(property "MPN" "ERJ2GE0R00X"
			(at 277.149 56.201 0)
			(layer "F.Fab")
			(hide yes)
			(effects
				(font
					(size 1 1)
					(thickness 0.15)
				)
			)
		)
		(property "Manufacturer" "Panasonic"
			(at 277.149 56.201 0)
			(layer "F.Fab")
			(hide yes)
			(effects
				(font
					(size 1 1)
					(thickness 0.15)
				)
			)
		)
		(property "Tolerance" "~"
			(at 277.149 56.201 0)
			(layer "F.Fab")
			(hide yes)
			(effects
				(font
					(size 1 1)
					(thickness 0.15)
				)
			)
		)
		(property "Val" "0R"
			(at 277.149 56.201 0)
			(layer "F.Fab")
			(hide yes)
			(effects
				(font
					(size 1 1)
					(thickness 0.15)
				)
			)
		)
		(sheetname "/Edge connector/")
		(sheetfile "edge-connector.kicad_sch")
		(attr smd)
		(fp_rect
			(start -0.925 -0.47)
			(end 0.925 0.47)
			(stroke
				(width 0.05)
				(type default)
			)
			(fill no)
			(layer "F.CrtYd")
		)
		(fp_rect
			(start -0.5 -0.25)
			(end 0.5 0.25)
			(stroke
				(width 0.15)
				(type solid)
			)
			(fill no)
			(layer "F.Fab")
		)
		(pad "1" smd roundrect
			(at -0.48 0 90)
			(size 0.59 0.64)
			(layers "F.Cu" "F.Mask" "F.Paste")
			(roundrect_rratio 0.25)
			(net 694 "Net-(J9-PadB35)")
			(pintype "passive")
		)
		(pad "2" smd roundrect
			(at 0.48 0 90)
			(size 0.59 0.64)
			(layers "F.Cu" "F.Mask" "F.Paste")
			(roundrect_rratio 0.25)
			(net 91 "RSVD2")
			(pintype "passive")
		)
	)
	(footprint "antmicro-footprints:R_0402_1005Metric"
		(layer "F.Cu")
		(at 109.374 166.675 -90)
		(descr "Resistor SMD 0402")
		(tags "resistor SMD 0402")
		(property "Reference" "R137"
			(at 0.925 -0.426 90)
			(layer "F.SilkS")
			(effects
				(font
					(size 0.7 0.7)
					(thickness 0.15)
				)
				(justify right bottom)
			)
		)
		(property "Value" "R_0R_0402"
			(at 0 1.4 90)
			(layer "F.Fab")
			(effects
				(font
					(size 0.7 0.7)
					(thickness 0.15)
				)
				(justify right bottom)
			)
		)
		(property "Datasheet" "https://industrial.panasonic.com/cdbs/www-data/pdf/RDA0000/AOA0000C301.pdf"
			(at 0 0 270)
			(layer "F.Fab")
			(hide yes)
			(effects
				(font
					(size 1.27 1.27)
					(thickness 0.15)
				)
			)
		)
		(property "Description" "SMD Chip Resistor, Jumper, 0 ohm, 100 mW, 0402 [1005 Metric], Thick Film, General Purpose"
			(at 0 0 270)
			(layer "F.Fab")
			(hide yes)
			(effects
				(font
					(size 1.27 1.27)
					(thickness 0.15)
				)
			)
		)
		(property "Author" "Antmicro"
			(at -57.301 276.049 0)
			(layer "F.Fab")
			(hide yes)
			(effects
				(font
					(size 1 1)
					(thickness 0.15)
				)
			)
		)
		(property "Current" "1A"
			(at -57.301 276.049 0)
			(layer "F.Fab")
			(hide yes)
			(effects
				(font
					(size 1 1)
					(thickness 0.15)
				)
			)
		)
		(property "License" "Apache-2.0"
			(at -57.301 276.049 0)
			(layer "F.Fab")
			(hide yes)
			(effects
				(font
					(size 1 1)
					(thickness 0.15)
				)
			)
		)
		(property "MPN" "ERJ2GE0R00X"
			(at -57.301 276.049 0)
			(layer "F.Fab")
			(hide yes)
			(effects
				(font
					(size 1 1)
					(thickness 0.15)
				)
			)
		)
		(property "Manufacturer" "Panasonic"
			(at -57.301 276.049 0)
			(layer "F.Fab")
			(hide yes)
			(effects
				(font
					(size 1 1)
					(thickness 0.15)
				)
			)
		)
		(property "Tolerance" "~"
			(at -57.301 276.049 0)
			(layer "F.Fab")
			(hide yes)
			(effects
				(font
					(size 1 1)
					(thickness 0.15)
				)
			)
		)
		(property "Val" "0R"
			(at -57.301 276.049 0)
			(layer "F.Fab")
			(hide yes)
			(effects
				(font
					(size 1 1)
					(thickness 0.15)
				)
			)
		)
		(sheetname "/Edge connector/")
		(sheetfile "edge-connector.kicad_sch")
		(attr smd)
		(fp_rect
			(start -0.925 -0.47)
			(end 0.925 0.47)
			(stroke
				(width 0.05)
				(type default)
			)
			(fill no)
			(layer "F.CrtYd")
		)
		(fp_rect
			(start -0.5 -0.25)
			(end 0.5 0.25)
			(stroke
				(width 0.15)
				(type solid)
			)
			(fill no)
			(layer "F.Fab")
		)
		(pad "1" smd roundrect
			(at -0.48 0 270)
			(size 0.59 0.64)
			(layers "F.Cu" "F.Mask" "F.Paste")
			(roundrect_rratio 0.25)
			(net 91 "RSVD2")
			(pintype "passive")
		)
		(pad "2" smd roundrect
			(at 0.48 0 270)
			(size 0.59 0.64)
			(layers "F.Cu" "F.Mask" "F.Paste")
			(roundrect_rratio 0.25)
			(net 87 "SGPIO0_CLK")
			(pintype "passive")
		)
	)
	(footprint "antmicro-footprints:TP_SMD_1mm"
		(layer "F.Cu")
		(at 64.335 84.240799)
		(property "Reference" "TP2"
			(at -2.635 0.259201 0)
			(layer "F.SilkS")
			(effects
				(font
					(size 0.7 0.7)
					(thickness 0.15)
				)
				(justify left bottom)
			)
		)
		(property "Value" "TP_1mm_SMD"
			(at 0 1.4 0)
			(layer "F.Fab")
			(effects
				(font
					(size 0.7 0.7)
					(thickness 0.15)
				)
				(justify left bottom)
			)
		)
		(property "Description" "Test point 1mm SMD"
			(at 0 0 0)
			(layer "F.Fab")
			(hide yes)
			(effects
				(font
					(size 1.27 1.27)
					(thickness 0.15)
				)
			)
		)
		(property "Author" "Antmicro"
			(at 0 0 0)
			(layer "F.Fab")
			(hide yes)
			(effects
				(font
					(size 1 1)
					(thickness 0.15)
				)
			)
		)
		(property "License" "Apache-2.0"
			(at 0 0 0)
			(layer "F.Fab")
			(hide yes)
			(effects
				(font
					(size 1 1)
					(thickness 0.15)
				)
			)
		)
		(property "MPN" ""
			(at 0 0 0)
			(layer "F.Fab")
			(hide yes)
			(effects
				(font
					(size 1 1)
					(thickness 0.15)
				)
			)
		)
		(property "Manufacturer" ""
			(at 0 0 0)
			(layer "F.Fab")
			(hide yes)
			(effects
				(font
					(size 1 1)
					(thickness 0.15)
				)
			)
		)
		(sheetname "/FPGA banks 34-35 & CFG/")
		(sheetfile "fpga-banks-34-25-cfg.kicad_sch")
		(attr exclude_from_pos_files exclude_from_bom)
		(fp_circle
			(center 0 0)
			(end 0.6 0)
			(stroke
				(width 0.05)
				(type default)
			)
			(fill no)
			(layer "F.CrtYd")
		)
		(pad "1" smd circle
			(at 0 0)
			(size 1 1)
			(layers "F.Cu" "F.Mask")
			(net 220 "DONE")
			(pinfunction "1")
			(pintype "passive")
		)
	)
	(footprint "antmicro-footprints:TP_SMD_1mm"
		(layer "F.Cu")
		(at 64.335 86.312899)
		(property "Reference" "TP5"
			(at -2.635 0.487101 0)
			(layer "F.SilkS")
			(effects
				(font
					(size 0.7 0.7)
					(thickness 0.15)
				)
				(justify left bottom)
			)
		)
		(property "Value" "TP_1mm_SMD"
			(at 0 1.4 0)
			(layer "F.Fab")
			(effects
				(font
					(size 0.7 0.7)
					(thickness 0.15)
				)
				(justify left bottom)
			)
		)
		(property "Description" "Test point 1mm SMD"
			(at 0 0 0)
			(layer "F.Fab")
			(hide yes)
			(effects
				(font
					(size 1.27 1.27)
					(thickness 0.15)
				)
			)
		)
		(property "Author" "Antmicro"
			(at 0 0 0)
			(layer "F.Fab")
			(hide yes)
			(effects
				(font
					(size 1 1)
					(thickness 0.15)
				)
			)
		)
		(property "License" "Apache-2.0"
			(at 0 0 0)
			(layer "F.Fab")
			(hide yes)
			(effects
				(font
					(size 1 1)
					(thickness 0.15)
				)
			)
		)
		(property "MPN" ""
			(at 0 0 0)
			(layer "F.Fab")
			(hide yes)
			(effects
				(font
					(size 1 1)
					(thickness 0.15)
				)
			)
		)
		(property "Manufacturer" ""
			(at 0 0 0)
			(layer "F.Fab")
			(hide yes)
			(effects
				(font
					(size 1 1)
					(thickness 0.15)
				)
			)
		)
		(sheetname "/FPGA banks 34-35 & CFG/")
		(sheetfile "fpga-banks-34-25-cfg.kicad_sch")
		(attr exclude_from_pos_files exclude_from_bom)
		(fp_circle
			(center 0 0)
			(end 0.6 0)
			(stroke
				(width 0.05)
				(type default)
			)
			(fill no)
			(layer "F.CrtYd")
		)
		(pad "1" smd circle
			(at 0 0)
			(size 1 1)
			(layers "F.Cu" "F.Mask")
			(net 222 "INIT")
			(pinfunction "1")
			(pintype "passive")
		)
	)
	(footprint "antmicro-footprints:TP_SMD_1mm"
		(layer "F.Cu")
		(at 64.335 88.385)
		(property "Reference" "TP6"
			(at -2.635 0.415 0)
			(layer "F.SilkS")
			(effects
				(font
					(size 0.7 0.7)
					(thickness 0.15)
				)
				(justify left bottom)
			)
		)
		(property "Value" "TP_1mm_SMD"
			(at 0 1.4 0)
			(layer "F.Fab")
			(effects
				(font
					(size 0.7 0.7)
					(thickness 0.15)
				)
				(justify left bottom)
			)
		)
		(property "Description" "Test point 1mm SMD"
			(at 0 0 0)
			(layer "F.Fab")
			(hide yes)
			(effects
				(font
					(size 1.27 1.27)
					(thickness 0.15)
				)
			)
		)
		(property "Author" "Antmicro"
			(at 0 0 0)
			(layer "F.Fab")
			(hide yes)
			(effects
				(font
					(size 1 1)
					(thickness 0.15)
				)
			)
		)
		(property "License" "Apache-2.0"
			(at 0 0 0)
			(layer "F.Fab")
			(hide yes)
			(effects
				(font
					(size 1 1)
					(thickness 0.15)
				)
			)
		)
		(property "MPN" ""
			(at 0 0 0)
			(layer "F.Fab")
			(hide yes)
			(effects
				(font
					(size 1 1)
					(thickness 0.15)
				)
			)
		)
		(property "Manufacturer" ""
			(at 0 0 0)
			(layer "F.Fab")
			(hide yes)
			(effects
				(font
					(size 1 1)
					(thickness 0.15)
				)
			)
		)
		(sheetname "/FPGA banks 34-35 & CFG/")
		(sheetfile "fpga-banks-34-25-cfg.kicad_sch")
		(attr exclude_from_pos_files exclude_from_bom)
		(fp_circle
			(center 0 0)
			(end 0.6 0)
			(stroke
				(width 0.05)
				(type default)
			)
			(fill no)
			(layer "F.CrtYd")
		)
		(pad "1" smd circle
			(at 0 0)
			(size 1 1)
			(layers "F.Cu" "F.Mask")
			(net 221 "PROGRAM")
			(pinfunction "1")
			(pintype "passive")
		)
	)
	(footprint "antmicro-footprints:TP_SMD_1mm"
		(layer "F.Cu")
		(at 142.575 161.675)
		(property "Reference" "TP13"
			(at 0.525 0.325 0)
			(layer "F.SilkS")
			(effects
				(font
					(size 0.7 0.7)
					(thickness 0.15)
				)
				(justify left bottom)
			)
		)
		(property "Value" "TP_1mm_SMD"
			(at 0 1.4 0)
			(layer "F.Fab")
			(effects
				(font
					(size 0.7 0.7)
					(thickness 0.15)
				)
				(justify left bottom)
			)
		)
		(property "Description" "Test point 1mm SMD"
			(at 0 0 0)
			(layer "F.Fab")
			(hide yes)
			(effects
				(font
					(size 1.27 1.27)
					(thickness 0.15)
				)
			)
		)
		(property "Author" "Antmicro"
			(at 0 0 0)
			(layer "F.Fab")
			(hide yes)
			(effects
				(font
					(size 1 1)
					(thickness 0.15)
				)
			)
		)
		(property "License" "Apache-2.0"
			(at 0 0 0)
			(layer "F.Fab")
			(hide yes)
			(effects
				(font
					(size 1 1)
					(thickness 0.15)
				)
			)
		)
		(property "MPN" ""
			(at 0 0 0)
			(layer "F.Fab")
			(hide yes)
			(effects
				(font
					(size 1 1)
					(thickness 0.15)
				)
			)
		)
		(property "Manufacturer" ""
			(at 0 0 0)
			(layer "F.Fab")
			(hide yes)
			(effects
				(font
					(size 1 1)
					(thickness 0.15)
				)
			)
		)
		(sheetname "/PCIe-connector/")
		(sheetfile "pcie-conn.kicad_sch")
		(attr exclude_from_pos_files exclude_from_bom)
		(fp_circle
			(center 0 0)
			(end 0.6 0)
			(stroke
				(width 0.05)
				(type default)
			)
			(fill no)
			(layer "F.CrtYd")
		)
		(pad "1" smd circle
			(at 0 0)
			(size 1 1)
			(layers "F.Cu" "F.Mask")
			(net 269 "Net-(J2-~{CLKREQ})")
			(pinfunction "1")
			(pintype "passive")
		)
	)
	(footprint "antmicro-footprints:TP_SMD_1mm"
		(layer "F.Cu")
		(at 142.575 160.2258)
		(property "Reference" "TP14"
			(at 0.525 0.325 0)
			(layer "F.SilkS")
			(effects
				(font
					(size 0.7 0.7)
					(thickness 0.15)
				)
				(justify left bottom)
			)
		)
		(property "Value" "TP_1mm_SMD"
			(at 0 1.4 0)
			(layer "F.Fab")
			(effects
				(font
					(size 0.7 0.7)
					(thickness 0.15)
				)
				(justify left bottom)
			)
		)
		(property "Description" "Test point 1mm SMD"
			(at 0 0 0)
			(layer "F.Fab")
			(hide yes)
			(effects
				(font
					(size 1.27 1.27)
					(thickness 0.15)
				)
			)
		)
		(property "Author" "Antmicro"
			(at 0 0 0)
			(layer "F.Fab")
			(hide yes)
			(effects
				(font
					(size 1 1)
					(thickness 0.15)
				)
			)
		)
		(property "License" "Apache-2.0"
			(at 0 0 0)
			(layer "F.Fab")
			(hide yes)
			(effects
				(font
					(size 1 1)
					(thickness 0.15)
				)
			)
		)
		(property "MPN" ""
			(at 0 0 0)
			(layer "F.Fab")
			(hide yes)
			(effects
				(font
					(size 1 1)
					(thickness 0.15)
				)
			)
		)
		(property "Manufacturer" ""
			(at 0 0 0)
			(layer "F.Fab")
			(hide yes)
			(effects
				(font
					(size 1 1)
					(thickness 0.15)
				)
			)
		)
		(sheetname "/PCIe-connector/")
		(sheetfile "pcie-conn.kicad_sch")
		(attr exclude_from_pos_files exclude_from_bom)
		(fp_circle
			(center 0 0)
			(end 0.6 0)
			(stroke
				(width 0.05)
				(type default)
			)
			(fill no)
			(layer "F.CrtYd")
		)
		(pad "1" smd circle
			(at 0 0)
			(size 1 1)
			(layers "F.Cu" "F.Mask")
			(net 118 "PRSNT1_N")
			(pinfunction "1")
			(pintype "passive")
		)
	)
	(footprint "antmicro-footprints:R_0402_1005Metric"
		(layer "F.Cu")
		(at 71.415 167.865 -90)
		(descr "Resistor SMD 0402")
		(tags "resistor SMD 0402")
		(property "Reference" "R114"
			(at 0.835 -0.385 90)
			(layer "F.SilkS")
			(effects
				(font
					(size 0.7 0.7)
					(thickness 0.15)
				)
				(justify right bottom)
			)
		)
		(property "Value" "R_0R_0402"
			(at 0 1.4 90)
			(layer "F.Fab")
			(effects
				(font
					(size 0.7 0.7)
					(thickness 0.15)
				)
				(justify right bottom)
			)
		)
		(property "Datasheet" "https://industrial.panasonic.com/cdbs/www-data/pdf/RDA0000/AOA0000C301.pdf"
			(at 0 0 270)
			(layer "F.Fab")
			(hide yes)
			(effects
				(font
					(size 1.27 1.27)
					(thickness 0.15)
				)
			)
		)
		(property "Description" "SMD Chip Resistor, Jumper, 0 ohm, 100 mW, 0402 [1005 Metric], Thick Film, General Purpose"
			(at 0 0 270)
			(layer "F.Fab")
			(hide yes)
			(effects
				(font
					(size 1.27 1.27)
					(thickness 0.15)
				)
			)
		)
		(property "Author" "Antmicro"
			(at -96.45 239.28 0)
			(layer "F.Fab")
			(hide yes)
			(effects
				(font
					(size 1 1)
					(thickness 0.15)
				)
			)
		)
		(property "Current" "1A"
			(at -96.45 239.28 0)
			(layer "F.Fab")
			(hide yes)
			(effects
				(font
					(size 1 1)
					(thickness 0.15)
				)
			)
		)
		(property "License" "Apache-2.0"
			(at -96.45 239.28 0)
			(layer "F.Fab")
			(hide yes)
			(effects
				(font
					(size 1 1)
					(thickness 0.15)
				)
			)
		)
		(property "MPN" "ERJ2GE0R00X"
			(at -96.45 239.28 0)
			(layer "F.Fab")
			(hide yes)
			(effects
				(font
					(size 1 1)
					(thickness 0.15)
				)
			)
		)
		(property "Manufacturer" "Panasonic"
			(at -96.45 239.28 0)
			(layer "F.Fab")
			(hide yes)
			(effects
				(font
					(size 1 1)
					(thickness 0.15)
				)
			)
		)
		(property "Tolerance" "~"
			(at -96.45 239.28 0)
			(layer "F.Fab")
			(hide yes)
			(effects
				(font
					(size 1 1)
					(thickness 0.15)
				)
			)
		)
		(property "Val" "0R"
			(at -96.45 239.28 0)
			(layer "F.Fab")
			(hide yes)
			(effects
				(font
					(size 1 1)
					(thickness 0.15)
				)
			)
		)
		(sheetname "/Edge connector/")
		(sheetfile "edge-connector.kicad_sch")
		(attr smd)
		(fp_rect
			(start -0.925 -0.47)
			(end 0.925 0.47)
			(stroke
				(width 0.05)
				(type default)
			)
			(fill no)
			(layer "F.CrtYd")
		)
		(fp_rect
			(start -0.5 -0.25)
			(end 0.5 0.25)
			(stroke
				(width 0.15)
				(type solid)
			)
			(fill no)
			(layer "F.Fab")
		)
		(pad "1" smd roundrect
			(at -0.48 0 270)
			(size 0.59 0.64)
			(layers "F.Cu" "F.Mask" "F.Paste")
			(roundrect_rratio 0.25)
			(net 521 "PRSNT0_N_R")
			(pintype "passive")
		)
		(pad "2" smd roundrect
			(at 0.48 0 270)
			(size 0.59 0.64)
			(layers "F.Cu" "F.Mask" "F.Paste")
			(roundrect_rratio 0.25)
			(net 243 "/Edge connector/PRSNT0_N")
			(pintype "passive")
		)
	)
	(footprint "antmicro-footprints:LED_0603_1608Metric_G"
		(layer "F.Cu")
		(at 67.466 84.215 180)
		(descr "LED SMD 0603 Green")
		(tags "LED SMD 0603 Green")
		(property "Reference" "D10"
			(at -3.434 -0.385 0)
			(layer "F.SilkS")
			(effects
				(font
					(size 0.7 0.7)
					(thickness 0.15)
				)
				(justify right bottom)
			)
		)
		(property "Value" "LED_G_0603_LG_L29K-G2J1-24-Z"
			(at 0 1.6 0)
			(layer "F.Fab")
			(effects
				(font
					(size 0.7 0.7)
					(thickness 0.15)
				)
				(justify right bottom)
			)
		)
		(property "Datasheet" "https://look.ams-osram.com/m/19ee86b3ae0ee95b/original/LG-L29K.pdf"
			(at 0 0 180)
			(layer "F.Fab")
			(hide yes)
			(effects
				(font
					(size 1.27 1.27)
					(thickness 0.15)
				)
			)
		)
		(property "Description" "LED, Green, SMD, 0603, 20 mA, 1.7 V, 570 nm"
			(at 0 0 180)
			(layer "F.Fab")
			(hide yes)
			(effects
				(font
					(size 1.27 1.27)
					(thickness 0.15)
				)
			)
		)
		(property "Author" "Antmicro"
			(at 134.932 168.43 0)
			(layer "F.Fab")
			(hide yes)
			(effects
				(font
					(size 1 1)
					(thickness 0.15)
				)
			)
		)
		(property "Color" "Green"
			(at 134.932 168.43 0)
			(layer "F.Fab")
			(hide yes)
			(effects
				(font
					(size 1 1)
					(thickness 0.15)
				)
			)
		)
		(property "License" "Apache-2.0"
			(at 134.932 168.43 0)
			(layer "F.Fab")
			(hide yes)
			(effects
				(font
					(size 1 1)
					(thickness 0.15)
				)
			)
		)
		(property "MPN" "LG L29K-G2J1-24-Z"
			(at 134.932 168.43 0)
			(layer "F.Fab")
			(hide yes)
			(effects
				(font
					(size 1 1)
					(thickness 0.15)
				)
			)
		)
		(property "Manufacturer" "OSRAM"
			(at 134.932 168.43 0)
			(layer "F.Fab")
			(hide yes)
			(effects
				(font
					(size 1 1)
					(thickness 0.15)
				)
			)
		)
		(sheetname "/FPGA banks 34-35 & CFG/")
		(sheetfile "fpga-banks-34-25-cfg.kicad_sch")
		(attr smd)
		(fp_line
			(start 0.22 0.35)
			(end -0.22 0.35)
			(stroke
				(width 0.15)
				(type solid)
			)
			(layer "F.SilkS")
		)
		(fp_line
			(start 0.22 -0.35)
			(end -0.22 -0.35)
			(stroke
				(width 0.15)
				(type solid)
			)
			(layer "F.SilkS")
		)
		(fp_line
			(start 0.105328 0.201008)
			(end 0.105328 -0.198992)
			(stroke
				(width 0.1)
				(type solid)
			)
			(layer "F.SilkS")
		)
		(fp_line
			(start 0.105328 0.201008)
			(end -0.094672 0.001008)
			(stroke
				(width 0.1)
				(type solid)
			)
			(layer "F.SilkS")
		)
		(fp_line
			(start 0.105328 0.001008)
			(end 0.24 0.001)
			(stroke
				(width 0.1)
				(type solid)
			)
			(layer "F.SilkS")
		)
		(fp_line
			(start -0.094672 0.201008)
			(end -0.094672 -0.198992)
			(stroke
				(width 0.1)
				(type solid)
			)
			(layer "F.SilkS")
		)
		(fp_line
			(start -0.094672 0.001008)
			(end 0.105328 -0.198992)
			(stroke
				(width 0.1)
				(type solid)
			)
			(layer "F.SilkS")
		)
		(fp_line
			(start -0.094672 0.001008)
			(end -0.24 0.001008)
			(stroke
				(width 0.1)
				(type solid)
			)
			(layer "F.SilkS")
		)
		(fp_line
			(start -1.18 -0.319)
			(end -1.18 0.321)
			(stroke
				(width 0.15)
				(type solid)
			)
			(layer "F.SilkS")
		)
		(fp_rect
			(start 1.25 0.65)
			(end -1.25 -0.65)
			(stroke
				(width 0.05)
				(type solid)
			)
			(fill no)
			(layer "F.CrtYd")
		)
		(fp_line
			(start 0.599 0)
			(end 0.201 0)
			(stroke
				(width 0.15)
				(type solid)
			)
			(layer "F.Fab")
		)
		(fp_line
			(start 0.201 0.2)
			(end 0.201 0)
			(stroke
				(width 0.15)
				(type solid)
			)
			(layer "F.Fab")
		)
		(fp_line
			(start 0.201 0)
			(end 0.201 -0.202)
			(stroke
				(width 0.15)
				(type solid)
			)
			(layer "F.Fab")
		)
		(fp_line
			(start 0.201 -0.202)
			(end -0.101 0)
			(stroke
				(width 0.15)
				(type solid)
			)
			(layer "F.Fab")
		)
		(fp_line
			(start -0.101 0)
			(end 0.201 0.2)
			(stroke
				(width 0.15)
				(type solid)
			)
			(layer "F.Fab")
		)
		(fp_line
			(start -0.199 0.2)
			(end -0.199 0.1)
			(stroke
				(width 0.15)
				(type solid)
			)
			(layer "F.Fab")
		)
		(fp_line
			(start -0.199 0)
			(end -0.597 0)
			(stroke
				(width 0.15)
				(type solid)
			)
			(layer "F.Fab")
		)
		(fp_line
			(start -0.199 -0.202)
			(end -0.199 0.1)
			(stroke
				(width 0.15)
				(type solid)
			)
			(layer "F.Fab")
		)
		(fp_rect
			(start 0.848 0.4)
			(end -0.85 -0.402)
			(stroke
				(width 0.15)
				(type solid)
			)
			(fill no)
			(layer "F.Fab")
		)
		(pad "1" smd roundrect
			(at -0.7 0)
			(size 0.8 1)
			(layers "F.Cu" "F.Mask" "F.Paste")
			(roundrect_rratio 0.2)
			(net 281 "Net-(D10-C)")
			(pinfunction "C")
			(pintype "passive")
		)
		(pad "2" smd roundrect
			(at 0.7 0)
			(size 0.8 1)
			(layers "F.Cu" "F.Mask" "F.Paste")
			(roundrect_rratio 0.2)
			(net 283 "Net-(D10-A)")
			(pinfunction "A")
			(pintype "passive")
		)
	)
	(footprint "antmicro-footprints:C_0402_1005Metric"
		(layer "F.Cu")
		(at 103.374 154.675 90)
		(descr "Capacitor SMD 0402")
		(tags "capacitor SMD 0402")
		(property "Reference" "C52"
			(at -3.425 -8.474 90)
			(layer "F.SilkS")
			(effects
				(font
					(size 0.7 0.7)
					(thickness 0.15)
				)
				(justify left bottom)
			)
		)
		(property "Value" "C_470n_0402"
			(at 0 1.4 90)
			(layer "F.Fab")
			(effects
				(font
					(size 0.7 0.7)
					(thickness 0.15)
				)
				(justify left bottom)
			)
		)
		(property "Datasheet" "https://product.tdk.com/en/search/capacitor/ceramic/mlcc/info?part_no=C1005X5R1E474M050BB"
			(at 0 0 90)
			(layer "F.Fab")
			(hide yes)
			(effects
				(font
					(size 1.27 1.27)
					(thickness 0.15)
				)
			)
		)
		(property "Description" "SMD Multilayer Ceramic Capacitor, 0.47 µF, 25 V, 0402 [1005 Metric], ± 20%, X5R, C"
			(at 0 0 90)
			(layer "F.Fab")
			(hide yes)
			(effects
				(font
					(size 1.27 1.27)
					(thickness 0.15)
				)
			)
		)
		(property "Author" "Antmicro"
			(at 258.049 51.301 0)
			(layer "F.Fab")
			(hide yes)
			(effects
				(font
					(size 1 1)
					(thickness 0.15)
				)
			)
		)
		(property "Dielectric" ""
			(at 258.049 51.301 0)
			(layer "F.Fab")
			(hide yes)
			(effects
				(font
					(size 1 1)
					(thickness 0.15)
				)
			)
		)
		(property "License" "Apache-2.0"
			(at 258.049 51.301 0)
			(layer "F.Fab")
			(hide yes)
			(effects
				(font
					(size 1 1)
					(thickness 0.15)
				)
			)
		)
		(property "MPN" "C1005X5R1E474M050BB"
			(at 258.049 51.301 0)
			(layer "F.Fab")
			(hide yes)
			(effects
				(font
					(size 1 1)
					(thickness 0.15)
				)
			)
		)
		(property "Manufacturer" "TDK"
			(at 258.049 51.301 0)
			(layer "F.Fab")
			(hide yes)
			(effects
				(font
					(size 1 1)
					(thickness 0.15)
				)
			)
		)
		(property "Val" "470n"
			(at 258.049 51.301 0)
			(layer "F.Fab")
			(hide yes)
			(effects
				(font
					(size 1 1)
					(thickness 0.15)
				)
			)
		)
		(property "Voltage" ""
			(at 258.049 51.301 0)
			(layer "F.Fab")
			(hide yes)
			(effects
				(font
					(size 1 1)
					(thickness 0.15)
				)
			)
		)
		(sheetname "/DDR3/")
		(sheetfile "ddr3.kicad_sch")
		(attr smd)
		(fp_rect
			(start -0.925 -0.47)
			(end 0.925 0.47)
			(stroke
				(width 0.05)
				(type default)
			)
			(fill no)
			(layer "F.CrtYd")
		)
		(fp_line
			(start 0.504 -0.25)
			(end 0.504 0.248)
			(stroke
				(width 0.15)
				(type solid)
			)
			(layer "F.Fab")
		)
		(fp_line
			(start -0.494 -0.25)
			(end 0.504 -0.25)
			(stroke
				(width 0.15)
				(type solid)
			)
			(layer "F.Fab")
		)
		(fp_line
			(start 0.504 0.248)
			(end -0.494 0.248)
			(stroke
				(width 0.15)
				(type solid)
			)
			(layer "F.Fab")
		)
		(fp_line
			(start -0.494 0.248)
			(end -0.494 -0.25)
			(stroke
				(width 0.15)
				(type solid)
			)
			(layer "F.Fab")
		)
		(pad "1" smd roundrect
			(at -0.48 0 90)
			(size 0.59 0.64)
			(layers "F.Cu" "F.Mask" "F.Paste")
			(roundrect_rratio 0.25)
			(net 1 "GND")
			(pintype "passive")
		)
		(pad "2" smd roundrect
			(at 0.48 0 90)
			(size 0.59 0.64)
			(layers "F.Cu" "F.Mask" "F.Paste")
			(roundrect_rratio 0.25)
			(net 3 "VCC1V35")
			(pintype "passive")
		)
	)
	(footprint "antmicro-footprints:C_0402_1005Metric"
		(layer "F.Cu")
		(at 101.774 140.075 -90)
		(descr "Capacitor SMD 0402")
		(tags "capacitor SMD 0402")
		(property "Reference" "C56"
			(at -2.975 -0.326 90)
			(layer "F.SilkS")
			(effects
				(font
					(size 0.7 0.7)
					(thickness 0.15)
				)
				(justify right bottom)
			)
		)
		(property "Value" "C_470n_0402"
			(at 0 1.4 90)
			(layer "F.Fab")
			(effects
				(font
					(size 0.7 0.7)
					(thickness 0.15)
				)
				(justify right bottom)
			)
		)
		(property "Datasheet" "https://product.tdk.com/en/search/capacitor/ceramic/mlcc/info?part_no=C1005X5R1E474M050BB"
			(at 0 0 270)
			(layer "F.Fab")
			(hide yes)
			(effects
				(font
					(size 1.27 1.27)
					(thickness 0.15)
				)
			)
		)
		(property "Description" "SMD Multilayer Ceramic Capacitor, 0.47 µF, 25 V, 0402 [1005 Metric], ± 20%, X5R, C"
			(at 0 0 270)
			(layer "F.Fab")
			(hide yes)
			(effects
				(font
					(size 1.27 1.27)
					(thickness 0.15)
				)
			)
		)
		(property "Author" "Antmicro"
			(at -38.301 241.849 0)
			(layer "F.Fab")
			(hide yes)
			(effects
				(font
					(size 1 1)
					(thickness 0.15)
				)
			)
		)
		(property "Dielectric" ""
			(at -38.301 241.849 0)
			(layer "F.Fab")
			(hide yes)
			(effects
				(font
					(size 1 1)
					(thickness 0.15)
				)
			)
		)
		(property "License" "Apache-2.0"
			(at -38.301 241.849 0)
			(layer "F.Fab")
			(hide yes)
			(effects
				(font
					(size 1 1)
					(thickness 0.15)
				)
			)
		)
		(property "MPN" "C1005X5R1E474M050BB"
			(at -38.301 241.849 0)
			(layer "F.Fab")
			(hide yes)
			(effects
				(font
					(size 1 1)
					(thickness 0.15)
				)
			)
		)
		(property "Manufacturer" "TDK"
			(at -38.301 241.849 0)
			(layer "F.Fab")
			(hide yes)
			(effects
				(font
					(size 1 1)
					(thickness 0.15)
				)
			)
		)
		(property "Val" "470n"
			(at -38.301 241.849 0)
			(layer "F.Fab")
			(hide yes)
			(effects
				(font
					(size 1 1)
					(thickness 0.15)
				)
			)
		)
		(property "Voltage" ""
			(at -38.301 241.849 0)
			(layer "F.Fab")
			(hide yes)
			(effects
				(font
					(size 1 1)
					(thickness 0.15)
				)
			)
		)
		(sheetname "/DDR3/")
		(sheetfile "ddr3.kicad_sch")
		(attr smd)
		(fp_rect
			(start -0.925 -0.47)
			(end 0.925 0.47)
			(stroke
				(width 0.05)
				(type default)
			)
			(fill no)
			(layer "F.CrtYd")
		)
		(fp_line
			(start -0.494 0.248)
			(end -0.494 -0.25)
			(stroke
				(width 0.15)
				(type solid)
			)
			(layer "F.Fab")
		)
		(fp_line
			(start 0.504 0.248)
			(end -0.494 0.248)
			(stroke
				(width 0.15)
				(type solid)
			)
			(layer "F.Fab")
		)
		(fp_line
			(start -0.494 -0.25)
			(end 0.504 -0.25)
			(stroke
				(width 0.15)
				(type solid)
			)
			(layer "F.Fab")
		)
		(fp_line
			(start 0.504 -0.25)
			(end 0.504 0.248)
			(stroke
				(width 0.15)
				(type solid)
			)
			(layer "F.Fab")
		)
		(pad "1" smd roundrect
			(at -0.48 0 270)
			(size 0.59 0.64)
			(layers "F.Cu" "F.Mask" "F.Paste")
			(roundrect_rratio 0.25)
			(net 1 "GND")
			(pintype "passive")
		)
		(pad "2" smd roundrect
			(at 0.48 0 270)
			(size 0.59 0.64)
			(layers "F.Cu" "F.Mask" "F.Paste")
			(roundrect_rratio 0.25)
			(net 3 "VCC1V35")
			(pintype "passive")
		)
	)
	(footprint "antmicro-footprints:C_0402_1005Metric"
		(layer "F.Cu")
		(at 98.774 140.075 -90)
		(descr "Capacitor SMD 0402")
		(tags "capacitor SMD 0402")
		(property "Reference" "C59"
			(at -2.975 -0.326 90)
			(layer "F.SilkS")
			(effects
				(font
					(size 0.7 0.7)
					(thickness 0.15)
				)
				(justify right bottom)
			)
		)
		(property "Value" "C_470n_0402"
			(at 0 1.4 90)
			(layer "F.Fab")
			(effects
				(font
					(size 0.7 0.7)
					(thickness 0.15)
				)
				(justify right bottom)
			)
		)
		(property "Datasheet" "https://product.tdk.com/en/search/capacitor/ceramic/mlcc/info?part_no=C1005X5R1E474M050BB"
			(at 0 0 270)
			(layer "F.Fab")
			(hide yes)
			(effects
				(font
					(size 1.27 1.27)
					(thickness 0.15)
				)
			)
		)
		(property "Description" "SMD Multilayer Ceramic Capacitor, 0.47 µF, 25 V, 0402 [1005 Metric], ± 20%, X5R, C"
			(at 0 0 270)
			(layer "F.Fab")
			(hide yes)
			(effects
				(font
					(size 1.27 1.27)
					(thickness 0.15)
				)
			)
		)
		(property "Author" "Antmicro"
			(at -41.301 238.849 0)
			(layer "F.Fab")
			(hide yes)
			(effects
				(font
					(size 1 1)
					(thickness 0.15)
				)
			)
		)
		(property "Dielectric" ""
			(at -41.301 238.849 0)
			(layer "F.Fab")
			(hide yes)
			(effects
				(font
					(size 1 1)
					(thickness 0.15)
				)
			)
		)
		(property "License" "Apache-2.0"
			(at -41.301 238.849 0)
			(layer "F.Fab")
			(hide yes)
			(effects
				(font
					(size 1 1)
					(thickness 0.15)
				)
			)
		)
		(property "MPN" "C1005X5R1E474M050BB"
			(at -41.301 238.849 0)
			(layer "F.Fab")
			(hide yes)
			(effects
				(font
					(size 1 1)
					(thickness 0.15)
				)
			)
		)
		(property "Manufacturer" "TDK"
			(at -41.301 238.849 0)
			(layer "F.Fab")
			(hide yes)
			(effects
				(font
					(size 1 1)
					(thickness 0.15)
				)
			)
		)
		(property "Val" "470n"
			(at -41.301 238.849 0)
			(layer "F.Fab")
			(hide yes)
			(effects
				(font
					(size 1 1)
					(thickness 0.15)
				)
			)
		)
		(property "Voltage" ""
			(at -41.301 238.849 0)
			(layer "F.Fab")
			(hide yes)
			(effects
				(font
					(size 1 1)
					(thickness 0.15)
				)
			)
		)
		(sheetname "/DDR3/")
		(sheetfile "ddr3.kicad_sch")
		(attr smd)
		(fp_rect
			(start -0.925 -0.47)
			(end 0.925 0.47)
			(stroke
				(width 0.05)
				(type default)
			)
			(fill no)
			(layer "F.CrtYd")
		)
		(fp_line
			(start -0.494 0.248)
			(end -0.494 -0.25)
			(stroke
				(width 0.15)
				(type solid)
			)
			(layer "F.Fab")
		)
		(fp_line
			(start 0.504 0.248)
			(end -0.494 0.248)
			(stroke
				(width 0.15)
				(type solid)
			)
			(layer "F.Fab")
		)
		(fp_line
			(start -0.494 -0.25)
			(end 0.504 -0.25)
			(stroke
				(width 0.15)
				(type solid)
			)
			(layer "F.Fab")
		)
		(fp_line
			(start 0.504 -0.25)
			(end 0.504 0.248)
			(stroke
				(width 0.15)
				(type solid)
			)
			(layer "F.Fab")
		)
		(pad "1" smd roundrect
			(at -0.48 0 270)
			(size 0.59 0.64)
			(layers "F.Cu" "F.Mask" "F.Paste")
			(roundrect_rratio 0.25)
			(net 1 "GND")
			(pintype "passive")
		)
		(pad "2" smd roundrect
			(at 0.48 0 270)
			(size 0.59 0.64)
			(layers "F.Cu" "F.Mask" "F.Paste")
			(roundrect_rratio 0.25)
			(net 3 "VCC1V35")
			(pintype "passive")
		)
	)
	(footprint "antmicro-footprints:C_0402_1005Metric"
		(layer "F.Cu")
		(at 97.774 140.075 -90)
		(descr "Capacitor SMD 0402")
		(tags "capacitor SMD 0402")
		(property "Reference" "C53"
			(at -2.975 -0.326 90)
			(layer "F.SilkS")
			(effects
				(font
					(size 0.7 0.7)
					(thickness 0.15)
				)
				(justify right bottom)
			)
		)
		(property "Value" "C_470n_0402"
			(at 0 1.4 90)
			(layer "F.Fab")
			(effects
				(font
					(size 0.7 0.7)
					(thickness 0.15)
				)
				(justify right bottom)
			)
		)
		(property "Datasheet" "https://product.tdk.com/en/search/capacitor/ceramic/mlcc/info?part_no=C1005X5R1E474M050BB"
			(at 0 0 270)
			(layer "F.Fab")
			(hide yes)
			(effects
				(font
					(size 1.27 1.27)
					(thickness 0.15)
				)
			)
		)
		(property "Description" "SMD Multilayer Ceramic Capacitor, 0.47 µF, 25 V, 0402 [1005 Metric], ± 20%, X5R, C"
			(at 0 0 270)
			(layer "F.Fab")
			(hide yes)
			(effects
				(font
					(size 1.27 1.27)
					(thickness 0.15)
				)
			)
		)
		(property "Author" "Antmicro"
			(at -42.301 237.849 0)
			(layer "F.Fab")
			(hide yes)
			(effects
				(font
					(size 1 1)
					(thickness 0.15)
				)
			)
		)
		(property "Dielectric" ""
			(at -42.301 237.849 0)
			(layer "F.Fab")
			(hide yes)
			(effects
				(font
					(size 1 1)
					(thickness 0.15)
				)
			)
		)
		(property "License" "Apache-2.0"
			(at -42.301 237.849 0)
			(layer "F.Fab")
			(hide yes)
			(effects
				(font
					(size 1 1)
					(thickness 0.15)
				)
			)
		)
		(property "MPN" "C1005X5R1E474M050BB"
			(at -42.301 237.849 0)
			(layer "F.Fab")
			(hide yes)
			(effects
				(font
					(size 1 1)
					(thickness 0.15)
				)
			)
		)
		(property "Manufacturer" "TDK"
			(at -42.301 237.849 0)
			(layer "F.Fab")
			(hide yes)
			(effects
				(font
					(size 1 1)
					(thickness 0.15)
				)
			)
		)
		(property "Val" "470n"
			(at -42.301 237.849 0)
			(layer "F.Fab")
			(hide yes)
			(effects
				(font
					(size 1 1)
					(thickness 0.15)
				)
			)
		)
		(property "Voltage" ""
			(at -42.301 237.849 0)
			(layer "F.Fab")
			(hide yes)
			(effects
				(font
					(size 1 1)
					(thickness 0.15)
				)
			)
		)
		(sheetname "/DDR3/")
		(sheetfile "ddr3.kicad_sch")
		(attr smd)
		(fp_rect
			(start -0.925 -0.47)
			(end 0.925 0.47)
			(stroke
				(width 0.05)
				(type default)
			)
			(fill no)
			(layer "F.CrtYd")
		)
		(fp_line
			(start -0.494 0.248)
			(end -0.494 -0.25)
			(stroke
				(width 0.15)
				(type solid)
			)
			(layer "F.Fab")
		)
		(fp_line
			(start 0.504 0.248)
			(end -0.494 0.248)
			(stroke
				(width 0.15)
				(type solid)
			)
			(layer "F.Fab")
		)
		(fp_line
			(start -0.494 -0.25)
			(end 0.504 -0.25)
			(stroke
				(width 0.15)
				(type solid)
			)
			(layer "F.Fab")
		)
		(fp_line
			(start 0.504 -0.25)
			(end 0.504 0.248)
			(stroke
				(width 0.15)
				(type solid)
			)
			(layer "F.Fab")
		)
		(pad "1" smd roundrect
			(at -0.48 0 270)
			(size 0.59 0.64)
			(layers "F.Cu" "F.Mask" "F.Paste")
			(roundrect_rratio 0.25)
			(net 1 "GND")
			(pintype "passive")
		)
		(pad "2" smd roundrect
			(at 0.48 0 270)
			(size 0.59 0.64)
			(layers "F.Cu" "F.Mask" "F.Paste")
			(roundrect_rratio 0.25)
			(net 3 "VCC1V35")
			(pintype "passive")
		)
	)
	(footprint "antmicro-footprints:C_0402_1005Metric"
		(layer "F.Cu")
		(at 95.674 140.075 -90)
		(descr "Capacitor SMD 0402")
		(tags "capacitor SMD 0402")
		(property "Reference" "C60"
			(at -2.975 -0.326 90)
			(layer "F.SilkS")
			(effects
				(font
					(size 0.7 0.7)
					(thickness 0.15)
				)
				(justify right bottom)
			)
		)
		(property "Value" "C_470n_0402"
			(at 0 1.4 90)
			(layer "F.Fab")
			(effects
				(font
					(size 0.7 0.7)
					(thickness 0.15)
				)
				(justify right bottom)
			)
		)
		(property "Datasheet" "https://product.tdk.com/en/search/capacitor/ceramic/mlcc/info?part_no=C1005X5R1E474M050BB"
			(at 0 0 270)
			(layer "F.Fab")
			(hide yes)
			(effects
				(font
					(size 1.27 1.27)
					(thickness 0.15)
				)
			)
		)
		(property "Description" "SMD Multilayer Ceramic Capacitor, 0.47 µF, 25 V, 0402 [1005 Metric], ± 20%, X5R, C"
			(at 0 0 270)
			(layer "F.Fab")
			(hide yes)
			(effects
				(font
					(size 1.27 1.27)
					(thickness 0.15)
				)
			)
		)
		(property "Author" "Antmicro"
			(at -44.401 235.749 0)
			(layer "F.Fab")
			(hide yes)
			(effects
				(font
					(size 1 1)
					(thickness 0.15)
				)
			)
		)
		(property "Dielectric" ""
			(at -44.401 235.749 0)
			(layer "F.Fab")
			(hide yes)
			(effects
				(font
					(size 1 1)
					(thickness 0.15)
				)
			)
		)
		(property "License" "Apache-2.0"
			(at -44.401 235.749 0)
			(layer "F.Fab")
			(hide yes)
			(effects
				(font
					(size 1 1)
					(thickness 0.15)
				)
			)
		)
		(property "MPN" "C1005X5R1E474M050BB"
			(at -44.401 235.749 0)
			(layer "F.Fab")
			(hide yes)
			(effects
				(font
					(size 1 1)
					(thickness 0.15)
				)
			)
		)
		(property "Manufacturer" "TDK"
			(at -44.401 235.749 0)
			(layer "F.Fab")
			(hide yes)
			(effects
				(font
					(size 1 1)
					(thickness 0.15)
				)
			)
		)
		(property "Val" "470n"
			(at -44.401 235.749 0)
			(layer "F.Fab")
			(hide yes)
			(effects
				(font
					(size 1 1)
					(thickness 0.15)
				)
			)
		)
		(property "Voltage" ""
			(at -44.401 235.749 0)
			(layer "F.Fab")
			(hide yes)
			(effects
				(font
					(size 1 1)
					(thickness 0.15)
				)
			)
		)
		(sheetname "/DDR3/")
		(sheetfile "ddr3.kicad_sch")
		(attr smd)
		(fp_rect
			(start -0.925 -0.47)
			(end 0.925 0.47)
			(stroke
				(width 0.05)
				(type default)
			)
			(fill no)
			(layer "F.CrtYd")
		)
		(fp_line
			(start -0.494 0.248)
			(end -0.494 -0.25)
			(stroke
				(width 0.15)
				(type solid)
			)
			(layer "F.Fab")
		)
		(fp_line
			(start 0.504 0.248)
			(end -0.494 0.248)
			(stroke
				(width 0.15)
				(type solid)
			)
			(layer "F.Fab")
		)
		(fp_line
			(start -0.494 -0.25)
			(end 0.504 -0.25)
			(stroke
				(width 0.15)
				(type solid)
			)
			(layer "F.Fab")
		)
		(fp_line
			(start 0.504 -0.25)
			(end 0.504 0.248)
			(stroke
				(width 0.15)
				(type solid)
			)
			(layer "F.Fab")
		)
		(pad "1" smd roundrect
			(at -0.48 0 270)
			(size 0.59 0.64)
			(layers "F.Cu" "F.Mask" "F.Paste")
			(roundrect_rratio 0.25)
			(net 1 "GND")
			(pintype "passive")
		)
		(pad "2" smd roundrect
			(at 0.48 0 270)
			(size 0.59 0.64)
			(layers "F.Cu" "F.Mask" "F.Paste")
			(roundrect_rratio 0.25)
			(net 3 "VCC1V35")
			(pintype "passive")
		)
	)
	(footprint "antmicro-footprints:C_0402_1005Metric"
		(layer "F.Cu")
		(at 96.174 154.675 90)
		(descr "Capacitor SMD 0402")
		(tags "capacitor SMD 0402")
		(property "Reference" "C61"
			(at -3.425 -8.074 90)
			(layer "F.SilkS")
			(effects
				(font
					(size 0.7 0.7)
					(thickness 0.15)
				)
				(justify left bottom)
			)
		)
		(property "Value" "C_470n_0402"
			(at 0 1.4 90)
			(layer "F.Fab")
			(effects
				(font
					(size 0.7 0.7)
					(thickness 0.15)
				)
				(justify left bottom)
			)
		)
		(property "Datasheet" "https://product.tdk.com/en/search/capacitor/ceramic/mlcc/info?part_no=C1005X5R1E474M050BB"
			(at 0 0 90)
			(layer "F.Fab")
			(hide yes)
			(effects
				(font
					(size 1.27 1.27)
					(thickness 0.15)
				)
			)
		)
		(property "Description" "SMD Multilayer Ceramic Capacitor, 0.47 µF, 25 V, 0402 [1005 Metric], ± 20%, X5R, C"
			(at 0 0 90)
			(layer "F.Fab")
			(hide yes)
			(effects
				(font
					(size 1.27 1.27)
					(thickness 0.15)
				)
			)
		)
		(property "Author" "Antmicro"
			(at 250.849 58.501 0)
			(layer "F.Fab")
			(hide yes)
			(effects
				(font
					(size 1 1)
					(thickness 0.15)
				)
			)
		)
		(property "Dielectric" ""
			(at 250.849 58.501 0)
			(layer "F.Fab")
			(hide yes)
			(effects
				(font
					(size 1 1)
					(thickness 0.15)
				)
			)
		)
		(property "License" "Apache-2.0"
			(at 250.849 58.501 0)
			(layer "F.Fab")
			(hide yes)
			(effects
				(font
					(size 1 1)
					(thickness 0.15)
				)
			)
		)
		(property "MPN" "C1005X5R1E474M050BB"
			(at 250.849 58.501 0)
			(layer "F.Fab")
			(hide yes)
			(effects
				(font
					(size 1 1)
					(thickness 0.15)
				)
			)
		)
		(property "Manufacturer" "TDK"
			(at 250.849 58.501 0)
			(layer "F.Fab")
			(hide yes)
			(effects
				(font
					(size 1 1)
					(thickness 0.15)
				)
			)
		)
		(property "Val" "470n"
			(at 250.849 58.501 0)
			(layer "F.Fab")
			(hide yes)
			(effects
				(font
					(size 1 1)
					(thickness 0.15)
				)
			)
		)
		(property "Voltage" ""
			(at 250.849 58.501 0)
			(layer "F.Fab")
			(hide yes)
			(effects
				(font
					(size 1 1)
					(thickness 0.15)
				)
			)
		)
		(sheetname "/DDR3/")
		(sheetfile "ddr3.kicad_sch")
		(attr smd)
		(fp_rect
			(start -0.925 -0.47)
			(end 0.925 0.47)
			(stroke
				(width 0.05)
				(type default)
			)
			(fill no)
			(layer "F.CrtYd")
		)
		(fp_line
			(start 0.504 -0.25)
			(end 0.504 0.248)
			(stroke
				(width 0.15)
				(type solid)
			)
			(layer "F.Fab")
		)
		(fp_line
			(start -0.494 -0.25)
			(end 0.504 -0.25)
			(stroke
				(width 0.15)
				(type solid)
			)
			(layer "F.Fab")
		)
		(fp_line
			(start 0.504 0.248)
			(end -0.494 0.248)
			(stroke
				(width 0.15)
				(type solid)
			)
			(layer "F.Fab")
		)
		(fp_line
			(start -0.494 0.248)
			(end -0.494 -0.25)
			(stroke
				(width 0.15)
				(type solid)
			)
			(layer "F.Fab")
		)
		(pad "1" smd roundrect
			(at -0.48 0 90)
			(size 0.59 0.64)
			(layers "F.Cu" "F.Mask" "F.Paste")
			(roundrect_rratio 0.25)
			(net 1 "GND")
			(pintype "passive")
		)
		(pad "2" smd roundrect
			(at 0.48 0 90)
			(size 0.59 0.64)
			(layers "F.Cu" "F.Mask" "F.Paste")
			(roundrect_rratio 0.25)
			(net 3 "VCC1V35")
			(pintype "passive")
		)
	)
	(footprint "antmicro-footprints:C_0402_1005Metric"
		(layer "F.Cu")
		(at 97.374 154.675 90)
		(descr "Capacitor SMD 0402")
		(tags "capacitor SMD 0402")
		(property "Reference" "C54"
			(at -3.425 -8.174 90)
			(layer "F.SilkS")
			(effects
				(font
					(size 0.7 0.7)
					(thickness 0.15)
				)
				(justify left bottom)
			)
		)
		(property "Value" "C_470n_0402"
			(at 0 1.4 90)
			(layer "F.Fab")
			(effects
				(font
					(size 0.7 0.7)
					(thickness 0.15)
				)
				(justify left bottom)
			)
		)
		(property "Datasheet" "https://product.tdk.com/en/search/capacitor/ceramic/mlcc/info?part_no=C1005X5R1E474M050BB"
			(at 0 0 90)
			(layer "F.Fab")
			(hide yes)
			(effects
				(font
					(size 1.27 1.27)
					(thickness 0.15)
				)
			)
		)
		(property "Description" "SMD Multilayer Ceramic Capacitor, 0.47 µF, 25 V, 0402 [1005 Metric], ± 20%, X5R, C"
			(at 0 0 90)
			(layer "F.Fab")
			(hide yes)
			(effects
				(font
					(size 1.27 1.27)
					(thickness 0.15)
				)
			)
		)
		(property "Author" "Antmicro"
			(at 252.049 57.301 0)
			(layer "F.Fab")
			(hide yes)
			(effects
				(font
					(size 1 1)
					(thickness 0.15)
				)
			)
		)
		(property "Dielectric" ""
			(at 252.049 57.301 0)
			(layer "F.Fab")
			(hide yes)
			(effects
				(font
					(size 1 1)
					(thickness 0.15)
				)
			)
		)
		(property "License" "Apache-2.0"
			(at 252.049 57.301 0)
			(layer "F.Fab")
			(hide yes)
			(effects
				(font
					(size 1 1)
					(thickness 0.15)
				)
			)
		)
		(property "MPN" "C1005X5R1E474M050BB"
			(at 252.049 57.301 0)
			(layer "F.Fab")
			(hide yes)
			(effects
				(font
					(size 1 1)
					(thickness 0.15)
				)
			)
		)
		(property "Manufacturer" "TDK"
			(at 252.049 57.301 0)
			(layer "F.Fab")
			(hide yes)
			(effects
				(font
					(size 1 1)
					(thickness 0.15)
				)
			)
		)
		(property "Val" "470n"
			(at 252.049 57.301 0)
			(layer "F.Fab")
			(hide yes)
			(effects
				(font
					(size 1 1)
					(thickness 0.15)
				)
			)
		)
		(property "Voltage" ""
			(at 252.049 57.301 0)
			(layer "F.Fab")
			(hide yes)
			(effects
				(font
					(size 1 1)
					(thickness 0.15)
				)
			)
		)
		(sheetname "/DDR3/")
		(sheetfile "ddr3.kicad_sch")
		(attr smd)
		(fp_rect
			(start -0.925 -0.47)
			(end 0.925 0.47)
			(stroke
				(width 0.05)
				(type default)
			)
			(fill no)
			(layer "F.CrtYd")
		)
		(fp_line
			(start 0.504 -0.25)
			(end 0.504 0.248)
			(stroke
				(width 0.15)
				(type solid)
			)
			(layer "F.Fab")
		)
		(fp_line
			(start -0.494 -0.25)
			(end 0.504 -0.25)
			(stroke
				(width 0.15)
				(type solid)
			)
			(layer "F.Fab")
		)
		(fp_line
			(start 0.504 0.248)
			(end -0.494 0.248)
			(stroke
				(width 0.15)
				(type solid)
			)
			(layer "F.Fab")
		)
		(fp_line
			(start -0.494 0.248)
			(end -0.494 -0.25)
			(stroke
				(width 0.15)
				(type solid)
			)
			(layer "F.Fab")
		)
		(pad "1" smd roundrect
			(at -0.48 0 90)
			(size 0.59 0.64)
			(layers "F.Cu" "F.Mask" "F.Paste")
			(roundrect_rratio 0.25)
			(net 1 "GND")
			(pintype "passive")
		)
		(pad "2" smd roundrect
			(at 0.48 0 90)
			(size 0.59 0.64)
			(layers "F.Cu" "F.Mask" "F.Paste")
			(roundrect_rratio 0.25)
			(net 3 "VCC1V35")
			(pintype "passive")
		)
	)
	(footprint "antmicro-footprints:C_0402_1005Metric"
		(layer "F.Cu")
		(at 93.674 140.075 -90)
		(descr "Capacitor SMD 0402")
		(tags "capacitor SMD 0402")
		(property "Reference" "C58"
			(at -2.975 -0.326 90)
			(layer "F.SilkS")
			(effects
				(font
					(size 0.7 0.7)
					(thickness 0.15)
				)
				(justify right bottom)
			)
		)
		(property "Value" "C_470n_0402"
			(at 0 1.4 90)
			(layer "F.Fab")
			(effects
				(font
					(size 0.7 0.7)
					(thickness 0.15)
				)
				(justify right bottom)
			)
		)
		(property "Datasheet" "https://product.tdk.com/en/search/capacitor/ceramic/mlcc/info?part_no=C1005X5R1E474M050BB"
			(at 0 0 270)
			(layer "F.Fab")
			(hide yes)
			(effects
				(font
					(size 1.27 1.27)
					(thickness 0.15)
				)
			)
		)
		(property "Description" "SMD Multilayer Ceramic Capacitor, 0.47 µF, 25 V, 0402 [1005 Metric], ± 20%, X5R, C"
			(at 0 0 270)
			(layer "F.Fab")
			(hide yes)
			(effects
				(font
					(size 1.27 1.27)
					(thickness 0.15)
				)
			)
		)
		(property "Author" "Antmicro"
			(at -46.401 233.749 0)
			(layer "F.Fab")
			(hide yes)
			(effects
				(font
					(size 1 1)
					(thickness 0.15)
				)
			)
		)
		(property "Dielectric" ""
			(at -46.401 233.749 0)
			(layer "F.Fab")
			(hide yes)
			(effects
				(font
					(size 1 1)
					(thickness 0.15)
				)
			)
		)
		(property "License" "Apache-2.0"
			(at -46.401 233.749 0)
			(layer "F.Fab")
			(hide yes)
			(effects
				(font
					(size 1 1)
					(thickness 0.15)
				)
			)
		)
		(property "MPN" "C1005X5R1E474M050BB"
			(at -46.401 233.749 0)
			(layer "F.Fab")
			(hide yes)
			(effects
				(font
					(size 1 1)
					(thickness 0.15)
				)
			)
		)
		(property "Manufacturer" "TDK"
			(at -46.401 233.749 0)
			(layer "F.Fab")
			(hide yes)
			(effects
				(font
					(size 1 1)
					(thickness 0.15)
				)
			)
		)
		(property "Val" "470n"
			(at -46.401 233.749 0)
			(layer "F.Fab")
			(hide yes)
			(effects
				(font
					(size 1 1)
					(thickness 0.15)
				)
			)
		)
		(property "Voltage" ""
			(at -46.401 233.749 0)
			(layer "F.Fab")
			(hide yes)
			(effects
				(font
					(size 1 1)
					(thickness 0.15)
				)
			)
		)
		(sheetname "/DDR3/")
		(sheetfile "ddr3.kicad_sch")
		(attr smd)
		(fp_rect
			(start -0.925 -0.47)
			(end 0.925 0.47)
			(stroke
				(width 0.05)
				(type default)
			)
			(fill no)
			(layer "F.CrtYd")
		)
		(fp_line
			(start -0.494 0.248)
			(end -0.494 -0.25)
			(stroke
				(width 0.15)
				(type solid)
			)
			(layer "F.Fab")
		)
		(fp_line
			(start 0.504 0.248)
			(end -0.494 0.248)
			(stroke
				(width 0.15)
				(type solid)
			)
			(layer "F.Fab")
		)
		(fp_line
			(start -0.494 -0.25)
			(end 0.504 -0.25)
			(stroke
				(width 0.15)
				(type solid)
			)
			(layer "F.Fab")
		)
		(fp_line
			(start 0.504 -0.25)
			(end 0.504 0.248)
			(stroke
				(width 0.15)
				(type solid)
			)
			(layer "F.Fab")
		)
		(pad "1" smd roundrect
			(at -0.48 0 270)
			(size 0.59 0.64)
			(layers "F.Cu" "F.Mask" "F.Paste")
			(roundrect_rratio 0.25)
			(net 1 "GND")
			(pintype "passive")
		)
		(pad "2" smd roundrect
			(at 0.48 0 270)
			(size 0.59 0.64)
			(layers "F.Cu" "F.Mask" "F.Paste")
			(roundrect_rratio 0.25)
			(net 3 "VCC1V35")
			(pintype "passive")
		)
	)
	(footprint "antmicro-footprints:C_0402_1005Metric"
		(layer "F.Cu")
		(at 93.374 154.675 90)
		(descr "Capacitor SMD 0402")
		(tags "capacitor SMD 0402")
		(property "Reference" "C51"
			(at -3.425 -7.774 90)
			(layer "F.SilkS")
			(effects
				(font
					(size 0.7 0.7)
					(thickness 0.15)
				)
				(justify left bottom)
			)
		)
		(property "Value" "C_470n_0402"
			(at 0 1.4 90)
			(layer "F.Fab")
			(effects
				(font
					(size 0.7 0.7)
					(thickness 0.15)
				)
				(justify left bottom)
			)
		)
		(property "Datasheet" "https://product.tdk.com/en/search/capacitor/ceramic/mlcc/info?part_no=C1005X5R1E474M050BB"
			(at 0 0 90)
			(layer "F.Fab")
			(hide yes)
			(effects
				(font
					(size 1.27 1.27)
					(thickness 0.15)
				)
			)
		)
		(property "Description" "SMD Multilayer Ceramic Capacitor, 0.47 µF, 25 V, 0402 [1005 Metric], ± 20%, X5R, C"
			(at 0 0 90)
			(layer "F.Fab")
			(hide yes)
			(effects
				(font
					(size 1.27 1.27)
					(thickness 0.15)
				)
			)
		)
		(property "Author" "Antmicro"
			(at 248.049 61.301 0)
			(layer "F.Fab")
			(hide yes)
			(effects
				(font
					(size 1 1)
					(thickness 0.15)
				)
			)
		)
		(property "Dielectric" ""
			(at 248.049 61.301 0)
			(layer "F.Fab")
			(hide yes)
			(effects
				(font
					(size 1 1)
					(thickness 0.15)
				)
			)
		)
		(property "License" "Apache-2.0"
			(at 248.049 61.301 0)
			(layer "F.Fab")
			(hide yes)
			(effects
				(font
					(size 1 1)
					(thickness 0.15)
				)
			)
		)
		(property "MPN" "C1005X5R1E474M050BB"
			(at 248.049 61.301 0)
			(layer "F.Fab")
			(hide yes)
			(effects
				(font
					(size 1 1)
					(thickness 0.15)
				)
			)
		)
		(property "Manufacturer" "TDK"
			(at 248.049 61.301 0)
			(layer "F.Fab")
			(hide yes)
			(effects
				(font
					(size 1 1)
					(thickness 0.15)
				)
			)
		)
		(property "Val" "470n"
			(at 248.049 61.301 0)
			(layer "F.Fab")
			(hide yes)
			(effects
				(font
					(size 1 1)
					(thickness 0.15)
				)
			)
		)
		(property "Voltage" ""
			(at 248.049 61.301 0)
			(layer "F.Fab")
			(hide yes)
			(effects
				(font
					(size 1 1)
					(thickness 0.15)
				)
			)
		)
		(sheetname "/DDR3/")
		(sheetfile "ddr3.kicad_sch")
		(attr smd)
		(fp_rect
			(start -0.925 -0.47)
			(end 0.925 0.47)
			(stroke
				(width 0.05)
				(type default)
			)
			(fill no)
			(layer "F.CrtYd")
		)
		(fp_line
			(start 0.504 -0.25)
			(end 0.504 0.248)
			(stroke
				(width 0.15)
				(type solid)
			)
			(layer "F.Fab")
		)
		(fp_line
			(start -0.494 -0.25)
			(end 0.504 -0.25)
			(stroke
				(width 0.15)
				(type solid)
			)
			(layer "F.Fab")
		)
		(fp_line
			(start 0.504 0.248)
			(end -0.494 0.248)
			(stroke
				(width 0.15)
				(type solid)
			)
			(layer "F.Fab")
		)
		(fp_line
			(start -0.494 0.248)
			(end -0.494 -0.25)
			(stroke
				(width 0.15)
				(type solid)
			)
			(layer "F.Fab")
		)
		(pad "1" smd roundrect
			(at -0.48 0 90)
			(size 0.59 0.64)
			(layers "F.Cu" "F.Mask" "F.Paste")
			(roundrect_rratio 0.25)
			(net 1 "GND")
			(pintype "passive")
		)
		(pad "2" smd roundrect
			(at 0.48 0 90)
			(size 0.59 0.64)
			(layers "F.Cu" "F.Mask" "F.Paste")
			(roundrect_rratio 0.25)
			(net 3 "VCC1V35")
			(pintype "passive")
		)
	)
	(footprint "antmicro-footprints:C_0402_1005Metric"
		(layer "F.Cu")
		(at 94.974 154.675 90)
		(descr "Capacitor SMD 0402")
		(tags "capacitor SMD 0402")
		(property "Reference" "C55"
			(at -3.425 -7.974 90)
			(layer "F.SilkS")
			(effects
				(font
					(size 0.7 0.7)
					(thickness 0.15)
				)
				(justify left bottom)
			)
		)
		(property "Value" "C_470n_0402"
			(at 0 1.4 90)
			(layer "F.Fab")
			(effects
				(font
					(size 0.7 0.7)
					(thickness 0.15)
				)
				(justify left bottom)
			)
		)
		(property "Datasheet" "https://product.tdk.com/en/search/capacitor/ceramic/mlcc/info?part_no=C1005X5R1E474M050BB"
			(at 0 0 90)
			(layer "F.Fab")
			(hide yes)
			(effects
				(font
					(size 1.27 1.27)
					(thickness 0.15)
				)
			)
		)
		(property "Description" "SMD Multilayer Ceramic Capacitor, 0.47 µF, 25 V, 0402 [1005 Metric], ± 20%, X5R, C"
			(at 0 0 90)
			(layer "F.Fab")
			(hide yes)
			(effects
				(font
					(size 1.27 1.27)
					(thickness 0.15)
				)
			)
		)
		(property "Author" "Antmicro"
			(at 249.649 59.701 0)
			(layer "F.Fab")
			(hide yes)
			(effects
				(font
					(size 1 1)
					(thickness 0.15)
				)
			)
		)
		(property "Dielectric" ""
			(at 249.649 59.701 0)
			(layer "F.Fab")
			(hide yes)
			(effects
				(font
					(size 1 1)
					(thickness 0.15)
				)
			)
		)
		(property "License" "Apache-2.0"
			(at 249.649 59.701 0)
			(layer "F.Fab")
			(hide yes)
			(effects
				(font
					(size 1 1)
					(thickness 0.15)
				)
			)
		)
		(property "MPN" "C1005X5R1E474M050BB"
			(at 249.649 59.701 0)
			(layer "F.Fab")
			(hide yes)
			(effects
				(font
					(size 1 1)
					(thickness 0.15)
				)
			)
		)
		(property "Manufacturer" "TDK"
			(at 249.649 59.701 0)
			(layer "F.Fab")
			(hide yes)
			(effects
				(font
					(size 1 1)
					(thickness 0.15)
				)
			)
		)
		(property "Val" "470n"
			(at 249.649 59.701 0)
			(layer "F.Fab")
			(hide yes)
			(effects
				(font
					(size 1 1)
					(thickness 0.15)
				)
			)
		)
		(property "Voltage" ""
			(at 249.649 59.701 0)
			(layer "F.Fab")
			(hide yes)
			(effects
				(font
					(size 1 1)
					(thickness 0.15)
				)
			)
		)
		(sheetname "/DDR3/")
		(sheetfile "ddr3.kicad_sch")
		(attr smd)
		(fp_rect
			(start -0.925 -0.47)
			(end 0.925 0.47)
			(stroke
				(width 0.05)
				(type default)
			)
			(fill no)
			(layer "F.CrtYd")
		)
		(fp_line
			(start 0.504 -0.25)
			(end 0.504 0.248)
			(stroke
				(width 0.15)
				(type solid)
			)
			(layer "F.Fab")
		)
		(fp_line
			(start -0.494 -0.25)
			(end 0.504 -0.25)
			(stroke
				(width 0.15)
				(type solid)
			)
			(layer "F.Fab")
		)
		(fp_line
			(start 0.504 0.248)
			(end -0.494 0.248)
			(stroke
				(width 0.15)
				(type solid)
			)
			(layer "F.Fab")
		)
		(fp_line
			(start -0.494 0.248)
			(end -0.494 -0.25)
			(stroke
				(width 0.15)
				(type solid)
			)
			(layer "F.Fab")
		)
		(pad "1" smd roundrect
			(at -0.48 0 90)
			(size 0.59 0.64)
			(layers "F.Cu" "F.Mask" "F.Paste")
			(roundrect_rratio 0.25)
			(net 1 "GND")
			(pintype "passive")
		)
		(pad "2" smd roundrect
			(at 0.48 0 90)
			(size 0.59 0.64)
			(layers "F.Cu" "F.Mask" "F.Paste")
			(roundrect_rratio 0.25)
			(net 3 "VCC1V35")
			(pintype "passive")
		)
	)
	(footprint "antmicro-footprints:C_0402_1005Metric"
		(layer "F.Cu")
		(at 101.774 154.675 90)
		(descr "Capacitor SMD 0402")
		(tags "capacitor SMD 0402")
		(property "Reference" "C50"
			(at -3.425 -8.174 90)
			(layer "F.SilkS")
			(effects
				(font
					(size 0.7 0.7)
					(thickness 0.15)
				)
				(justify left bottom)
			)
		)
		(property "Value" "C_470n_0402"
			(at 0 1.4 90)
			(layer "F.Fab")
			(effects
				(font
					(size 0.7 0.7)
					(thickness 0.15)
				)
				(justify left bottom)
			)
		)
		(property "Datasheet" "https://product.tdk.com/en/search/capacitor/ceramic/mlcc/info?part_no=C1005X5R1E474M050BB"
			(at 0 0 90)
			(layer "F.Fab")
			(hide yes)
			(effects
				(font
					(size 1.27 1.27)
					(thickness 0.15)
				)
			)
		)
		(property "Description" "SMD Multilayer Ceramic Capacitor, 0.47 µF, 25 V, 0402 [1005 Metric], ± 20%, X5R, C"
			(at 0 0 90)
			(layer "F.Fab")
			(hide yes)
			(effects
				(font
					(size 1.27 1.27)
					(thickness 0.15)
				)
			)
		)
		(property "Author" "Antmicro"
			(at 256.449 52.901 0)
			(layer "F.Fab")
			(hide yes)
			(effects
				(font
					(size 1 1)
					(thickness 0.15)
				)
			)
		)
		(property "Dielectric" ""
			(at 256.449 52.901 0)
			(layer "F.Fab")
			(hide yes)
			(effects
				(font
					(size 1 1)
					(thickness 0.15)
				)
			)
		)
		(property "License" "Apache-2.0"
			(at 256.449 52.901 0)
			(layer "F.Fab")
			(hide yes)
			(effects
				(font
					(size 1 1)
					(thickness 0.15)
				)
			)
		)
		(property "MPN" "C1005X5R1E474M050BB"
			(at 256.449 52.901 0)
			(layer "F.Fab")
			(hide yes)
			(effects
				(font
					(size 1 1)
					(thickness 0.15)
				)
			)
		)
		(property "Manufacturer" "TDK"
			(at 256.449 52.901 0)
			(layer "F.Fab")
			(hide yes)
			(effects
				(font
					(size 1 1)
					(thickness 0.15)
				)
			)
		)
		(property "Val" "470n"
			(at 256.449 52.901 0)
			(layer "F.Fab")
			(hide yes)
			(effects
				(font
					(size 1 1)
					(thickness 0.15)
				)
			)
		)
		(property "Voltage" ""
			(at 256.449 52.901 0)
			(layer "F.Fab")
			(hide yes)
			(effects
				(font
					(size 1 1)
					(thickness 0.15)
				)
			)
		)
		(sheetname "/DDR3/")
		(sheetfile "ddr3.kicad_sch")
		(attr smd)
		(fp_rect
			(start -0.925 -0.47)
			(end 0.925 0.47)
			(stroke
				(width 0.05)
				(type default)
			)
			(fill no)
			(layer "F.CrtYd")
		)
		(fp_line
			(start 0.504 -0.25)
			(end 0.504 0.248)
			(stroke
				(width 0.15)
				(type solid)
			)
			(layer "F.Fab")
		)
		(fp_line
			(start -0.494 -0.25)
			(end 0.504 -0.25)
			(stroke
				(width 0.15)
				(type solid)
			)
			(layer "F.Fab")
		)
		(fp_line
			(start 0.504 0.248)
			(end -0.494 0.248)
			(stroke
				(width 0.15)
				(type solid)
			)
			(layer "F.Fab")
		)
		(fp_line
			(start -0.494 0.248)
			(end -0.494 -0.25)
			(stroke
				(width 0.15)
				(type solid)
			)
			(layer "F.Fab")
		)
		(pad "1" smd roundrect
			(at -0.48 0 90)
			(size 0.59 0.64)
			(layers "F.Cu" "F.Mask" "F.Paste")
			(roundrect_rratio 0.25)
			(net 1 "GND")
			(pintype "passive")
		)
		(pad "2" smd roundrect
			(at 0.48 0 90)
			(size 0.59 0.64)
			(layers "F.Cu" "F.Mask" "F.Paste")
			(roundrect_rratio 0.25)
			(net 3 "VCC1V35")
			(pintype "passive")
		)
	)
	(footprint "antmicro-footprints:R_0402_1005Metric"
		(layer "F.Cu")
		(at 96.225 95.975 -90)
		(descr "Resistor SMD 0402")
		(tags "resistor SMD 0402")
		(property "Reference" "R157"
			(at 0.925 -0.375 90)
			(layer "F.SilkS")
			(effects
				(font
					(size 0.7 0.7)
					(thickness 0.15)
				)
				(justify right bottom)
			)
		)
		(property "Value" "R_10k2_0402"
			(at 0 1.4 90)
			(layer "F.Fab")
			(effects
				(font
					(size 0.7 0.7)
					(thickness 0.15)
				)
				(justify right bottom)
			)
		)
		(property "Datasheet" "https://www.bourns.com/docs/product-datasheets/cr.pdf"
			(at 0 0 270)
			(layer "F.Fab")
			(hide yes)
			(effects
				(font
					(size 1.27 1.27)
					(thickness 0.15)
				)
			)
		)
		(property "Description" "SMD Chip Resistor"
			(at 0 0 270)
			(layer "F.Fab")
			(hide yes)
			(effects
				(font
					(size 1.27 1.27)
					(thickness 0.15)
				)
			)
		)
		(property "Author" "Antmicro"
			(at 0.25 192.2 0)
			(layer "F.Fab")
			(hide yes)
			(effects
				(font
					(size 1 1)
					(thickness 0.15)
				)
			)
		)
		(property "License" "Apache-2.0"
			(at 0.25 192.2 0)
			(layer "F.Fab")
			(hide yes)
			(effects
				(font
					(size 1 1)
					(thickness 0.15)
				)
			)
		)
		(property "MPN" "CR0402-FX-1022GLF"
			(at 0.25 192.2 0)
			(layer "F.Fab")
			(hide yes)
			(effects
				(font
					(size 1 1)
					(thickness 0.15)
				)
			)
		)
		(property "Manufacturer" "Bourns"
			(at 0.25 192.2 0)
			(layer "F.Fab")
			(hide yes)
			(effects
				(font
					(size 1 1)
					(thickness 0.15)
				)
			)
		)
		(property "Tolerance" "1%"
			(at 0.25 192.2 0)
			(layer "F.Fab")
			(hide yes)
			(effects
				(font
					(size 1 1)
					(thickness 0.15)
				)
			)
		)
		(property "Val" "10k2"
			(at 0.25 192.2 0)
			(layer "F.Fab")
			(hide yes)
			(effects
				(font
					(size 1 1)
					(thickness 0.15)
				)
			)
		)
		(sheetname "/Ethernet/")
		(sheetfile "ethernet.kicad_sch")
		(attr smd)
		(fp_rect
			(start -0.925 -0.47)
			(end 0.925 0.47)
			(stroke
				(width 0.05)
				(type default)
			)
			(fill no)
			(layer "F.CrtYd")
		)
		(fp_rect
			(start -0.5 -0.25)
			(end 0.5 0.25)
			(stroke
				(width 0.15)
				(type solid)
			)
			(fill no)
			(layer "F.Fab")
		)
		(pad "1" smd roundrect
			(at -0.48 0 270)
			(size 0.59 0.64)
			(layers "F.Cu" "F.Mask" "F.Paste")
			(roundrect_rratio 0.25)
			(net 415 "/Ethernet/ETH_LED1")
			(pintype "passive")
		)
		(pad "2" smd roundrect
			(at 0.48 0 270)
			(size 0.59 0.64)
			(layers "F.Cu" "F.Mask" "F.Paste")
			(roundrect_rratio 0.25)
			(net 2 "VCC3V3")
			(pintype "passive")
		)
	)
	(footprint "antmicro-footprints:R_0402_1005Metric"
		(layer "F.Cu")
		(at 96.225 94.06 90)
		(descr "Resistor SMD 0402")
		(tags "resistor SMD 0402")
		(property "Reference" "R158"
			(at 0.86 0.375 90)
			(layer "F.SilkS")
			(effects
				(font
					(size 0.7 0.7)
					(thickness 0.15)
				)
				(justify left bottom)
			)
		)
		(property "Value" "R_10k2_0402"
			(at 0 1.4 90)
			(layer "F.Fab")
			(effects
				(font
					(size 0.7 0.7)
					(thickness 0.15)
				)
				(justify left bottom)
			)
		)
		(property "Datasheet" "https://www.bourns.com/docs/product-datasheets/cr.pdf"
			(at 0 0 90)
			(layer "F.Fab")
			(hide yes)
			(effects
				(font
					(size 1.27 1.27)
					(thickness 0.15)
				)
			)
		)
		(property "Description" "SMD Chip Resistor"
			(at 0 0 90)
			(layer "F.Fab")
			(hide yes)
			(effects
				(font
					(size 1.27 1.27)
					(thickness 0.15)
				)
			)
		)
		(property "Author" "Antmicro"
			(at 190.285 -2.165 0)
			(layer "F.Fab")
			(hide yes)
			(effects
				(font
					(size 1 1)
					(thickness 0.15)
				)
			)
		)
		(property "License" "Apache-2.0"
			(at 190.285 -2.165 0)
			(layer "F.Fab")
			(hide yes)
			(effects
				(font
					(size 1 1)
					(thickness 0.15)
				)
			)
		)
		(property "MPN" "CR0402-FX-1022GLF"
			(at 190.285 -2.165 0)
			(layer "F.Fab")
			(hide yes)
			(effects
				(font
					(size 1 1)
					(thickness 0.15)
				)
			)
		)
		(property "Manufacturer" "Bourns"
			(at 190.285 -2.165 0)
			(layer "F.Fab")
			(hide yes)
			(effects
				(font
					(size 1 1)
					(thickness 0.15)
				)
			)
		)
		(property "Tolerance" "1%"
			(at 190.285 -2.165 0)
			(layer "F.Fab")
			(hide yes)
			(effects
				(font
					(size 1 1)
					(thickness 0.15)
				)
			)
		)
		(property "Val" "10k2"
			(at 190.285 -2.165 0)
			(layer "F.Fab")
			(hide yes)
			(effects
				(font
					(size 1 1)
					(thickness 0.15)
				)
			)
		)
		(sheetname "/Ethernet/")
		(sheetfile "ethernet.kicad_sch")
		(attr smd)
		(fp_rect
			(start -0.925 -0.47)
			(end 0.925 0.47)
			(stroke
				(width 0.05)
				(type default)
			)
			(fill no)
			(layer "F.CrtYd")
		)
		(fp_rect
			(start -0.5 -0.25)
			(end 0.5 0.25)
			(stroke
				(width 0.15)
				(type solid)
			)
			(fill no)
			(layer "F.Fab")
		)
		(pad "1" smd roundrect
			(at -0.48 0 90)
			(size 0.59 0.64)
			(layers "F.Cu" "F.Mask" "F.Paste")
			(roundrect_rratio 0.25)
			(net 416 "/Ethernet/ETH_LED2")
			(pintype "passive")
		)
		(pad "2" smd roundrect
			(at 0.48 0 90)
			(size 0.59 0.64)
			(layers "F.Cu" "F.Mask" "F.Paste")
			(roundrect_rratio 0.25)
			(net 2 "VCC3V3")
			(pintype "passive")
		)
	)
	(footprint "antmicro-footprints:QFN-48-1EP_7x7x0.9mm_P0.5mm_EP3.5x3.5mm"
		(layer "F.Cu")
		(at 102.1 96.225 -90)
		(property "Reference" "U20"
			(at -4.285 -4.08 270)
			(layer "F.SilkS")
			(effects
				(font
					(size 0.7 0.7)
					(thickness 0.15)
				)
				(justify left bottom)
			)
		)
		(property "Value" "KSZ9031RNXCA"
			(at 0 5.1 270)
			(layer "F.Fab")
			(hide yes)
			(effects
				(font
					(size 0.7 0.7)
					(thickness 0.15)
				)
				(justify left bottom)
			)
		)
		(property "Datasheet" "http://ww1.microchip.com/downloads/en/DeviceDoc/00002117F.pdf"
			(at 0 0 270)
			(layer "F.Fab")
			(hide yes)
			(effects
				(font
					(size 1.27 1.27)
					(thickness 0.15)
				)
			)
		)
		(property "Description" "Ethernet Controller, 1000 Mbps, IEEE 802.3, 1.14 V, 3.465 V, QFN, 48 Pins"
			(at 0 0 270)
			(layer "F.Fab")
			(hide yes)
			(effects
				(font
					(size 1.27 1.27)
					(thickness 0.15)
				)
			)
		)
		(property "Author" "Antmicro"
			(at 5.875 198.325 0)
			(layer "F.Fab")
			(hide yes)
			(effects
				(font
					(size 1 1)
					(thickness 0.15)
				)
			)
		)
		(property "License" "Apache-2.0"
			(at 5.875 198.325 0)
			(layer "F.Fab")
			(hide yes)
			(effects
				(font
					(size 1 1)
					(thickness 0.15)
				)
			)
		)
		(property "MPN" "KSZ9031RNXCA"
			(at 5.875 198.325 0)
			(layer "F.Fab")
			(hide yes)
			(effects
				(font
					(size 1 1)
					(thickness 0.15)
				)
			)
		)
		(property "Manufacturer" "Microchip Technology"
			(at 5.875 198.325 0)
			(layer "F.Fab")
			(hide yes)
			(effects
				(font
					(size 1 1)
					(thickness 0.15)
				)
			)
		)
		(sheetname "/Ethernet/")
		(sheetfile "ethernet.kicad_sch")
		(attr smd)
		(fp_line
			(start -3.65 3.648)
			(end -3.65 3.249)
			(stroke
				(width 0.15)
				(type solid)
			)
			(layer "F.SilkS")
		)
		(fp_line
			(start -3.25 3.648)
			(end -3.65 3.648)
			(stroke
				(width 0.15)
				(type solid)
			)
			(layer "F.SilkS")
		)
		(fp_line
			(start 3.249 3.648)
			(end 3.648 3.648)
			(stroke
				(width 0.15)
				(type solid)
			)
			(layer "F.SilkS")
		)
		(fp_line
			(start 3.648 3.648)
			(end 3.648 3.249)
			(stroke
				(width 0.15)
				(type solid)
			)
			(layer "F.SilkS")
		)
		(fp_line
			(start -3.65 -3.3)
			(end -3.65 -3.65)
			(stroke
				(width 0.15)
				(type solid)
			)
			(layer "F.SilkS")
		)
		(fp_line
			(start -3.3 -3.65)
			(end -3.65 -3.65)
			(stroke
				(width 0.15)
				(type solid)
			)
			(layer "F.SilkS")
		)
		(fp_line
			(start 3.249 -3.65)
			(end 3.648 -3.65)
			(stroke
				(width 0.15)
				(type solid)
			)
			(layer "F.SilkS")
		)
		(fp_line
			(start 3.648 -3.65)
			(end 3.648 -3.25)
			(stroke
				(width 0.15)
				(type solid)
			)
			(layer "F.SilkS")
		)
		(fp_circle
			(center -3.7 -3.05)
			(end -3.65 -3.05)
			(stroke
				(width 0.15)
				(type solid)
			)
			(fill yes)
			(layer "F.SilkS")
		)
		(fp_rect
			(start -4.15 -4.15)
			(end 4.15 4.15)
			(stroke
				(width 0.05)
				(type solid)
			)
			(fill no)
			(layer "F.CrtYd")
		)
		(fp_line
			(start -3.5 3.499)
			(end 3.499 3.499)
			(stroke
				(width 0.15)
				(type solid)
			)
			(layer "F.Fab")
		)
		(fp_line
			(start 3.499 3.499)
			(end 3.499 -3.5)
			(stroke
				(width 0.15)
				(type solid)
			)
			(layer "F.Fab")
		)
		(fp_line
			(start -3.5 -2.5)
			(end -3.5 3.499)
			(stroke
				(width 0.15)
				(type solid)
			)
			(layer "F.Fab")
		)
		(fp_line
			(start -2.5 -3.5)
			(end -3.5 -2.5)
			(stroke
				(width 0.15)
				(type solid)
			)
			(layer "F.Fab")
		)
		(fp_line
			(start 3.499 -3.5)
			(end -2.5 -3.5)
			(stroke
				(width 0.15)
				(type solid)
			)
			(layer "F.Fab")
		)
		(pad "1" smd oval
			(at -3.5 -2.75)
			(size 0.3 0.9)
			(layers "F.Cu" "F.Mask" "F.Paste")
			(net 406 "/Ethernet/AVDDH")
			(pinfunction "AVDDH")
			(pintype "power_in")
		)
		(pad "2" smd oval
			(at -3.5 -2.25)
			(size 0.3 0.9)
			(layers "F.Cu" "F.Mask" "F.Paste")
			(net 435 "/Ethernet/ETH1_P")
			(pinfunction "TXRXP_A")
			(pintype "bidirectional")
		)
		(pad "3" smd oval
			(at -3.5 -1.75)
			(size 0.3 0.9)
			(layers "F.Cu" "F.Mask" "F.Paste")
			(net 434 "/Ethernet/ETH1_N")
			(pinfunction "TXRXM_A")
			(pintype "bidirectional")
		)
		(pad "4" smd oval
			(at -3.5 -1.25)
			(size 0.3 0.9)
			(layers "F.Cu" "F.Mask" "F.Paste")
			(net 405 "/Ethernet/AVDDL")
			(pinfunction "AVDDL")
			(pintype "power_in")
		)
		(pad "5" smd oval
			(at -3.5 -0.75)
			(size 0.3 0.9)
			(layers "F.Cu" "F.Mask" "F.Paste")
			(net 433 "/Ethernet/ETH2_P")
			(pinfunction "TXRXP_B")
			(pintype "bidirectional")
		)
		(pad "6" smd oval
			(at -3.5 -0.25)
			(size 0.3 0.9)
			(layers "F.Cu" "F.Mask" "F.Paste")
			(net 432 "/Ethernet/ETH2_N")
			(pinfunction "TXRXM_B")
			(pintype "bidirectional")
		)
		(pad "7" smd oval
			(at -3.5 0.248)
			(size 0.3 0.9)
			(layers "F.Cu" "F.Mask" "F.Paste")
			(net 431 "/Ethernet/ETH3_P")
			(pinfunction "TXRXP_C")
			(pintype "bidirectional")
		)
		(pad "8" smd oval
			(at -3.5 0.748)
			(size 0.3 0.9)
			(layers "F.Cu" "F.Mask" "F.Paste")
			(net 430 "/Ethernet/ETH3_N")
			(pinfunction "TXRXM_C")
			(pintype "bidirectional")
		)
		(pad "9" smd oval
			(at -3.5 1.249)
			(size 0.3 0.9)
			(layers "F.Cu" "F.Mask" "F.Paste")
			(net 405 "/Ethernet/AVDDL")
			(pinfunction "AVDDL")
			(pintype "passive")
		)
		(pad "10" smd oval
			(at -3.5 1.749)
			(size 0.3 0.9)
			(layers "F.Cu" "F.Mask" "F.Paste")
			(net 429 "/Ethernet/ETH4_P")
			(pinfunction "TXRXP_D")
			(pintype "bidirectional")
		)
		(pad "11" smd oval
			(at -3.5 2.249)
			(size 0.3 0.9)
			(layers "F.Cu" "F.Mask" "F.Paste")
			(net 428 "/Ethernet/ETH4_N")
			(pinfunction "TXRXM_D")
			(pintype "bidirectional")
		)
		(pad "12" smd oval
			(at -3.5 2.749)
			(size 0.3 0.9)
			(layers "F.Cu" "F.Mask" "F.Paste")
			(net 406 "/Ethernet/AVDDH")
			(pinfunction "AVDDH")
			(pintype "passive")
		)
		(pad "13" smd oval
			(at -2.75 3.499 270)
			(size 0.3 0.9)
			(layers "F.Cu" "F.Mask" "F.Paste")
			(net 687 "unconnected-(U20-NC-Pad13)")
			(pinfunction "NC")
			(pintype "no_connect")
		)
		(pad "14" smd oval
			(at -2.25 3.499 270)
			(size 0.3 0.9)
			(layers "F.Cu" "F.Mask" "F.Paste")
			(net 339 "VCC1V2")
			(pinfunction "DVDDL")
			(pintype "power_in")
		)
		(pad "15" smd oval
			(at -1.75 3.499 270)
			(size 0.3 0.9)
			(layers "F.Cu" "F.Mask" "F.Paste")
			(net 416 "/Ethernet/ETH_LED2")
			(pinfunction "LED2/PHYAD1")
			(pintype "bidirectional")
		)
		(pad "16" smd oval
			(at -1.25 3.499 270)
			(size 0.3 0.9)
			(layers "F.Cu" "F.Mask" "F.Paste")
			(net 2 "VCC3V3")
			(pinfunction "DVDDH")
			(pintype "power_in")
		)
		(pad "17" smd oval
			(at -0.75 3.499 270)
			(size 0.3 0.9)
			(layers "F.Cu" "F.Mask" "F.Paste")
			(net 415 "/Ethernet/ETH_LED1")
			(pinfunction "LED1/PHYAD0/PME_N1")
			(pintype "bidirectional")
		)
		(pad "18" smd oval
			(at -0.25 3.499 270)
			(size 0.3 0.9)
			(layers "F.Cu" "F.Mask" "F.Paste")
			(net 339 "VCC1V2")
			(pinfunction "DVDDL")
			(pintype "passive")
		)
		(pad "19" smd oval
			(at 0.248 3.499 270)
			(size 0.3 0.9)
			(layers "F.Cu" "F.Mask" "F.Paste")
			(net 425 "RGMII_TXD0")
			(pinfunction "TXD0")
			(pintype "input")
		)
		(pad "20" smd oval
			(at 0.748 3.499 270)
			(size 0.3 0.9)
			(layers "F.Cu" "F.Mask" "F.Paste")
			(net 424 "RGMII_TXD1")
			(pinfunction "TXD1")
			(pintype "input")
		)
		(pad "21" smd oval
			(at 1.249 3.499 270)
			(size 0.3 0.9)
			(layers "F.Cu" "F.Mask" "F.Paste")
			(net 423 "RGMII_TXD2")
			(pinfunction "TXD2")
			(pintype "input")
		)
		(pad "22" smd oval
			(at 1.749 3.499 270)
			(size 0.3 0.9)
			(layers "F.Cu" "F.Mask" "F.Paste")
			(net 422 "RGMII_TXD3")
			(pinfunction "TXD3")
			(pintype "input")
		)
		(pad "23" smd oval
			(at 2.249 3.499 270)
			(size 0.3 0.9)
			(layers "F.Cu" "F.Mask" "F.Paste")
			(net 339 "VCC1V2")
			(pinfunction "DVDDL")
			(pintype "passive")
		)
		(pad "24" smd oval
			(at 2.749 3.499 270)
			(size 0.3 0.9)
			(layers "F.Cu" "F.Mask" "F.Paste")
			(net 421 "RGMII_TX_CLK")
			(pinfunction "GTX_CLK")
			(pintype "input")
		)
		(pad "25" smd oval
			(at 3.499 2.749)
			(size 0.3 0.9)
			(layers "F.Cu" "F.Mask" "F.Paste")
			(net 427 "RGMII_TX_DV")
			(pinfunction "TX_EN")
			(pintype "input")
		)
		(pad "26" smd oval
			(at 3.499 2.249)
			(size 0.3 0.9)
			(layers "F.Cu" "F.Mask" "F.Paste")
			(net 339 "VCC1V2")
			(pinfunction "DVDDL")
			(pintype "passive")
		)
		(pad "27" smd oval
			(at 3.499 1.749)
			(size 0.3 0.9)
			(layers "F.Cu" "F.Mask" "F.Paste")
			(net 410 "RGMII_RXD3")
			(pinfunction "RXD3/MODE3")
			(pintype "input")
		)
		(pad "28" smd oval
			(at 3.499 1.249)
			(size 0.3 0.9)
			(layers "F.Cu" "F.Mask" "F.Paste")
			(net 409 "RGMII_RXD2")
			(pinfunction "RXD2/MODE2")
			(pintype "input")
		)
		(pad "29" smd oval
			(at 3.499 0.748)
			(size 0.3 0.9)
			(layers "F.Cu" "F.Mask" "F.Paste")
			(net 1 "GND")
			(pinfunction "VSS")
			(pintype "power_in")
		)
		(pad "30" smd oval
			(at 3.499 0.248)
			(size 0.3 0.9)
			(layers "F.Cu" "F.Mask" "F.Paste")
			(net 339 "VCC1V2")
			(pinfunction "DVDDL")
			(pintype "passive")
		)
		(pad "31" smd oval
			(at 3.499 -0.25)
			(size 0.3 0.9)
			(layers "F.Cu" "F.Mask" "F.Paste")
			(net 408 "RGMII_RXD1")
			(pinfunction "RXD1/MODE1")
			(pintype "input")
		)
		(pad "32" smd oval
			(at 3.499 -0.75)
			(size 0.3 0.9)
			(layers "F.Cu" "F.Mask" "F.Paste")
			(net 407 "RGMII_RXD0")
			(pinfunction "RXD0/MODE0")
			(pintype "input")
		)
		(pad "33" smd oval
			(at 3.499 -1.25)
			(size 0.3 0.9)
			(layers "F.Cu" "F.Mask" "F.Paste")
			(net 411 "RGMII_RX_DV")
			(pinfunction "RX_DV/CLK125_EN")
			(pintype "input")
		)
		(pad "34" smd oval
			(at 3.499 -1.75)
			(size 0.3 0.9)
			(layers "F.Cu" "F.Mask" "F.Paste")
			(net 2 "VCC3V3")
			(pinfunction "DVDDH")
			(pintype "passive")
		)
		(pad "35" smd oval
			(at 3.499 -2.25)
			(size 0.3 0.9)
			(layers "F.Cu" "F.Mask" "F.Paste")
			(net 412 "RGMII_RX_CLK")
			(pinfunction "RX_CLK/PHYAD2")
			(pintype "input")
		)
		(pad "36" smd oval
			(at 3.499 -2.75)
			(size 0.3 0.9)
			(layers "F.Cu" "F.Mask" "F.Paste")
			(net 141 "ETH_MDC")
			(pinfunction "MDC")
			(pintype "input")
		)
		(pad "37" smd oval
			(at 2.749 -3.5 270)
			(size 0.3 0.9)
			(layers "F.Cu" "F.Mask" "F.Paste")
			(net 142 "ETH_MDIO")
			(pinfunction "MDIO")
			(pintype "input")
		)
		(pad "38" smd oval
			(at 2.249 -3.5 270)
			(size 0.3 0.9)
			(layers "F.Cu" "F.Mask" "F.Paste")
			(net 420 "ETH_INT_N")
			(pinfunction "~{INT/PME}")
			(pintype "input")
		)
		(pad "39" smd oval
			(at 1.749 -3.5 270)
			(size 0.3 0.9)
			(layers "F.Cu" "F.Mask" "F.Paste")
			(net 339 "VCC1V2")
			(pinfunction "DVDDL")
			(pintype "passive")
		)
		(pad "40" smd oval
			(at 1.249 -3.5 270)
			(size 0.3 0.9)
			(layers "F.Cu" "F.Mask" "F.Paste")
			(net 2 "VCC3V3")
			(pinfunction "DVDDH")
			(pintype "passive")
		)
		(pad "41" smd oval
			(at 0.748 -3.5 270)
			(size 0.3 0.9)
			(layers "F.Cu" "F.Mask" "F.Paste")
			(net 413 "RGMII_REF_CLK")
			(pinfunction "CLK125_NDO/LED_MODE")
			(pintype "input")
		)
		(pad "42" smd oval
			(at 0.248 -3.5 270)
			(size 0.3 0.9)
			(layers "F.Cu" "F.Mask" "F.Paste")
			(net 414 "ETH_~{RESET}")
			(pinfunction "~{RESET}")
			(pintype "input")
		)
		(pad "43" smd oval
			(at -0.25 -3.5 270)
			(size 0.3 0.9)
			(layers "F.Cu" "F.Mask" "F.Paste")
			(net 688 "unconnected-(U20-LDO_O-Pad43)")
			(pinfunction "LDO_O")
			(pintype "input+no_connect")
		)
		(pad "44" smd oval
			(at -0.75 -3.5 270)
			(size 0.3 0.9)
			(layers "F.Cu" "F.Mask" "F.Paste")
			(net 404 "/Ethernet/AVDDL_PLL")
			(pinfunction "AVDDL_PLL")
			(pintype "power_in")
		)
		(pad "45" smd oval
			(at -1.25 -3.5 270)
			(size 0.3 0.9)
			(layers "F.Cu" "F.Mask" "F.Paste")
			(net 199 "Net-(U20-XO)")
			(pinfunction "XO")
			(pintype "input")
		)
		(pad "46" smd oval
			(at -1.75 -3.5 270)
			(size 0.3 0.9)
			(layers "F.Cu" "F.Mask" "F.Paste")
			(net 201 "Net-(U20-XI)")
			(pinfunction "XI")
			(pintype "input")
		)
		(pad "47" smd oval
			(at -2.25 -3.5 270)
			(size 0.3 0.9)
			(layers "F.Cu" "F.Mask" "F.Paste")
			(net 689 "unconnected-(U20-NC-Pad47)")
			(pinfunction "NC")
			(pintype "no_connect")
		)
		(pad "48" smd oval
			(at -2.75 -3.5 270)
			(size 0.3 0.9)
			(layers "F.Cu" "F.Mask" "F.Paste")
			(net 345 "Net-(U20-ISET)")
			(pinfunction "ISET")
			(pintype "output")
		)
		(pad "49" smd rect
			(at 0 0 270)
			(size 3.5 3.5)
			(layers "F.Cu" "F.Mask" "F.Paste")
			(net 1 "GND")
			(pinfunction "PAD_GND")
			(pintype "power_in")
		)
	)
	(footprint "antmicro-footprints:PinSocket_2x6_P2.54mm_Drill1.02mm_PMOD"
		(layer "F.Cu")
		(at 65.13 103.05 90)
		(descr "http://portal.fciconnect.com/Comergent//fci/drawing/68020.pdf")
		(property "Reference" "J4"
			(at 2.7 -1.63 90)
			(layer "F.SilkS")
			(effects
				(font
					(size 0.7 0.7)
					(thickness 0.15)
				)
				(justify left bottom)
			)
		)
		(property "Value" "PinSocket_2x6_P2.54mm_Drill1.02mm_PMOD"
			(at 1.6 15.8 90)
			(layer "F.Fab")
			(effects
				(font
					(size 0.7 0.7)
					(thickness 0.15)
				)
				(justify left bottom)
			)
		)
		(property "Datasheet" "https://cdn.harwin.com/pdfs/M20-783.pdf"
			(at 0 0 90)
			(layer "F.Fab")
			(hide yes)
			(effects
				(font
					(size 1.27 1.27)
					(thickness 0.15)
				)
			)
		)
		(property "Description" "PCB Receptacle, Board-to-Board, 2.54 mm, 2 Rows, 12 Contacts, Through Hole Mount, M20"
			(at 0 0 90)
			(layer "F.Fab")
			(hide yes)
			(effects
				(font
					(size 1.27 1.27)
					(thickness 0.15)
				)
			)
		)
		(property "Author" "Antmicro"
			(at 168.18 37.92 0)
			(layer "F.Fab")
			(hide yes)
			(effects
				(font
					(size 1 1)
					(thickness 0.15)
				)
			)
		)
		(property "License" "Apache-2.0"
			(at 168.18 37.92 0)
			(layer "F.Fab")
			(hide yes)
			(effects
				(font
					(size 1 1)
					(thickness 0.15)
				)
			)
		)
		(property "MPN" "M20-7830642"
			(at 168.18 37.92 0)
			(layer "F.Fab")
			(hide yes)
			(effects
				(font
					(size 1 1)
					(thickness 0.15)
				)
			)
		)
		(property "Manufacturer" "Harwin"
			(at 168.18 37.92 0)
			(layer "F.Fab")
			(hide yes)
			(effects
				(font
					(size 1 1)
					(thickness 0.15)
				)
			)
		)
		(sheetname "/RoT/")
		(sheetfile "rot.kicad_sch")
		(attr through_hole)
		(fp_line
			(start 3.898 -1.401)
			(end 3.499 -1.401)
			(stroke
				(width 0.15)
				(type solid)
			)
			(layer "F.SilkS")
		)
		(fp_line
			(start 3.898 -1.401)
			(end 3.898 -1)
			(stroke
				(width 0.15)
				(type solid)
			)
			(layer "F.SilkS")
		)
		(fp_line
			(start -1.401 -1.401)
			(end -1 -1.401)
			(stroke
				(width 0.15)
				(type solid)
			)
			(layer "F.SilkS")
		)
		(fp_line
			(start -1.401 -1.401)
			(end -1.401 -1)
			(stroke
				(width 0.15)
				(type solid)
			)
			(layer "F.SilkS")
		)
		(fp_line
			(start 3.898 14.098)
			(end 3.898 13.698)
			(stroke
				(width 0.15)
				(type solid)
			)
			(layer "F.SilkS")
		)
		(fp_line
			(start 3.898 14.098)
			(end 3.499 14.098)
			(stroke
				(width 0.15)
				(type solid)
			)
			(layer "F.SilkS")
		)
		(fp_line
			(start -1.401 14.098)
			(end -1.401 13.698)
			(stroke
				(width 0.15)
				(type solid)
			)
			(layer "F.SilkS")
		)
		(fp_line
			(start -1.401 14.098)
			(end -1 14.098)
			(stroke
				(width 0.15)
				(type solid)
			)
			(layer "F.SilkS")
		)
		(fp_line
			(start -1.52 -1.52)
			(end 4.04 -1.52)
			(stroke
				(width 0.05)
				(type solid)
			)
			(layer "F.CrtYd")
		)
		(fp_line
			(start 4.04 14.22)
			(end 4.04 -1.52)
			(stroke
				(width 0.05)
				(type solid)
			)
			(layer "F.CrtYd")
		)
		(fp_line
			(start -1.52 14.22)
			(end -1.52 -1.52)
			(stroke
				(width 0.05)
				(type solid)
			)
			(layer "F.CrtYd")
		)
		(fp_line
			(start -1.52 14.22)
			(end 4.04 14.22)
			(stroke
				(width 0.05)
				(type solid)
			)
			(layer "F.CrtYd")
		)
		(fp_line
			(start 3.809 -1.27)
			(end 3.809 13.97)
			(stroke
				(width 0.15)
				(type solid)
			)
			(layer "F.Fab")
		)
		(fp_line
			(start -1.27 -1.27)
			(end 3.809 -1.27)
			(stroke
				(width 0.15)
				(type solid)
			)
			(layer "F.Fab")
		)
		(fp_line
			(start -1.27 -1.27)
			(end -1.27 13.97)
			(stroke
				(width 0.15)
				(type solid)
			)
			(layer "F.Fab")
		)
		(fp_line
			(start -1.27 13.97)
			(end 3.809 13.97)
			(stroke
				(width 0.15)
				(type solid)
			)
			(layer "F.Fab")
		)
		(pad "1" thru_hole circle
			(at 0 0 90)
			(size 1.8 1.8)
			(drill 1.02)
			(layers "*.Cu" "*.Mask")
			(remove_unused_layers no)
			(net 55 "SPI0_CS_N")
			(pintype "passive")
		)
		(pad "2" thru_hole circle
			(at 0 2.539 90)
			(size 1.8 1.8)
			(drill 1.02)
			(layers "*.Cu" "*.Mask")
			(remove_unused_layers no)
			(net 57 "SPI0_MOSI")
			(pintype "passive")
		)
		(pad "3" thru_hole circle
			(at 0 5.078 90)
			(size 1.8 1.8)
			(drill 1.02)
			(layers "*.Cu" "*.Mask")
			(remove_unused_layers no)
			(net 58 "SPI0_MISO")
			(pintype "passive")
		)
		(pad "4" thru_hole circle
			(at 0 7.618 90)
			(size 1.8 1.8)
			(drill 1.02)
			(layers "*.Cu" "*.Mask")
			(remove_unused_layers no)
			(net 56 "SPI0_CLK")
			(pintype "passive")
		)
		(pad "5" thru_hole circle
			(at 0 10.159 90)
			(size 1.8 1.8)
			(drill 1.02)
			(layers "*.Cu" "*.Mask")
			(remove_unused_layers no)
			(net 1 "GND")
			(pintype "passive")
		)
		(pad "6" thru_hole circle
			(at 0 12.698 90)
			(size 1.8 1.8)
			(drill 1.02)
			(layers "*.Cu" "*.Mask")
			(remove_unused_layers no)
			(net 2 "VCC3V3")
			(pintype "passive")
		)
		(pad "7" thru_hole circle
			(at 2.539 0 90)
			(size 1.8 1.8)
			(drill 1.02)
			(layers "*.Cu" "*.Mask")
			(remove_unused_layers no)
			(net 592 "TPM_PIRQ#")
			(pintype "passive")
		)
		(pad "8" thru_hole circle
			(at 2.539 2.539 90)
			(size 1.8 1.8)
			(drill 1.02)
			(layers "*.Cu" "*.Mask")
			(remove_unused_layers no)
			(net 591 "TPM_RST")
			(pintype "passive")
		)
		(pad "9" thru_hole circle
			(at 2.539 5.078 90)
			(size 1.8 1.8)
			(drill 1.02)
			(layers "*.Cu" "*.Mask")
			(remove_unused_layers no)
			(net 590 "TPM_GPIO")
			(pintype "passive")
		)
		(pad "10" thru_hole circle
			(at 2.539 7.618 90)
			(size 1.8 1.8)
			(drill 1.02)
			(layers "*.Cu" "*.Mask")
			(remove_unused_layers no)
			(net 589 "TPM_PP")
			(pintype "passive")
		)
		(pad "11" thru_hole circle
			(at 2.539 10.159 90)
			(size 1.8 1.8)
			(drill 1.02)
			(layers "*.Cu" "*.Mask")
			(remove_unused_layers no)
			(net 1 "GND")
			(pintype "passive")
		)
		(pad "12" thru_hole circle
			(at 2.539 12.698 90)
			(size 1.8 1.8)
			(drill 1.02)
			(layers "*.Cu" "*.Mask")
			(remove_unused_layers no)
			(net 2 "VCC3V3")
			(pintype "passive")
		)
	)
	(footprint "antmicro-footprints:R_0402_1005Metric"
		(layer "F.Cu")
		(at 124.57 154.22 -90)
		(descr "Resistor SMD 0402")
		(tags "resistor SMD 0402")
		(property "Reference" "R20"
			(at -2.92 -0.33 90)
			(layer "F.SilkS")
			(effects
				(font
					(size 0.7 0.7)
					(thickness 0.15)
				)
				(justify right bottom)
			)
		)
		(property "Value" "R_10k_0402"
			(at 0 1.4 90)
			(layer "F.Fab")
			(effects
				(font
					(size 0.7 0.7)
					(thickness 0.15)
				)
				(justify right bottom)
			)
		)
		(property "Datasheet" "https://www.bourns.com/docs/product-datasheets/cr.pdf"
			(at 0 0 270)
			(layer "F.Fab")
			(hide yes)
			(effects
				(font
					(size 1.27 1.27)
					(thickness 0.15)
				)
			)
		)
		(property "Description" "SMD Chip Resistor, 10 kohm, ± 1%, 62.5 mW, 0402 [1005 Metric], Thick Film, General Purpose"
			(at 0 0 270)
			(layer "F.Fab")
			(hide yes)
			(effects
				(font
					(size 1.27 1.27)
					(thickness 0.15)
				)
			)
		)
		(property "Author" "Antmicro"
			(at -29.65 278.79 0)
			(layer "F.Fab")
			(hide yes)
			(effects
				(font
					(size 1 1)
					(thickness 0.15)
				)
			)
		)
		(property "License" "Apache-2.0"
			(at -29.65 278.79 0)
			(layer "F.Fab")
			(hide yes)
			(effects
				(font
					(size 1 1)
					(thickness 0.15)
				)
			)
		)
		(property "MPN" "CR0402-FX-1002GLF"
			(at -29.65 278.79 0)
			(layer "F.Fab")
			(hide yes)
			(effects
				(font
					(size 1 1)
					(thickness 0.15)
				)
			)
		)
		(property "Manufacturer" "Bourns"
			(at -29.65 278.79 0)
			(layer "F.Fab")
			(hide yes)
			(effects
				(font
					(size 1 1)
					(thickness 0.15)
				)
			)
		)
		(property "Tolerance" "1%"
			(at -29.65 278.79 0)
			(layer "F.Fab")
			(hide yes)
			(effects
				(font
					(size 1 1)
					(thickness 0.15)
				)
			)
		)
		(property "Val" "10k"
			(at -29.65 278.79 0)
			(layer "F.Fab")
			(hide yes)
			(effects
				(font
					(size 1 1)
					(thickness 0.15)
				)
			)
		)
		(sheetname "/PCIe-connector/")
		(sheetfile "pcie-conn.kicad_sch")
		(attr smd)
		(fp_rect
			(start -0.925 -0.47)
			(end 0.925 0.47)
			(stroke
				(width 0.05)
				(type default)
			)
			(fill no)
			(layer "F.CrtYd")
		)
		(fp_rect
			(start -0.5 -0.25)
			(end 0.5 0.25)
			(stroke
				(width 0.15)
				(type solid)
			)
			(fill no)
			(layer "F.Fab")
		)
		(pad "1" smd roundrect
			(at -0.48 0 270)
			(size 0.59 0.64)
			(layers "F.Cu" "F.Mask" "F.Paste")
			(roundrect_rratio 0.25)
			(net 5 "VCC1V8")
			(pintype "passive")
		)
		(pad "2" smd roundrect
			(at 0.48 0 270)
			(size 0.59 0.64)
			(layers "F.Cu" "F.Mask" "F.Paste")
			(roundrect_rratio 0.25)
			(net 264 "Net-(J2-ALERT)")
			(pintype "passive")
		)
	)
	(footprint "antmicro-footprints:R_0402_1005Metric"
		(layer "F.Cu")
		(at 129.975 115.675 180)
		(descr "Resistor SMD 0402")
		(tags "resistor SMD 0402")
		(property "Reference" "R5"
			(at 0.775 -0.425 0)
			(layer "F.SilkS")
			(effects
				(font
					(size 0.7 0.7)
					(thickness 0.15)
				)
				(justify right bottom)
			)
		)
		(property "Value" "R_12k_0402"
			(at 0 1.4 0)
			(layer "F.Fab")
			(effects
				(font
					(size 0.7 0.7)
					(thickness 0.15)
				)
				(justify right bottom)
			)
		)
		(property "Datasheet" "https://www.bourns.com/docs/product-datasheets/cr.pdf"
			(at 0 0 180)
			(layer "F.Fab")
			(hide yes)
			(effects
				(font
					(size 1.27 1.27)
					(thickness 0.15)
				)
			)
		)
		(property "Description" "SMD Chip Resistor, 12 kohm, ± 1%, 62.5 mW, 0402 [1005 Metric], Thick Film, General Purpose"
			(at 0 0 180)
			(layer "F.Fab")
			(hide yes)
			(effects
				(font
					(size 1.27 1.27)
					(thickness 0.15)
				)
			)
		)
		(property "Author" "Antmicro"
			(at 259.95 231.35 0)
			(layer "F.Fab")
			(hide yes)
			(effects
				(font
					(size 1 1)
					(thickness 0.15)
				)
			)
		)
		(property "License" "Apache-2.0"
			(at 259.95 231.35 0)
			(layer "F.Fab")
			(hide yes)
			(effects
				(font
					(size 1 1)
					(thickness 0.15)
				)
			)
		)
		(property "MPN" "CR0402-FX-1202GLF"
			(at 259.95 231.35 0)
			(layer "F.Fab")
			(hide yes)
			(effects
				(font
					(size 1 1)
					(thickness 0.15)
				)
			)
		)
		(property "Manufacturer" "Bourns"
			(at 259.95 231.35 0)
			(layer "F.Fab")
			(hide yes)
			(effects
				(font
					(size 1 1)
					(thickness 0.15)
				)
			)
		)
		(property "Tolerance" "1%"
			(at 259.95 231.35 0)
			(layer "F.Fab")
			(hide yes)
			(effects
				(font
					(size 1 1)
					(thickness 0.15)
				)
			)
		)
		(property "Val" "12k"
			(at 259.95 231.35 0)
			(layer "F.Fab")
			(hide yes)
			(effects
				(font
					(size 1 1)
					(thickness 0.15)
				)
			)
		)
		(sheetname "/Interfaces/")
		(sheetfile "interfaces.kicad_sch")
		(attr smd)
		(fp_rect
			(start -0.925 -0.47)
			(end 0.925 0.47)
			(stroke
				(width 0.05)
				(type default)
			)
			(fill no)
			(layer "F.CrtYd")
		)
		(fp_rect
			(start -0.5 -0.25)
			(end 0.5 0.25)
			(stroke
				(width 0.15)
				(type solid)
			)
			(fill no)
			(layer "F.Fab")
		)
		(pad "1" smd roundrect
			(at -0.48 0 180)
			(size 0.59 0.64)
			(layers "F.Cu" "F.Mask" "F.Paste")
			(roundrect_rratio 0.25)
			(net 1 "GND")
			(pintype "passive")
		)
		(pad "2" smd roundrect
			(at 0.48 0 180)
			(size 0.59 0.64)
			(layers "F.Cu" "F.Mask" "F.Paste")
			(roundrect_rratio 0.25)
			(net 300 "Net-(U17-RBIAS)")
			(pintype "passive")
		)
	)
	(footprint "antmicro-footprints:R_0402_1005Metric"
		(layer "F.Cu")
		(at 128.575 131.375 180)
		(descr "Resistor SMD 0402")
		(tags "resistor SMD 0402")
		(property "Reference" "R7"
			(at -2.225 -0.325 0)
			(layer "F.SilkS")
			(effects
				(font
					(size 0.7 0.7)
					(thickness 0.15)
				)
				(justify right bottom)
			)
		)
		(property "Value" "R_12k_0402"
			(at 0 1.4 0)
			(layer "F.Fab")
			(effects
				(font
					(size 0.7 0.7)
					(thickness 0.15)
				)
				(justify right bottom)
			)
		)
		(property "Datasheet" "https://www.bourns.com/docs/product-datasheets/cr.pdf"
			(at 0 0 180)
			(layer "F.Fab")
			(hide yes)
			(effects
				(font
					(size 1.27 1.27)
					(thickness 0.15)
				)
			)
		)
		(property "Description" "SMD Chip Resistor, 12 kohm, ± 1%, 62.5 mW, 0402 [1005 Metric], Thick Film, General Purpose"
			(at 0 0 180)
			(layer "F.Fab")
			(hide yes)
			(effects
				(font
					(size 1.27 1.27)
					(thickness 0.15)
				)
			)
		)
		(property "Author" "Antmicro"
			(at 257.15 262.75 0)
			(layer "F.Fab")
			(hide yes)
			(effects
				(font
					(size 1 1)
					(thickness 0.15)
				)
			)
		)
		(property "License" "Apache-2.0"
			(at 257.15 262.75 0)
			(layer "F.Fab")
			(hide yes)
			(effects
				(font
					(size 1 1)
					(thickness 0.15)
				)
			)
		)
		(property "MPN" "CR0402-FX-1202GLF"
			(at 257.15 262.75 0)
			(layer "F.Fab")
			(hide yes)
			(effects
				(font
					(size 1 1)
					(thickness 0.15)
				)
			)
		)
		(property "Manufacturer" "Bourns"
			(at 257.15 262.75 0)
			(layer "F.Fab")
			(hide yes)
			(effects
				(font
					(size 1 1)
					(thickness 0.15)
				)
			)
		)
		(property "Tolerance" "1%"
			(at 257.15 262.75 0)
			(layer "F.Fab")
			(hide yes)
			(effects
				(font
					(size 1 1)
					(thickness 0.15)
				)
			)
		)
		(property "Val" "12k"
			(at 257.15 262.75 0)
			(layer "F.Fab")
			(hide yes)
			(effects
				(font
					(size 1 1)
					(thickness 0.15)
				)
			)
		)
		(sheetname "/Interfaces/")
		(sheetfile "interfaces.kicad_sch")
		(attr smd)
		(fp_rect
			(start -0.925 -0.47)
			(end 0.925 0.47)
			(stroke
				(width 0.05)
				(type default)
			)
			(fill no)
			(layer "F.CrtYd")
		)
		(fp_rect
			(start -0.5 -0.25)
			(end 0.5 0.25)
			(stroke
				(width 0.15)
				(type solid)
			)
			(fill no)
			(layer "F.Fab")
		)
		(pad "1" smd roundrect
			(at -0.48 0 180)
			(size 0.59 0.64)
			(layers "F.Cu" "F.Mask" "F.Paste")
			(roundrect_rratio 0.25)
			(net 1 "GND")
			(pintype "passive")
		)
		(pad "2" smd roundrect
			(at 0.48 0 180)
			(size 0.59 0.64)
			(layers "F.Cu" "F.Mask" "F.Paste")
			(roundrect_rratio 0.25)
			(net 303 "Net-(U18-RBIAS)")
			(pintype "passive")
		)
	)
	(footprint "antmicro-footprints:R_0402_1005Metric"
		(layer "F.Cu")
		(at 129.975 116.775 180)
		(descr "Resistor SMD 0402")
		(tags "resistor SMD 0402")
		(property "Reference" "R10"
			(at 0.775 -0.425 0)
			(layer "F.SilkS")
			(effects
				(font
					(size 0.7 0.7)
					(thickness 0.15)
				)
				(justify right bottom)
			)
		)
		(property "Value" "R_0R_0402"
			(at 0 1.4 0)
			(layer "F.Fab")
			(effects
				(font
					(size 0.7 0.7)
					(thickness 0.15)
				)
				(justify right bottom)
			)
		)
		(property "Datasheet" "https://industrial.panasonic.com/cdbs/www-data/pdf/RDA0000/AOA0000C301.pdf"
			(at 0 0 180)
			(layer "F.Fab")
			(hide yes)
			(effects
				(font
					(size 1.27 1.27)
					(thickness 0.15)
				)
			)
		)
		(property "Description" "SMD Chip Resistor, Jumper, 0 ohm, 100 mW, 0402 [1005 Metric], Thick Film, General Purpose"
			(at 0 0 180)
			(layer "F.Fab")
			(hide yes)
			(effects
				(font
					(size 1.27 1.27)
					(thickness 0.15)
				)
			)
		)
		(property "Author" "Antmicro"
			(at 259.95 233.55 0)
			(layer "F.Fab")
			(hide yes)
			(effects
				(font
					(size 1 1)
					(thickness 0.15)
				)
			)
		)
		(property "Current" "1A"
			(at 259.95 233.55 0)
			(layer "F.Fab")
			(hide yes)
			(effects
				(font
					(size 1 1)
					(thickness 0.15)
				)
			)
		)
		(property "License" "Apache-2.0"
			(at 259.95 233.55 0)
			(layer "F.Fab")
			(hide yes)
			(effects
				(font
					(size 1 1)
					(thickness 0.15)
				)
			)
		)
		(property "MPN" "ERJ2GE0R00X"
			(at 259.95 233.55 0)
			(layer "F.Fab")
			(hide yes)
			(effects
				(font
					(size 1 1)
					(thickness 0.15)
				)
			)
		)
		(property "Manufacturer" "Panasonic"
			(at 259.95 233.55 0)
			(layer "F.Fab")
			(hide yes)
			(effects
				(font
					(size 1 1)
					(thickness 0.15)
				)
			)
		)
		(property "Tolerance" "~"
			(at 259.95 233.55 0)
			(layer "F.Fab")
			(hide yes)
			(effects
				(font
					(size 1 1)
					(thickness 0.15)
				)
			)
		)
		(property "Val" "0R"
			(at 259.95 233.55 0)
			(layer "F.Fab")
			(hide yes)
			(effects
				(font
					(size 1 1)
					(thickness 0.15)
				)
			)
		)
		(sheetname "/Interfaces/")
		(sheetfile "interfaces.kicad_sch")
		(attr smd)
		(fp_rect
			(start -0.925 -0.47)
			(end 0.925 0.47)
			(stroke
				(width 0.05)
				(type default)
			)
			(fill no)
			(layer "F.CrtYd")
		)
		(fp_rect
			(start -0.5 -0.25)
			(end 0.5 0.25)
			(stroke
				(width 0.15)
				(type solid)
			)
			(fill no)
			(layer "F.Fab")
		)
		(pad "1" smd roundrect
			(at -0.48 0 180)
			(size 0.59 0.64)
			(layers "F.Cu" "F.Mask" "F.Paste")
			(roundrect_rratio 0.25)
			(net 2 "VCC3V3")
			(pintype "passive")
		)
		(pad "2" smd roundrect
			(at 0.48 0 180)
			(size 0.59 0.64)
			(layers "F.Cu" "F.Mask" "F.Paste")
			(roundrect_rratio 0.25)
			(net 308 "Net-(U17-REG_EN)")
			(pintype "passive")
		)
	)
	(footprint "antmicro-footprints:R_0402_1005Metric"
		(layer "F.Cu")
		(at 128.575 132.475)
		(descr "Resistor SMD 0402")
		(tags "resistor SMD 0402")
		(property "Reference" "R11"
			(at 0.725 0.425 0)
			(layer "F.SilkS")
			(effects
				(font
					(size 0.7 0.7)
					(thickness 0.15)
				)
				(justify left bottom)
			)
		)
		(property "Value" "R_0R_0402"
			(at 0 1.4 0)
			(layer "F.Fab")
			(effects
				(font
					(size 0.7 0.7)
					(thickness 0.15)
				)
				(justify left bottom)
			)
		)
		(property "Datasheet" "https://industrial.panasonic.com/cdbs/www-data/pdf/RDA0000/AOA0000C301.pdf"
			(at 0 0 0)
			(layer "F.Fab")
			(hide yes)
			(effects
				(font
					(size 1.27 1.27)
					(thickness 0.15)
				)
			)
		)
		(property "Description" "SMD Chip Resistor, Jumper, 0 ohm, 100 mW, 0402 [1005 Metric], Thick Film, General Purpose"
			(at 0 0 0)
			(layer "F.Fab")
			(hide yes)
			(effects
				(font
					(size 1.27 1.27)
					(thickness 0.15)
				)
			)
		)
		(property "Author" "Antmicro"
			(at 0 0 0)
			(layer "F.Fab")
			(hide yes)
			(effects
				(font
					(size 1 1)
					(thickness 0.15)
				)
			)
		)
		(property "Current" "1A"
			(at 0 0 0)
			(layer "F.Fab")
			(hide yes)
			(effects
				(font
					(size 1 1)
					(thickness 0.15)
				)
			)
		)
		(property "License" "Apache-2.0"
			(at 0 0 0)
			(layer "F.Fab")
			(hide yes)
			(effects
				(font
					(size 1 1)
					(thickness 0.15)
				)
			)
		)
		(property "MPN" "ERJ2GE0R00X"
			(at 0 0 0)
			(layer "F.Fab")
			(hide yes)
			(effects
				(font
					(size 1 1)
					(thickness 0.15)
				)
			)
		)
		(property "Manufacturer" "Panasonic"
			(at 0 0 0)
			(layer "F.Fab")
			(hide yes)
			(effects
				(font
					(size 1 1)
					(thickness 0.15)
				)
			)
		)
		(property "Tolerance" "~"
			(at 0 0 0)
			(layer "F.Fab")
			(hide yes)
			(effects
				(font
					(size 1 1)
					(thickness 0.15)
				)
			)
		)
		(property "Val" "0R"
			(at 0 0 0)
			(layer "F.Fab")
			(hide yes)
			(effects
				(font
					(size 1 1)
					(thickness 0.15)
				)
			)
		)
		(sheetname "/Interfaces/")
		(sheetfile "interfaces.kicad_sch")
		(attr smd)
		(fp_rect
			(start -0.925 -0.47)
			(end 0.925 0.47)
			(stroke
				(width 0.05)
				(type default)
			)
			(fill no)
			(layer "F.CrtYd")
		)
		(fp_rect
			(start -0.5 -0.25)
			(end 0.5 0.25)
			(stroke
				(width 0.15)
				(type solid)
			)
			(fill no)
			(layer "F.Fab")
		)
		(pad "1" smd roundrect
			(at -0.48 0)
			(size 0.59 0.64)
			(layers "F.Cu" "F.Mask" "F.Paste")
			(roundrect_rratio 0.25)
			(net 310 "Net-(U18-REG_EN)")
			(pintype "passive")
		)
		(pad "2" smd roundrect
			(at 0.48 0)
			(size 0.59 0.64)
			(layers "F.Cu" "F.Mask" "F.Paste")
			(roundrect_rratio 0.25)
			(net 2 "VCC3V3")
			(pintype "passive")
		)
	)
	(footprint "antmicro-footprints:R_0402_1005Metric"
		(layer "F.Cu")
		(at 105.074 154.675 -90)
		(descr "Resistor SMD 0402")
		(tags "resistor SMD 0402")
		(property "Reference" "R13"
			(at 1.225 8.874 90)
			(layer "F.SilkS")
			(effects
				(font
					(size 0.7 0.7)
					(thickness 0.15)
				)
				(justify right bottom)
			)
		)
		(property "Value" "R_4k7_0402"
			(at 0 1.4 90)
			(layer "F.Fab")
			(effects
				(font
					(size 0.7 0.7)
					(thickness 0.15)
				)
				(justify right bottom)
			)
		)
		(property "Datasheet" "https://www.bourns.com/docs/product-datasheets/cr.pdf"
			(at 0 0 270)
			(layer "F.Fab")
			(hide yes)
			(effects
				(font
					(size 1.27 1.27)
					(thickness 0.15)
				)
			)
		)
		(property "Description" "SMD Chip Resistor, 4.7 kohm, ± 1%, 62.5 mW, 0402 [1005 Metric], Thick Film, General Purpose"
			(at 0 0 270)
			(layer "F.Fab")
			(hide yes)
			(effects
				(font
					(size 1.27 1.27)
					(thickness 0.15)
				)
			)
		)
		(property "Author" "Antmicro"
			(at -49.601 259.749 0)
			(layer "F.Fab")
			(hide yes)
			(effects
				(font
					(size 1 1)
					(thickness 0.15)
				)
			)
		)
		(property "License" "Apache-2.0"
			(at -49.601 259.749 0)
			(layer "F.Fab")
			(hide yes)
			(effects
				(font
					(size 1 1)
					(thickness 0.15)
				)
			)
		)
		(property "MPN" "CR0402-FX-4701GLF"
			(at -49.601 259.749 0)
			(layer "F.Fab")
			(hide yes)
			(effects
				(font
					(size 1 1)
					(thickness 0.15)
				)
			)
		)
		(property "Manufacturer" "Bourns"
			(at -49.601 259.749 0)
			(layer "F.Fab")
			(hide yes)
			(effects
				(font
					(size 1 1)
					(thickness 0.15)
				)
			)
		)
		(property "Tolerance" "1%"
			(at -49.601 259.749 0)
			(layer "F.Fab")
			(hide yes)
			(effects
				(font
					(size 1 1)
					(thickness 0.15)
				)
			)
		)
		(property "Val" "4k7"
			(at -49.601 259.749 0)
			(layer "F.Fab")
			(hide yes)
			(effects
				(font
					(size 1 1)
					(thickness 0.15)
				)
			)
		)
		(sheetname "/DDR3/")
		(sheetfile "ddr3.kicad_sch")
		(attr smd)
		(fp_rect
			(start -0.925 -0.47)
			(end 0.925 0.47)
			(stroke
				(width 0.05)
				(type default)
			)
			(fill no)
			(layer "F.CrtYd")
		)
		(fp_rect
			(start -0.5 -0.25)
			(end 0.5 0.25)
			(stroke
				(width 0.15)
				(type solid)
			)
			(fill no)
			(layer "F.Fab")
		)
		(pad "1" smd roundrect
			(at -0.48 0 270)
			(size 0.59 0.64)
			(layers "F.Cu" "F.Mask" "F.Paste")
			(roundrect_rratio 0.25)
			(net 191 "DDR3_RESET")
			(pintype "passive")
		)
		(pad "2" smd roundrect
			(at 0.48 0 270)
			(size 0.59 0.64)
			(layers "F.Cu" "F.Mask" "F.Paste")
			(roundrect_rratio 0.25)
			(net 1 "GND")
			(pintype "passive")
		)
	)
	(footprint "antmicro-footprints:R_0402_1005Metric"
		(layer "F.Cu")
		(at 129.775 112.175 90)
		(descr "Resistor SMD 0402")
		(tags "resistor SMD 0402")
		(property "Reference" "R6"
			(at 0.775 0.425 90)
			(layer "F.SilkS")
			(effects
				(font
					(size 0.7 0.7)
					(thickness 0.15)
				)
				(justify left bottom)
			)
		)
		(property "Value" "R_1k_0402"
			(at 0 1.4 90)
			(layer "F.Fab")
			(effects
				(font
					(size 0.7 0.7)
					(thickness 0.15)
				)
				(justify left bottom)
			)
		)
		(property "Datasheet" "https://www.bourns.com/docs/product-datasheets/cr.pdf"
			(at 0 0 90)
			(layer "F.Fab")
			(hide yes)
			(effects
				(font
					(size 1.27 1.27)
					(thickness 0.15)
				)
			)
		)
		(property "Description" "SMD Chip Resistor, 1 kohm, ± 1%, 63 mW, 0402 [1005 Metric], Thick Film, General Purpose"
			(at 0 0 90)
			(layer "F.Fab")
			(hide yes)
			(effects
				(font
					(size 1.27 1.27)
					(thickness 0.15)
				)
			)
		)
		(property "Author" "Antmicro"
			(at 241.95 -17.6 0)
			(layer "F.Fab")
			(hide yes)
			(effects
				(font
					(size 1 1)
					(thickness 0.15)
				)
			)
		)
		(property "License" "Apache-2.0"
			(at 241.95 -17.6 0)
			(layer "F.Fab")
			(hide yes)
			(effects
				(font
					(size 1 1)
					(thickness 0.15)
				)
			)
		)
		(property "MPN" "CR0402-FX-1001GLF"
			(at 241.95 -17.6 0)
			(layer "F.Fab")
			(hide yes)
			(effects
				(font
					(size 1 1)
					(thickness 0.15)
				)
			)
		)
		(property "Manufacturer" "Bourns"
			(at 241.95 -17.6 0)
			(layer "F.Fab")
			(hide yes)
			(effects
				(font
					(size 1 1)
					(thickness 0.15)
				)
			)
		)
		(property "Tolerance" "1%"
			(at 241.95 -17.6 0)
			(layer "F.Fab")
			(hide yes)
			(effects
				(font
					(size 1 1)
					(thickness 0.15)
				)
			)
		)
		(property "Val" "1k"
			(at 241.95 -17.6 0)
			(layer "F.Fab")
			(hide yes)
			(effects
				(font
					(size 1 1)
					(thickness 0.15)
				)
			)
		)
		(sheetname "/Interfaces/")
		(sheetfile "interfaces.kicad_sch")
		(attr smd)
		(fp_rect
			(start -0.925 -0.47)
			(end 0.925 0.47)
			(stroke
				(width 0.05)
				(type default)
			)
			(fill no)
			(layer "F.CrtYd")
		)
		(fp_rect
			(start -0.5 -0.25)
			(end 0.5 0.25)
			(stroke
				(width 0.15)
				(type solid)
			)
			(fill no)
			(layer "F.Fab")
		)
		(pad "1" smd roundrect
			(at -0.48 0 90)
			(size 0.59 0.64)
			(layers "F.Cu" "F.Mask" "F.Paste")
			(roundrect_rratio 0.25)
			(net 4 "VCC5V0")
			(pintype "passive")
		)
		(pad "2" smd roundrect
			(at 0.48 0 90)
			(size 0.59 0.64)
			(layers "F.Cu" "F.Mask" "F.Paste")
			(roundrect_rratio 0.25)
			(net 302 "Net-(U17-VBUS)")
			(pintype "passive")
		)
	)
	(footprint "antmicro-footprints:R_0402_1005Metric"
		(layer "F.Cu")
		(at 129.075 128.175 90)
		(descr "Resistor SMD 0402")
		(tags "resistor SMD 0402")
		(property "Reference" "R8"
			(at 0.775 0.425 90)
			(layer "F.SilkS")
			(effects
				(font
					(size 0.7 0.7)
					(thickness 0.15)
				)
				(justify left bottom)
			)
		)
		(property "Value" "R_1k_0402"
			(at 0 1.4 90)
			(layer "F.Fab")
			(effects
				(font
					(size 0.7 0.7)
					(thickness 0.15)
				)
				(justify left bottom)
			)
		)
		(property "Datasheet" "https://www.bourns.com/docs/product-datasheets/cr.pdf"
			(at 0 0 90)
			(layer "F.Fab")
			(hide yes)
			(effects
				(font
					(size 1.27 1.27)
					(thickness 0.15)
				)
			)
		)
		(property "Description" "SMD Chip Resistor, 1 kohm, ± 1%, 63 mW, 0402 [1005 Metric], Thick Film, General Purpose"
			(at 0 0 90)
			(layer "F.Fab")
			(hide yes)
			(effects
				(font
					(size 1.27 1.27)
					(thickness 0.15)
				)
			)
		)
		(property "Author" "Antmicro"
			(at 257.25 -0.9 0)
			(layer "F.Fab")
			(hide yes)
			(effects
				(font
					(size 1 1)
					(thickness 0.15)
				)
			)
		)
		(property "License" "Apache-2.0"
			(at 257.25 -0.9 0)
			(layer "F.Fab")
			(hide yes)
			(effects
				(font
					(size 1 1)
					(thickness 0.15)
				)
			)
		)
		(property "MPN" "CR0402-FX-1001GLF"
			(at 257.25 -0.9 0)
			(layer "F.Fab")
			(hide yes)
			(effects
				(font
					(size 1 1)
					(thickness 0.15)
				)
			)
		)
		(property "Manufacturer" "Bourns"
			(at 257.25 -0.9 0)
			(layer "F.Fab")
			(hide yes)
			(effects
				(font
					(size 1 1)
					(thickness 0.15)
				)
			)
		)
		(property "Tolerance" "1%"
			(at 257.25 -0.9 0)
			(layer "F.Fab")
			(hide yes)
			(effects
				(font
					(size 1 1)
					(thickness 0.15)
				)
			)
		)
		(property "Val" "1k"
			(at 257.25 -0.9 0)
			(layer "F.Fab")
			(hide yes)
			(effects
				(font
					(size 1 1)
					(thickness 0.15)
				)
			)
		)
		(sheetname "/Interfaces/")
		(sheetfile "interfaces.kicad_sch")
		(attr smd)
		(fp_rect
			(start -0.925 -0.47)
			(end 0.925 0.47)
			(stroke
				(width 0.05)
				(type default)
			)
			(fill no)
			(layer "F.CrtYd")
		)
		(fp_rect
			(start -0.5 -0.25)
			(end 0.5 0.25)
			(stroke
				(width 0.15)
				(type solid)
			)
			(fill no)
			(layer "F.Fab")
		)
		(pad "1" smd roundrect
			(at -0.48 0 90)
			(size 0.59 0.64)
			(layers "F.Cu" "F.Mask" "F.Paste")
			(roundrect_rratio 0.25)
			(net 4 "VCC5V0")
			(pintype "passive")
		)
		(pad "2" smd roundrect
			(at 0.48 0 90)
			(size 0.59 0.64)
			(layers "F.Cu" "F.Mask" "F.Paste")
			(roundrect_rratio 0.25)
			(net 304 "Net-(U18-VBUS)")
			(pintype "passive")
		)
	)
	(footprint "antmicro-footprints:QFN-32-1EP_5x5mm"
		(layer "F.Cu")
		(at 125.175 111.375 180)
		(property "Reference" "U17"
			(at -0.925 3.175 180)
			(layer "F.SilkS")
			(effects
				(font
					(size 0.7 0.7)
					(thickness 0.15)
				)
				(justify left bottom)
			)
		)
		(property "Value" "USB3300-EZK-TR"
			(at -4.94 3.91 180)
			(layer "F.Fab")
			(effects
				(font
					(size 0.7 0.7)
					(thickness 0.15)
				)
				(justify left bottom)
			)
		)
		(property "Datasheet" "https://ww1.microchip.com/downloads/en/DeviceDoc/00001783C.pdf"
			(at 0 0 180)
			(layer "F.Fab")
			(hide yes)
			(effects
				(font
					(size 1.27 1.27)
					(thickness 0.15)
				)
			)
		)
		(property "Description" "USB Interface, USB Host Controller, USB 2.0 OTG, 3 V, 3.6 V, VQFN, 32 Pins"
			(at 0 0 180)
			(layer "F.Fab")
			(hide yes)
			(effects
				(font
					(size 1.27 1.27)
					(thickness 0.15)
				)
			)
		)
		(property "Author" "Antmicro"
			(at 250.35 222.75 0)
			(layer "F.Fab")
			(hide yes)
			(effects
				(font
					(size 1 1)
					(thickness 0.15)
				)
			)
		)
		(property "License" "Apache-2.0"
			(at 250.35 222.75 0)
			(layer "F.Fab")
			(hide yes)
			(effects
				(font
					(size 1 1)
					(thickness 0.15)
				)
			)
		)
		(property "MPN" "USB3300-EZK-TR"
			(at 250.35 222.75 0)
			(layer "F.Fab")
			(hide yes)
			(effects
				(font
					(size 1 1)
					(thickness 0.15)
				)
			)
		)
		(property "Manufacturer" "Microchip Technology"
			(at 250.35 222.75 0)
			(layer "F.Fab")
			(hide yes)
			(effects
				(font
					(size 1 1)
					(thickness 0.15)
				)
			)
		)
		(sheetname "/Interfaces/")
		(sheetfile "interfaces.kicad_sch")
		(attr smd)
		(fp_line
			(start 2.581 2.648)
			(end 2.178 2.648)
			(stroke
				(width 0.15)
				(type solid)
			)
			(layer "F.SilkS")
		)
		(fp_line
			(start 2.581 2.249)
			(end 2.581 2.648)
			(stroke
				(width 0.15)
				(type solid)
			)
			(layer "F.SilkS")
		)
		(fp_line
			(start 2.581 -2.551)
			(end 2.581 -2.149)
			(stroke
				(width 0.15)
				(type solid)
			)
			(layer "F.SilkS")
		)
		(fp_line
			(start 2.581 -2.551)
			(end 2.178 -2.551)
			(stroke
				(width 0.15)
				(type solid)
			)
			(layer "F.SilkS")
		)
		(fp_line
			(start -2.221 2.648)
			(end -2.62 2.648)
			(stroke
				(width 0.15)
				(type solid)
			)
			(layer "F.SilkS")
		)
		(fp_line
			(start -2.221 -2.551)
			(end -2.62 -2.149)
			(stroke
				(width 0.15)
				(type solid)
			)
			(layer "F.SilkS")
		)
		(fp_line
			(start -2.62 2.648)
			(end -2.62 2.249)
			(stroke
				(width 0.15)
				(type solid)
			)
			(layer "F.SilkS")
		)
		(fp_circle
			(center -3.25 -1.702)
			(end -3.2 -1.702)
			(stroke
				(width 0.15)
				(type solid)
			)
			(fill yes)
			(layer "F.SilkS")
		)
		(fp_rect
			(start 0.203 1.474)
			(end 1.403 0.274)
			(stroke
				(width 0.2)
				(type solid)
			)
			(fill yes)
			(layer "F.Paste")
		)
		(fp_rect
			(start 0.203 -0.175)
			(end 1.403 -1.375)
			(stroke
				(width 0.2)
				(type solid)
			)
			(fill yes)
			(layer "F.Paste")
		)
		(fp_rect
			(start -1.446 1.474)
			(end -0.246 0.274)
			(stroke
				(width 0.2)
				(type solid)
			)
			(fill yes)
			(layer "F.Paste")
		)
		(fp_rect
			(start -1.446 -0.175)
			(end -0.246 -1.375)
			(stroke
				(width 0.2)
				(type solid)
			)
			(fill yes)
			(layer "F.Paste")
		)
		(fp_rect
			(start -2.74 -2.75)
			(end 2.75 2.74)
			(stroke
				(width 0.05)
				(type solid)
			)
			(fill no)
			(layer "F.CrtYd")
		)
		(fp_line
			(start -2.499 -2.299)
			(end -2.298 -2.5)
			(stroke
				(width 0.15)
				(type solid)
			)
			(layer "F.Fab")
		)
		(fp_rect
			(start -2.499 -2.5)
			(end 2.5 2.499)
			(stroke
				(width 0.15)
				(type solid)
			)
			(fill no)
			(layer "F.Fab")
		)
		(pad "1" smd rect
			(at -2.495 -1.702 90)
			(size 0.28 0.85)
			(layers "F.Cu" "F.Mask" "F.Paste")
			(net 1 "GND")
			(pinfunction "GND")
			(pintype "power_in")
			(solder_mask_margin 0.07)
		)
		(pad "2" smd rect
			(at -2.495 -1.2 90)
			(size 0.28 0.85)
			(layers "F.Cu" "F.Mask" "F.Paste")
			(net 1 "GND")
			(pinfunction "GND")
			(pintype "passive")
			(solder_mask_margin 0.07)
		)
		(pad "3" smd rect
			(at -2.495 -0.701 90)
			(size 0.28 0.85)
			(layers "F.Cu" "F.Mask" "F.Paste")
			(net 647 "unconnected-(U17-CPEN-Pad3)")
			(pinfunction "CPEN")
			(pintype "output+no_connect")
			(solder_mask_margin 0.07)
		)
		(pad "4" smd rect
			(at -2.495 -0.201 90)
			(size 0.28 0.85)
			(layers "F.Cu" "F.Mask" "F.Paste")
			(net 302 "Net-(U17-VBUS)")
			(pinfunction "VBUS")
			(pintype "bidirectional")
			(solder_mask_margin 0.07)
		)
		(pad "5" smd rect
			(at -2.495 0.296 90)
			(size 0.28 0.85)
			(layers "F.Cu" "F.Mask" "F.Paste")
			(net 648 "unconnected-(U17-ID-Pad5)")
			(pinfunction "ID")
			(pintype "input+no_connect")
			(solder_mask_margin 0.07)
		)
		(pad "6" smd rect
			(at -2.495 0.8 90)
			(size 0.28 0.85)
			(layers "F.Cu" "F.Mask" "F.Paste")
			(net 2 "VCC3V3")
			(pinfunction "VDD3.3")
			(pintype "power_in")
			(solder_mask_margin 0.07)
		)
		(pad "7" smd rect
			(at -2.495 1.3 90)
			(size 0.28 0.85)
			(layers "F.Cu" "F.Mask" "F.Paste")
			(net 385 "USB1_D_P")
			(pinfunction "DP")
			(pintype "bidirectional")
			(solder_mask_margin 0.07)
		)
		(pad "8" smd rect
			(at -2.495 1.8 90)
			(size 0.28 0.85)
			(layers "F.Cu" "F.Mask" "F.Paste")
			(net 386 "USB1_D_N")
			(pinfunction "DM")
			(pintype "bidirectional")
			(solder_mask_margin 0.07)
		)
		(pad "9" smd rect
			(at -1.768 2.523 90)
			(size 0.85 0.28)
			(layers "F.Cu" "F.Mask" "F.Paste")
			(net 442 "ULPI1_RESET")
			(pinfunction "RESET")
			(pintype "input")
			(solder_mask_margin 0.07)
		)
		(pad "10" smd rect
			(at -1.269 2.523 90)
			(size 0.85 0.28)
			(layers "F.Cu" "F.Mask" "F.Paste")
			(net 649 "unconnected-(U17-EXTVBUS-Pad10)")
			(pinfunction "EXTVBUS")
			(pintype "input+no_connect")
			(solder_mask_margin 0.07)
		)
		(pad "11" smd rect
			(at -0.772 2.523 90)
			(size 0.85 0.28)
			(layers "F.Cu" "F.Mask" "F.Paste")
			(net 444 "ULPI1_NXT")
			(pinfunction "NXT")
			(pintype "output")
			(solder_mask_margin 0.07)
		)
		(pad "12" smd rect
			(at -0.272 2.523 90)
			(size 0.85 0.28)
			(layers "F.Cu" "F.Mask" "F.Paste")
			(net 445 "ULPI1_DIR")
			(pinfunction "DIR")
			(pintype "output")
			(solder_mask_margin 0.07)
		)
		(pad "13" smd rect
			(at 0.229 2.523 90)
			(size 0.85 0.28)
			(layers "F.Cu" "F.Mask" "F.Paste")
			(net 446 "ULPI1_STP")
			(pinfunction "STP")
			(pintype "input")
			(solder_mask_margin 0.07)
		)
		(pad "14" smd rect
			(at 0.728 2.523 90)
			(size 0.85 0.28)
			(layers "F.Cu" "F.Mask" "F.Paste")
			(net 447 "ULPI1_CLKOUT")
			(pinfunction "CLKOUT")
			(pintype "output")
			(solder_mask_margin 0.07)
		)
		(pad "15" smd rect
			(at 1.23 2.523 90)
			(size 0.85 0.28)
			(layers "F.Cu" "F.Mask" "F.Paste")
			(net 105 "Net-(C20-Pad2)")
			(pinfunction "VDD1.8")
			(pintype "power_in")
			(solder_mask_margin 0.07)
		)
		(pad "16" smd rect
			(at 1.73 2.523 90)
			(size 0.85 0.28)
			(layers "F.Cu" "F.Mask" "F.Paste")
			(net 2 "VCC3V3")
			(pinfunction "VDD3.3")
			(pintype "passive")
			(solder_mask_margin 0.07)
		)
		(pad "17" smd rect
			(at 2.456 1.8 90)
			(size 0.28 0.85)
			(layers "F.Cu" "F.Mask" "F.Paste")
			(net 448 "ULPI1_DATA7")
			(pinfunction "DATA[7]")
			(pintype "bidirectional")
			(solder_mask_margin 0.07)
		)
		(pad "18" smd rect
			(at 2.456 1.3 90)
			(size 0.28 0.85)
			(layers "F.Cu" "F.Mask" "F.Paste")
			(net 449 "ULPI1_DATA6")
			(pinfunction "DATA[6]")
			(pintype "bidirectional")
			(solder_mask_margin 0.07)
		)
		(pad "19" smd rect
			(at 2.456 0.8 90)
			(size 0.28 0.85)
			(layers "F.Cu" "F.Mask" "F.Paste")
			(net 450 "ULPI1_DATA5")
			(pinfunction "DATA[5]")
			(pintype "bidirectional")
			(solder_mask_margin 0.07)
		)
		(pad "20" smd rect
			(at 2.456 0.296 90)
			(size 0.28 0.85)
			(layers "F.Cu" "F.Mask" "F.Paste")
			(net 451 "ULPI1_DATA4")
			(pinfunction "DATA[4]")
			(pintype "bidirectional")
			(solder_mask_margin 0.07)
		)
		(pad "21" smd rect
			(at 2.456 -0.201 90)
			(size 0.28 0.85)
			(layers "F.Cu" "F.Mask" "F.Paste")
			(net 452 "ULPI1_DATA3")
			(pinfunction "DATA[3]")
			(pintype "bidirectional")
			(solder_mask_margin 0.07)
		)
		(pad "22" smd rect
			(at 2.456 -0.701 90)
			(size 0.28 0.85)
			(layers "F.Cu" "F.Mask" "F.Paste")
			(net 453 "ULPI1_DATA2")
			(pinfunction "DATA[2]")
			(pintype "bidirectional")
			(solder_mask_margin 0.07)
		)
		(pad "23" smd rect
			(at 2.456 -1.2 90)
			(size 0.28 0.85)
			(layers "F.Cu" "F.Mask" "F.Paste")
			(net 454 "ULPI1_DATA1")
			(pinfunction "DATA[1]")
			(pintype "bidirectional")
			(solder_mask_margin 0.07)
		)
		(pad "24" smd rect
			(at 2.456 -1.702 90)
			(size 0.28 0.85)
			(layers "F.Cu" "F.Mask" "F.Paste")
			(net 455 "ULPI1_DATA0")
			(pinfunction "DATA[0]")
			(pintype "bidirectional")
			(solder_mask_margin 0.07)
		)
		(pad "25" smd rect
			(at 1.73 -2.426 90)
			(size 0.85 0.28)
			(layers "F.Cu" "F.Mask" "F.Paste")
			(net 2 "VCC3V3")
			(pinfunction "VDD3.3")
			(pintype "passive")
			(solder_mask_margin 0.07)
		)
		(pad "26" smd rect
			(at 1.23 -2.426 90)
			(size 0.85 0.28)
			(layers "F.Cu" "F.Mask" "F.Paste")
			(net 105 "Net-(C20-Pad2)")
			(pinfunction "VDD1.8")
			(pintype "passive")
			(solder_mask_margin 0.07)
		)
		(pad "27" smd rect
			(at 0.728 -2.426 90)
			(size 0.85 0.28)
			(layers "F.Cu" "F.Mask" "F.Paste")
			(net 650 "unconnected-(U17-XO-Pad27)")
			(pinfunction "XO")
			(pintype "output+no_connect")
			(solder_mask_margin 0.07)
		)
		(pad "28" smd rect
			(at 0.229 -2.426 90)
			(size 0.85 0.28)
			(layers "F.Cu" "F.Mask" "F.Paste")
			(net 651 "Net-(U17-XI)")
			(pinfunction "XI")
			(pintype "input")
			(solder_mask_margin 0.07)
		)
		(pad "29" smd rect
			(at -0.272 -2.426 90)
			(size 0.85 0.28)
			(layers "F.Cu" "F.Mask" "F.Paste")
			(net 12 "Net-(U17-VDDA1.8)")
			(pinfunction "VDDA1.8")
			(pintype "power_in")
			(solder_mask_margin 0.07)
		)
		(pad "30" smd rect
			(at -0.772 -2.426 90)
			(size 0.85 0.28)
			(layers "F.Cu" "F.Mask" "F.Paste")
			(net 2 "VCC3V3")
			(pinfunction "VDD3.3")
			(pintype "passive")
			(solder_mask_margin 0.07)
		)
		(pad "31" smd rect
			(at -1.269 -2.426 90)
			(size 0.85 0.28)
			(layers "F.Cu" "F.Mask" "F.Paste")
			(net 308 "Net-(U17-REG_EN)")
			(pinfunction "REG_EN")
			(pintype "bidirectional")
			(solder_mask_margin 0.07)
		)
		(pad "32" smd rect
			(at -1.768 -2.426 90)
			(size 0.85 0.28)
			(layers "F.Cu" "F.Mask" "F.Paste")
			(net 300 "Net-(U17-RBIAS)")
			(pinfunction "RBIAS")
			(pintype "bidirectional")
			(solder_mask_margin 0.07)
		)
		(pad "33" smd rect
			(at -0.02 0.048 90)
			(size 3.45 3.45)
			(layers "F.Cu" "F.Mask")
			(net 1 "GND")
			(pinfunction "EP")
			(pintype "passive")
		)
	)
	(footprint "antmicro-footprints:QFN-32-1EP_5x5mm"
		(layer "F.Cu")
		(at 124.995 127.525 180)
		(property "Reference" "U18"
			(at -0.905 3.125 180)
			(layer "F.SilkS")
			(effects
				(font
					(size 0.7 0.7)
					(thickness 0.15)
				)
				(justify left bottom)
			)
		)
		(property "Value" "USB3300-EZK-TR"
			(at -4.94 3.91 180)
			(layer "F.Fab")
			(effects
				(font
					(size 0.7 0.7)
					(thickness 0.15)
				)
				(justify left bottom)
			)
		)
		(property "Datasheet" "https://ww1.microchip.com/downloads/en/DeviceDoc/00001783C.pdf"
			(at 0 0 180)
			(layer "F.Fab")
			(hide yes)
			(effects
				(font
					(size 1.27 1.27)
					(thickness 0.15)
				)
			)
		)
		(property "Description" "USB Interface, USB Host Controller, USB 2.0 OTG, 3 V, 3.6 V, VQFN, 32 Pins"
			(at 0 0 180)
			(layer "F.Fab")
			(hide yes)
			(effects
				(font
					(size 1.27 1.27)
					(thickness 0.15)
				)
			)
		)
		(property "Author" "Antmicro"
			(at 249.99 255.05 0)
			(layer "F.Fab")
			(hide yes)
			(effects
				(font
					(size 1 1)
					(thickness 0.15)
				)
			)
		)
		(property "License" "Apache-2.0"
			(at 249.99 255.05 0)
			(layer "F.Fab")
			(hide yes)
			(effects
				(font
					(size 1 1)
					(thickness 0.15)
				)
			)
		)
		(property "MPN" "USB3300-EZK-TR"
			(at 249.99 255.05 0)
			(layer "F.Fab")
			(hide yes)
			(effects
				(font
					(size 1 1)
					(thickness 0.15)
				)
			)
		)
		(property "Manufacturer" "Microchip Technology"
			(at 249.99 255.05 0)
			(layer "F.Fab")
			(hide yes)
			(effects
				(font
					(size 1 1)
					(thickness 0.15)
				)
			)
		)
		(sheetname "/Interfaces/")
		(sheetfile "interfaces.kicad_sch")
		(attr smd)
		(fp_line
			(start 2.581 2.648)
			(end 2.178 2.648)
			(stroke
				(width 0.15)
				(type solid)
			)
			(layer "F.SilkS")
		)
		(fp_line
			(start 2.581 2.249)
			(end 2.581 2.648)
			(stroke
				(width 0.15)
				(type solid)
			)
			(layer "F.SilkS")
		)
		(fp_line
			(start 2.581 -2.551)
			(end 2.581 -2.149)
			(stroke
				(width 0.15)
				(type solid)
			)
			(layer "F.SilkS")
		)
		(fp_line
			(start 2.581 -2.551)
			(end 2.178 -2.551)
			(stroke
				(width 0.15)
				(type solid)
			)
			(layer "F.SilkS")
		)
		(fp_line
			(start -2.221 2.648)
			(end -2.62 2.648)
			(stroke
				(width 0.15)
				(type solid)
			)
			(layer "F.SilkS")
		)
		(fp_line
			(start -2.221 -2.551)
			(end -2.62 -2.149)
			(stroke
				(width 0.15)
				(type solid)
			)
			(layer "F.SilkS")
		)
		(fp_line
			(start -2.62 2.648)
			(end -2.62 2.249)
			(stroke
				(width 0.15)
				(type solid)
			)
			(layer "F.SilkS")
		)
		(fp_circle
			(center -3.25 -1.702)
			(end -3.2 -1.702)
			(stroke
				(width 0.15)
				(type solid)
			)
			(fill yes)
			(layer "F.SilkS")
		)
		(fp_rect
			(start 0.203 1.474)
			(end 1.403 0.274)
			(stroke
				(width 0.2)
				(type solid)
			)
			(fill yes)
			(layer "F.Paste")
		)
		(fp_rect
			(start 0.203 -0.175)
			(end 1.403 -1.375)
			(stroke
				(width 0.2)
				(type solid)
			)
			(fill yes)
			(layer "F.Paste")
		)
		(fp_rect
			(start -1.446 1.474)
			(end -0.246 0.274)
			(stroke
				(width 0.2)
				(type solid)
			)
			(fill yes)
			(layer "F.Paste")
		)
		(fp_rect
			(start -1.446 -0.175)
			(end -0.246 -1.375)
			(stroke
				(width 0.2)
				(type solid)
			)
			(fill yes)
			(layer "F.Paste")
		)
		(fp_rect
			(start -2.74 -2.75)
			(end 2.75 2.74)
			(stroke
				(width 0.05)
				(type solid)
			)
			(fill no)
			(layer "F.CrtYd")
		)
		(fp_line
			(start -2.499 -2.299)
			(end -2.298 -2.5)
			(stroke
				(width 0.15)
				(type solid)
			)
			(layer "F.Fab")
		)
		(fp_rect
			(start -2.499 -2.5)
			(end 2.5 2.499)
			(stroke
				(width 0.15)
				(type solid)
			)
			(fill no)
			(layer "F.Fab")
		)
		(pad "1" smd rect
			(at -2.495 -1.702 90)
			(size 0.28 0.85)
			(layers "F.Cu" "F.Mask" "F.Paste")
			(net 1 "GND")
			(pinfunction "GND")
			(pintype "power_in")
			(solder_mask_margin 0.07)
		)
		(pad "2" smd rect
			(at -2.495 -1.2 90)
			(size 0.28 0.85)
			(layers "F.Cu" "F.Mask" "F.Paste")
			(net 1 "GND")
			(pinfunction "GND")
			(pintype "passive")
			(solder_mask_margin 0.07)
		)
		(pad "3" smd rect
			(at -2.495 -0.701 90)
			(size 0.28 0.85)
			(layers "F.Cu" "F.Mask" "F.Paste")
			(net 652 "unconnected-(U18-CPEN-Pad3)")
			(pinfunction "CPEN")
			(pintype "output+no_connect")
			(solder_mask_margin 0.07)
		)
		(pad "4" smd rect
			(at -2.495 -0.201 90)
			(size 0.28 0.85)
			(layers "F.Cu" "F.Mask" "F.Paste")
			(net 304 "Net-(U18-VBUS)")
			(pinfunction "VBUS")
			(pintype "bidirectional")
			(solder_mask_margin 0.07)
		)
		(pad "5" smd rect
			(at -2.495 0.296 90)
			(size 0.28 0.85)
			(layers "F.Cu" "F.Mask" "F.Paste")
			(net 653 "unconnected-(U18-ID-Pad5)")
			(pinfunction "ID")
			(pintype "input+no_connect")
			(solder_mask_margin 0.07)
		)
		(pad "6" smd rect
			(at -2.495 0.8 90)
			(size 0.28 0.85)
			(layers "F.Cu" "F.Mask" "F.Paste")
			(net 2 "VCC3V3")
			(pinfunction "VDD3.3")
			(pintype "power_in")
			(solder_mask_margin 0.07)
		)
		(pad "7" smd rect
			(at -2.495 1.3 90)
			(size 0.28 0.85)
			(layers "F.Cu" "F.Mask" "F.Paste")
			(net 383 "USB2_D_P")
			(pinfunction "DP")
			(pintype "bidirectional")
			(solder_mask_margin 0.07)
		)
		(pad "8" smd rect
			(at -2.495 1.8 90)
			(size 0.28 0.85)
			(layers "F.Cu" "F.Mask" "F.Paste")
			(net 384 "USB2_D_N")
			(pinfunction "DM")
			(pintype "bidirectional")
			(solder_mask_margin 0.07)
		)
		(pad "9" smd rect
			(at -1.768 2.523 90)
			(size 0.85 0.28)
			(layers "F.Cu" "F.Mask" "F.Paste")
			(net 457 "ULPI2_RESET")
			(pinfunction "RESET")
			(pintype "input")
			(solder_mask_margin 0.07)
		)
		(pad "10" smd rect
			(at -1.269 2.523 90)
			(size 0.85 0.28)
			(layers "F.Cu" "F.Mask" "F.Paste")
			(net 654 "unconnected-(U18-EXTVBUS-Pad10)")
			(pinfunction "EXTVBUS")
			(pintype "input+no_connect")
			(solder_mask_margin 0.07)
		)
		(pad "11" smd rect
			(at -0.772 2.523 90)
			(size 0.85 0.28)
			(layers "F.Cu" "F.Mask" "F.Paste")
			(net 458 "ULPI2_NXT")
			(pinfunction "NXT")
			(pintype "output")
			(solder_mask_margin 0.07)
		)
		(pad "12" smd rect
			(at -0.272 2.523 90)
			(size 0.85 0.28)
			(layers "F.Cu" "F.Mask" "F.Paste")
			(net 459 "ULPI2_DIR")
			(pinfunction "DIR")
			(pintype "output")
			(solder_mask_margin 0.07)
		)
		(pad "13" smd rect
			(at 0.229 2.523 90)
			(size 0.85 0.28)
			(layers "F.Cu" "F.Mask" "F.Paste")
			(net 460 "ULPI2_STP")
			(pinfunction "STP")
			(pintype "input")
			(solder_mask_margin 0.07)
		)
		(pad "14" smd rect
			(at 0.728 2.523 90)
			(size 0.85 0.28)
			(layers "F.Cu" "F.Mask" "F.Paste")
			(net 461 "ULPI2_CLKOUT")
			(pinfunction "CLKOUT")
			(pintype "output")
			(solder_mask_margin 0.07)
		)
		(pad "15" smd rect
			(at 1.23 2.523 90)
			(size 0.85 0.28)
			(layers "F.Cu" "F.Mask" "F.Paste")
			(net 108 "Net-(C177-Pad2)")
			(pinfunction "VDD1.8")
			(pintype "power_in")
			(solder_mask_margin 0.07)
		)
		(pad "16" smd rect
			(at 1.73 2.523 90)
			(size 0.85 0.28)
			(layers "F.Cu" "F.Mask" "F.Paste")
			(net 2 "VCC3V3")
			(pinfunction "VDD3.3")
			(pintype "passive")
			(solder_mask_margin 0.07)
		)
		(pad "17" smd rect
			(at 2.456 1.8 90)
			(size 0.28 0.85)
			(layers "F.Cu" "F.Mask" "F.Paste")
			(net 462 "ULPI2_DATA7")
			(pinfunction "DATA[7]")
			(pintype "bidirectional")
			(solder_mask_margin 0.07)
		)
		(pad "18" smd rect
			(at 2.456 1.3 90)
			(size 0.28 0.85)
			(layers "F.Cu" "F.Mask" "F.Paste")
			(net 463 "ULPI2_DATA6")
			(pinfunction "DATA[6]")
			(pintype "bidirectional")
			(solder_mask_margin 0.07)
		)
		(pad "19" smd rect
			(at 2.456 0.8 90)
			(size 0.28 0.85)
			(layers "F.Cu" "F.Mask" "F.Paste")
			(net 464 "ULPI2_DATA5")
			(pinfunction "DATA[5]")
			(pintype "bidirectional")
			(solder_mask_margin 0.07)
		)
		(pad "20" smd rect
			(at 2.456 0.296 90)
			(size 0.28 0.85)
			(layers "F.Cu" "F.Mask" "F.Paste")
			(net 465 "ULPI2_DATA4")
			(pinfunction "DATA[4]")
			(pintype "bidirectional")
			(solder_mask_margin 0.07)
		)
		(pad "21" smd rect
			(at 2.456 -0.201 90)
			(size 0.28 0.85)
			(layers "F.Cu" "F.Mask" "F.Paste")
			(net 466 "ULPI2_DATA3")
			(pinfunction "DATA[3]")
			(pintype "bidirectional")
			(solder_mask_margin 0.07)
		)
		(pad "22" smd rect
			(at 2.456 -0.701 90)
			(size 0.28 0.85)
			(layers "F.Cu" "F.Mask" "F.Paste")
			(net 467 "ULPI2_DATA2")
			(pinfunction "DATA[2]")
			(pintype "bidirectional")
			(solder_mask_margin 0.07)
		)
		(pad "23" smd rect
			(at 2.456 -1.2 90)
			(size 0.28 0.85)
			(layers "F.Cu" "F.Mask" "F.Paste")
			(net 468 "ULPI2_DATA1")
			(pinfunction "DATA[1]")
			(pintype "bidirectional")
			(solder_mask_margin 0.07)
		)
		(pad "24" smd rect
			(at 2.456 -1.702 90)
			(size 0.28 0.85)
			(layers "F.Cu" "F.Mask" "F.Paste")
			(net 469 "ULPI2_DATA0")
			(pinfunction "DATA[0]")
			(pintype "bidirectional")
			(solder_mask_margin 0.07)
		)
		(pad "25" smd rect
			(at 1.73 -2.426 90)
			(size 0.85 0.28)
			(layers "F.Cu" "F.Mask" "F.Paste")
			(net 2 "VCC3V3")
			(pinfunction "VDD3.3")
			(pintype "passive")
			(solder_mask_margin 0.07)
		)
		(pad "26" smd rect
			(at 1.23 -2.426 90)
			(size 0.85 0.28)
			(layers "F.Cu" "F.Mask" "F.Paste")
			(net 108 "Net-(C177-Pad2)")
			(pinfunction "VDD1.8")
			(pintype "passive")
			(solder_mask_margin 0.07)
		)
		(pad "27" smd rect
			(at 0.728 -2.426 90)
			(size 0.85 0.28)
			(layers "F.Cu" "F.Mask" "F.Paste")
			(net 655 "unconnected-(U18-XO-Pad27)")
			(pinfunction "XO")
			(pintype "output+no_connect")
			(solder_mask_margin 0.07)
		)
		(pad "28" smd rect
			(at 0.229 -2.426 90)
			(size 0.85 0.28)
			(layers "F.Cu" "F.Mask" "F.Paste")
			(net 656 "Net-(U18-XI)")
			(pinfunction "XI")
			(pintype "input")
			(solder_mask_margin 0.07)
		)
		(pad "29" smd rect
			(at -0.272 -2.426 90)
			(size 0.85 0.28)
			(layers "F.Cu" "F.Mask" "F.Paste")
			(net 11 "Net-(U18-VDDA1.8)")
			(pinfunction "VDDA1.8")
			(pintype "power_in")
			(solder_mask_margin 0.07)
		)
		(pad "30" smd rect
			(at -0.772 -2.426 90)
			(size 0.85 0.28)
			(layers "F.Cu" "F.Mask" "F.Paste")
			(net 2 "VCC3V3")
			(pinfunction "VDD3.3")
			(pintype "passive")
			(solder_mask_margin 0.07)
		)
		(pad "31" smd rect
			(at -1.269 -2.426 90)
			(size 0.85 0.28)
			(layers "F.Cu" "F.Mask" "F.Paste")
			(net 310 "Net-(U18-REG_EN)")
			(pinfunction "REG_EN")
			(pintype "bidirectional")
			(solder_mask_margin 0.07)
		)
		(pad "32" smd rect
			(at -1.768 -2.426 90)
			(size 0.85 0.28)
			(layers "F.Cu" "F.Mask" "F.Paste")
			(net 303 "Net-(U18-RBIAS)")
			(pinfunction "RBIAS")
			(pintype "bidirectional")
			(solder_mask_margin 0.07)
		)
		(pad "33" smd rect
			(at -0.02 0.048 90)
			(size 3.45 3.45)
			(layers "F.Cu" "F.Mask")
			(net 1 "GND")
			(pinfunction "EP")
			(pintype "passive")
		)
	)
	(footprint "antmicro-footprints:C_0402_1005Metric"
		(layer "F.Cu")
		(at 103.374 140.075 -90)
		(descr "Capacitor SMD 0402")
		(tags "capacitor SMD 0402")
		(property "Reference" "C8"
			(at -2.275 -0.326 90)
			(layer "F.SilkS")
			(effects
				(font
					(size 0.7 0.7)
					(thickness 0.15)
				)
				(justify right bottom)
			)
		)
		(property "Value" "C_470n_0402"
			(at 0 1.4 90)
			(layer "F.Fab")
			(effects
				(font
					(size 0.7 0.7)
					(thickness 0.15)
				)
				(justify right bottom)
			)
		)
		(property "Datasheet" "https://product.tdk.com/en/search/capacitor/ceramic/mlcc/info?part_no=C1005X5R1E474M050BB"
			(at 0 0 270)
			(layer "F.Fab")
			(hide yes)
			(effects
				(font
					(size 1.27 1.27)
					(thickness 0.15)
				)
			)
		)
		(property "Description" "SMD Multilayer Ceramic Capacitor, 0.47 µF, 25 V, 0402 [1005 Metric], ± 20%, X5R, C"
			(at 0 0 270)
			(layer "F.Fab")
			(hide yes)
			(effects
				(font
					(size 1.27 1.27)
					(thickness 0.15)
				)
			)
		)
		(property "Author" "Antmicro"
			(at -36.701 243.449 0)
			(layer "F.Fab")
			(hide yes)
			(effects
				(font
					(size 1 1)
					(thickness 0.15)
				)
			)
		)
		(property "Dielectric" ""
			(at -36.701 243.449 0)
			(layer "F.Fab")
			(hide yes)
			(effects
				(font
					(size 1 1)
					(thickness 0.15)
				)
			)
		)
		(property "License" "Apache-2.0"
			(at -36.701 243.449 0)
			(layer "F.Fab")
			(hide yes)
			(effects
				(font
					(size 1 1)
					(thickness 0.15)
				)
			)
		)
		(property "MPN" "C1005X5R1E474M050BB"
			(at -36.701 243.449 0)
			(layer "F.Fab")
			(hide yes)
			(effects
				(font
					(size 1 1)
					(thickness 0.15)
				)
			)
		)
		(property "Manufacturer" "TDK"
			(at -36.701 243.449 0)
			(layer "F.Fab")
			(hide yes)
			(effects
				(font
					(size 1 1)
					(thickness 0.15)
				)
			)
		)
		(property "Val" "470n"
			(at -36.701 243.449 0)
			(layer "F.Fab")
			(hide yes)
			(effects
				(font
					(size 1 1)
					(thickness 0.15)
				)
			)
		)
		(property "Voltage" ""
			(at -36.701 243.449 0)
			(layer "F.Fab")
			(hide yes)
			(effects
				(font
					(size 1 1)
					(thickness 0.15)
				)
			)
		)
		(sheetname "/DDR3/")
		(sheetfile "ddr3.kicad_sch")
		(attr smd)
		(fp_rect
			(start -0.925 -0.47)
			(end 0.925 0.47)
			(stroke
				(width 0.05)
				(type default)
			)
			(fill no)
			(layer "F.CrtYd")
		)
		(fp_line
			(start -0.494 0.248)
			(end -0.494 -0.25)
			(stroke
				(width 0.15)
				(type solid)
			)
			(layer "F.Fab")
		)
		(fp_line
			(start 0.504 0.248)
			(end -0.494 0.248)
			(stroke
				(width 0.15)
				(type solid)
			)
			(layer "F.Fab")
		)
		(fp_line
			(start -0.494 -0.25)
			(end 0.504 -0.25)
			(stroke
				(width 0.15)
				(type solid)
			)
			(layer "F.Fab")
		)
		(fp_line
			(start 0.504 -0.25)
			(end 0.504 0.248)
			(stroke
				(width 0.15)
				(type solid)
			)
			(layer "F.Fab")
		)
		(pad "1" smd roundrect
			(at -0.48 0 270)
			(size 0.59 0.64)
			(layers "F.Cu" "F.Mask" "F.Paste")
			(roundrect_rratio 0.25)
			(net 1 "GND")
			(pintype "passive")
		)
		(pad "2" smd roundrect
			(at 0.48 0 270)
			(size 0.59 0.64)
			(layers "F.Cu" "F.Mask" "F.Paste")
			(roundrect_rratio 0.25)
			(net 3 "VCC1V35")
			(pintype "passive")
		)
	)
	(footprint "antmicro-footprints:C_0402_1005Metric"
		(layer "F.Cu")
		(at 91.774 140.075 -90)
		(descr "Capacitor SMD 0402")
		(tags "capacitor SMD 0402")
		(property "Reference" "C9"
			(at -2.375 -0.326 90)
			(layer "F.SilkS")
			(effects
				(font
					(size 0.7 0.7)
					(thickness 0.15)
				)
				(justify right bottom)
			)
		)
		(property "Value" "C_470n_0402"
			(at 0 1.4 90)
			(layer "F.Fab")
			(effects
				(font
					(size 0.7 0.7)
					(thickness 0.15)
				)
				(justify right bottom)
			)
		)
		(property "Datasheet" "https://product.tdk.com/en/search/capacitor/ceramic/mlcc/info?part_no=C1005X5R1E474M050BB"
			(at 0 0 270)
			(layer "F.Fab")
			(hide yes)
			(effects
				(font
					(size 1.27 1.27)
					(thickness 0.15)
				)
			)
		)
		(property "Description" "SMD Multilayer Ceramic Capacitor, 0.47 µF, 25 V, 0402 [1005 Metric], ± 20%, X5R, C"
			(at 0 0 270)
			(layer "F.Fab")
			(hide yes)
			(effects
				(font
					(size 1.27 1.27)
					(thickness 0.15)
				)
			)
		)
		(property "Author" "Antmicro"
			(at -48.301 231.849 0)
			(layer "F.Fab")
			(hide yes)
			(effects
				(font
					(size 1 1)
					(thickness 0.15)
				)
			)
		)
		(property "Dielectric" ""
			(at -48.301 231.849 0)
			(layer "F.Fab")
			(hide yes)
			(effects
				(font
					(size 1 1)
					(thickness 0.15)
				)
			)
		)
		(property "License" "Apache-2.0"
			(at -48.301 231.849 0)
			(layer "F.Fab")
			(hide yes)
			(effects
				(font
					(size 1 1)
					(thickness 0.15)
				)
			)
		)
		(property "MPN" "C1005X5R1E474M050BB"
			(at -48.301 231.849 0)
			(layer "F.Fab")
			(hide yes)
			(effects
				(font
					(size 1 1)
					(thickness 0.15)
				)
			)
		)
		(property "Manufacturer" "TDK"
			(at -48.301 231.849 0)
			(layer "F.Fab")
			(hide yes)
			(effects
				(font
					(size 1 1)
					(thickness 0.15)
				)
			)
		)
		(property "Val" "470n"
			(at -48.301 231.849 0)
			(layer "F.Fab")
			(hide yes)
			(effects
				(font
					(size 1 1)
					(thickness 0.15)
				)
			)
		)
		(property "Voltage" ""
			(at -48.301 231.849 0)
			(layer "F.Fab")
			(hide yes)
			(effects
				(font
					(size 1 1)
					(thickness 0.15)
				)
			)
		)
		(sheetname "/DDR3/")
		(sheetfile "ddr3.kicad_sch")
		(attr smd)
		(fp_rect
			(start -0.925 -0.47)
			(end 0.925 0.47)
			(stroke
				(width 0.05)
				(type default)
			)
			(fill no)
			(layer "F.CrtYd")
		)
		(fp_line
			(start -0.494 0.248)
			(end -0.494 -0.25)
			(stroke
				(width 0.15)
				(type solid)
			)
			(layer "F.Fab")
		)
		(fp_line
			(start 0.504 0.248)
			(end -0.494 0.248)
			(stroke
				(width 0.15)
				(type solid)
			)
			(layer "F.Fab")
		)
		(fp_line
			(start -0.494 -0.25)
			(end 0.504 -0.25)
			(stroke
				(width 0.15)
				(type solid)
			)
			(layer "F.Fab")
		)
		(fp_line
			(start 0.504 -0.25)
			(end 0.504 0.248)
			(stroke
				(width 0.15)
				(type solid)
			)
			(layer "F.Fab")
		)
		(pad "1" smd roundrect
			(at -0.48 0 270)
			(size 0.59 0.64)
			(layers "F.Cu" "F.Mask" "F.Paste")
			(roundrect_rratio 0.25)
			(net 1 "GND")
			(pintype "passive")
		)
		(pad "2" smd roundrect
			(at 0.48 0 270)
			(size 0.59 0.64)
			(layers "F.Cu" "F.Mask" "F.Paste")
			(roundrect_rratio 0.25)
			(net 3 "VCC1V35")
			(pintype "passive")
		)
	)
	(footprint "antmicro-footprints:SOIC-8_5.3x5.3x2mm_P1.27mm"
		(layer "F.Cu")
		(at 66.45 147.405 90)
		(descr "8-Pin SOIC 208-mil")
		(property "Reference" "U5"
			(at -0.0015 -3.2 90)
			(layer "F.SilkS")
			(effects
				(font
					(size 0.7 0.7)
					(thickness 0.15)
				)
				(justify left bottom)
			)
		)
		(property "Value" "W25Q32JW_SOIC-8"
			(at 0 3.8 90)
			(layer "F.Fab")
			(effects
				(font
					(size 0.7 0.7)
					(thickness 0.15)
				)
				(justify left bottom)
			)
		)
		(property "Datasheet" "https://www.mouser.com/datasheet/2/949/w25q32jw_spi_revf_09042018-1489621.pdf"
			(at 0 0 90)
			(layer "F.Fab")
			(hide yes)
			(effects
				(font
					(size 1.27 1.27)
					(thickness 0.15)
				)
			)
		)
		(property "Description" "FLASH - NOR Memory IC 32Mbit SPI - Quad I/O 133 MHz 8-SOIC"
			(at 0 0 90)
			(layer "F.Fab")
			(hide yes)
			(effects
				(font
					(size 1.27 1.27)
					(thickness 0.15)
				)
			)
		)
		(property "Author" "Antmicro"
			(at 213.855 80.955 0)
			(layer "F.Fab")
			(hide yes)
			(effects
				(font
					(size 1 1)
					(thickness 0.15)
				)
			)
		)
		(property "License" "Apache-2.0"
			(at 213.855 80.955 0)
			(layer "F.Fab")
			(hide yes)
			(effects
				(font
					(size 1 1)
					(thickness 0.15)
				)
			)
		)
		(property "MPN" "W25Q32JWSSIQ"
			(at 213.855 80.955 0)
			(layer "F.Fab")
			(hide yes)
			(effects
				(font
					(size 1 1)
					(thickness 0.15)
				)
			)
		)
		(property "Manufacturer" "Winbond"
			(at 213.855 80.955 0)
			(layer "F.Fab")
			(hide yes)
			(effects
				(font
					(size 1 1)
					(thickness 0.15)
				)
			)
		)
		(sheetname "/RoT/")
		(sheetfile "rot.kicad_sch")
		(attr smd)
		(fp_line
			(start -2.8 -2.641)
			(end -4.4 -2.641)
			(stroke
				(width 0.15)
				(type solid)
			)
			(layer "F.SilkS")
		)
		(fp_circle
			(center -4.85 -1.905)
			(end -4.8 -1.855)
			(stroke
				(width 0.15)
				(type solid)
			)
			(fill yes)
			(layer "F.SilkS")
		)
		(fp_rect
			(start 4.675 -3)
			(end -4.675 3)
			(stroke
				(width 0.05)
				(type solid)
			)
			(fill no)
			(layer "F.CrtYd")
		)
		(fp_line
			(start 2.64 -2.641)
			(end 2.64 2.64)
			(stroke
				(width 0.15)
				(type solid)
			)
			(layer "F.Fab")
		)
		(fp_line
			(start -2.641 -2.641)
			(end 2.64 -2.641)
			(stroke
				(width 0.15)
				(type solid)
			)
			(layer "F.Fab")
		)
		(fp_line
			(start -2.641 -1.371)
			(end -1.371 -2.641)
			(stroke
				(width 0.15)
				(type solid)
			)
			(layer "F.Fab")
		)
		(fp_line
			(start 2.64 2.64)
			(end -2.641 2.64)
			(stroke
				(width 0.15)
				(type solid)
			)
			(layer "F.Fab")
		)
		(fp_line
			(start -2.641 2.64)
			(end -2.641 -2.641)
			(stroke
				(width 0.15)
				(type solid)
			)
			(layer "F.Fab")
		)
		(pad "1" smd roundrect
			(at -3.601 -1.905 180)
			(size 0.65 1.65)
			(layers "F.Cu" "F.Mask" "F.Paste")
			(roundrect_rratio 0.25)
			(net 135 "QSPIA1_CS_N")
			(pinfunction "~{CS}")
			(pintype "input")
		)
		(pad "2" smd roundrect
			(at -3.601 -0.635 180)
			(size 0.65 1.65)
			(layers "F.Cu" "F.Mask" "F.Paste")
			(roundrect_rratio 0.25)
			(net 132 "QSPIA1_D1")
			(pinfunction "SO/IO1")
			(pintype "bidirectional")
		)
		(pad "3" smd roundrect
			(at -3.601 0.633 180)
			(size 0.65 1.65)
			(layers "F.Cu" "F.Mask" "F.Paste")
			(roundrect_rratio 0.25)
			(net 133 "QSPIA1_D2")
			(pinfunction "~{WP}/IO2")
			(pintype "bidirectional")
		)
		(pad "4" smd roundrect
			(at -3.601 1.904 180)
			(size 0.65 1.65)
			(layers "F.Cu" "F.Mask" "F.Paste")
			(roundrect_rratio 0.25)
			(net 1 "GND")
			(pinfunction "VSS")
			(pintype "power_in")
		)
		(pad "5" smd roundrect
			(at 3.6 1.904 180)
			(size 0.65 1.65)
			(layers "F.Cu" "F.Mask" "F.Paste")
			(roundrect_rratio 0.25)
			(net 131 "QSPIA1_D0")
			(pinfunction "SI/IO0")
			(pintype "bidirectional")
		)
		(pad "6" smd roundrect
			(at 3.6 0.633 180)
			(size 0.65 1.65)
			(layers "F.Cu" "F.Mask" "F.Paste")
			(roundrect_rratio 0.25)
			(net 130 "QSPIA_CLK")
			(pinfunction "SCLK")
			(pintype "input")
		)
		(pad "7" smd roundrect
			(at 3.6 -0.635 180)
			(size 0.65 1.65)
			(layers "F.Cu" "F.Mask" "F.Paste")
			(roundrect_rratio 0.25)
			(net 134 "QSPIA1_D3")
			(pinfunction "~{HOLD}/IO3")
			(pintype "bidirectional")
		)
		(pad "8" smd roundrect
			(at 3.6 -1.905 180)
			(size 0.65 1.65)
			(layers "F.Cu" "F.Mask" "F.Paste")
			(roundrect_rratio 0.25)
			(net 2 "VCC3V3")
			(pinfunction "VCC")
			(pintype "power_in")
		)
	)
	(footprint "antmicro-footprints:RJ45_BEL_L834-1G1T-S7"
		(layer "F.Cu")
		(at 99.595 80.835 180)
		(property "Reference" "J1"
			(at -13.505 -4.165 180)
			(layer "F.SilkS")
			(effects
				(font
					(size 0.7 0.7)
					(thickness 0.15)
				)
				(justify left bottom)
			)
		)
		(property "Value" "L834-1G1T-S7"
			(at -2.92 -5.906 180)
			(layer "F.Fab")
			(effects
				(font
					(size 0.7 0.7)
					(thickness 0.15)
				)
				(justify left bottom)
			)
		)
		(property "Datasheet" "https://www.belfuse.com/resources/drawings/magneticsolutions/dr-mag-l834-1g1t-s7.pdf"
			(at 0 0 180)
			(layer "F.Fab")
			(hide yes)
			(effects
				(font
					(size 1.27 1.27)
					(thickness 0.15)
				)
			)
		)
		(property "Description" "Modular connector with magnetics"
			(at 0 0 180)
			(layer "F.Fab")
			(hide yes)
			(effects
				(font
					(size 1.27 1.27)
					(thickness 0.15)
				)
			)
		)
		(property "Author" "Antmicro"
			(at 199.19 161.67 0)
			(layer "F.Fab")
			(hide yes)
			(effects
				(font
					(size 1 1)
					(thickness 0.15)
				)
			)
		)
		(property "License" "Apache-2.0"
			(at 199.19 161.67 0)
			(layer "F.Fab")
			(hide yes)
			(effects
				(font
					(size 1 1)
					(thickness 0.15)
				)
			)
		)
		(property "MPN" "L834-1G1T-S7"
			(at 199.19 161.67 0)
			(layer "F.Fab")
			(hide yes)
			(effects
				(font
					(size 1 1)
					(thickness 0.15)
				)
			)
		)
		(property "Manufacturer" "Bel Fuse"
			(at 199.19 161.67 0)
			(layer "F.Fab")
			(hide yes)
			(effects
				(font
					(size 1 1)
					(thickness 0.15)
				)
			)
		)
		(sheetname "/Ethernet/")
		(sheetfile "ethernet.kicad_sch")
		(attr through_hole)
		(fp_line
			(start 3.179 12.53)
			(end 3.179 18.158)
			(stroke
				(width 0.15)
				(type solid)
			)
			(layer "F.SilkS")
		)
		(fp_line
			(start 3.179 8.13)
			(end 3.179 9.529)
			(stroke
				(width 0.15)
				(type solid)
			)
			(layer "F.SilkS")
		)
		(fp_line
			(start 3.179 -4.121)
			(end 3.179 1.929)
			(stroke
				(width 0.15)
				(type solid)
			)
			(layer "F.SilkS")
		)
		(fp_line
			(start 3.179 -4.121)
			(end -13.34 -4.121)
			(stroke
				(width 0.15)
				(type solid)
			)
			(layer "F.SilkS")
		)
		(fp_line
			(start -13.34 10.13)
			(end -13.34 18.158)
			(stroke
				(width 0.15)
				(type solid)
			)
			(layer "F.SilkS")
		)
		(fp_line
			(start -13.34 2.53)
			(end -13.34 3.93)
			(stroke
				(width 0.15)
				(type solid)
			)
			(layer "F.SilkS")
		)
		(fp_line
			(start -13.34 -4.121)
			(end -13.34 -0.471)
			(stroke
				(width 0.15)
				(type solid)
			)
			(layer "F.SilkS")
		)
		(fp_line
			(start 4.87 22.19)
			(end -15.06 22.19)
			(stroke
				(width 0.05)
				(type solid)
			)
			(layer "F.CrtYd")
		)
		(fp_line
			(start 4.87 -0.3)
			(end 4.87 22.19)
			(stroke
				(width 0.05)
				(type solid)
			)
			(layer "F.CrtYd")
		)
		(fp_line
			(start 4.87 -0.3)
			(end 3.5 -0.3)
			(stroke
				(width 0.05)
				(type solid)
			)
			(layer "F.CrtYd")
		)
		(fp_line
			(start 3.5 -0.3)
			(end 3.5 -4.4)
			(stroke
				(width 0.05)
				(type solid)
			)
			(layer "F.CrtYd")
		)
		(fp_line
			(start -13.6 -0.3)
			(end -13.6 -4.4)
			(stroke
				(width 0.05)
				(type solid)
			)
			(layer "F.CrtYd")
		)
		(fp_line
			(start -13.6 -0.3)
			(end -15.06 -0.3)
			(stroke
				(width 0.05)
				(type solid)
			)
			(layer "F.CrtYd")
		)
		(fp_line
			(start -13.6 -4.4)
			(end 3.5 -4.4)
			(stroke
				(width 0.05)
				(type solid)
			)
			(layer "F.CrtYd")
		)
		(fp_line
			(start -15.06 22.19)
			(end -15.06 -0.3)
			(stroke
				(width 0.05)
				(type solid)
			)
			(layer "F.CrtYd")
		)
		(fp_line
			(start 3.179 21.94)
			(end 3.179 -4.121)
			(stroke
				(width 0.15)
				(type solid)
			)
			(layer "F.Fab")
		)
		(fp_line
			(start 3.179 -4.121)
			(end -13.34 -4.121)
			(stroke
				(width 0.15)
				(type solid)
			)
			(layer "F.Fab")
		)
		(fp_line
			(start -13.34 21.94)
			(end 3.179 21.94)
			(stroke
				(width 0.15)
				(type solid)
			)
			(layer "F.Fab")
		)
		(fp_line
			(start -13.34 -4.121)
			(end -13.34 21.94)
			(stroke
				(width 0.15)
				(type solid)
			)
			(layer "F.Fab")
		)
		(fp_arc
			(start 4.578 14.192)
			(mid 4.389 18.158)
			(end 3.179 21.94)
			(stroke
				(width 0.15)
				(type solid)
			)
			(layer "F.Fab")
		)
		(fp_arc
			(start -13.34 21.94)
			(mid -14.551 18.158)
			(end -14.74 14.192)
			(stroke
				(width 0.15)
				(type solid)
			)
			(layer "F.Fab")
		)
		(pad "" np_thru_hole circle
			(at -13.235 1.009 180)
			(size 2.31 2.31)
			(drill 2.31)
			(layers "*.Cu" "*.Mask")
		)
		(pad "" np_thru_hole circle
			(at -13.235 8.63 180)
			(size 2.31 2.31)
			(drill 2.31)
			(layers "*.Cu" "*.Mask")
		)
		(pad "" np_thru_hole circle
			(at 3.073 3.43 180)
			(size 2.31 2.31)
			(drill 2.31)
			(layers "*.Cu" "*.Mask")
		)
		(pad "" np_thru_hole circle
			(at 3.073 11.047 180)
			(size 2.31 2.31)
			(drill 2.31)
			(layers "*.Cu" "*.Mask")
		)
		(pad "1" thru_hole rect
			(at 0 0 180)
			(size 1.53 1.53)
			(drill 1.02)
			(layers "*.Cu" "*.Mask")
			(remove_unused_layers no)
			(net 204 "Net-(J1-TRCT3)")
			(pinfunction "TRCT3")
			(pintype "passive")
		)
		(pad "2" thru_hole circle
			(at -2.032 0 180)
			(size 1.53 1.53)
			(drill 1.02)
			(layers "*.Cu" "*.Mask")
			(remove_unused_layers no)
			(net 430 "/Ethernet/ETH3_N")
			(pinfunction "TRD3-")
			(pintype "passive")
		)
		(pad "3" thru_hole circle
			(at -4.064 0 180)
			(size 1.53 1.53)
			(drill 1.02)
			(layers "*.Cu" "*.Mask")
			(remove_unused_layers no)
			(net 431 "/Ethernet/ETH3_P")
			(pinfunction "TRD3+")
			(pintype "passive")
		)
		(pad "4" thru_hole circle
			(at -6.096 0 180)
			(size 1.53 1.53)
			(drill 1.02)
			(layers "*.Cu" "*.Mask")
			(remove_unused_layers no)
			(net 433 "/Ethernet/ETH2_P")
			(pinfunction "TRD2+")
			(pintype "passive")
		)
		(pad "5" thru_hole circle
			(at -8.128 0 180)
			(size 1.53 1.53)
			(drill 1.02)
			(layers "*.Cu" "*.Mask")
			(remove_unused_layers no)
			(net 432 "/Ethernet/ETH2_N")
			(pinfunction "TRD2-")
			(pintype "passive")
		)
		(pad "6" thru_hole circle
			(at -10.16 0 180)
			(size 1.53 1.53)
			(drill 1.02)
			(layers "*.Cu" "*.Mask")
			(remove_unused_layers no)
			(net 203 "Net-(J1-TRCT2)")
			(pinfunction "TRCT2")
			(pintype "passive")
		)
		(pad "7" thru_hole circle
			(at 1.015 -2.54 180)
			(size 1.53 1.53)
			(drill 1.02)
			(layers "*.Cu" "*.Mask")
			(remove_unused_layers no)
			(net 206 "Net-(J1-TRCT4)")
			(pinfunction "TRCT4")
			(pintype "passive")
		)
		(pad "8" thru_hole circle
			(at -1.016 -2.54 180)
			(size 1.53 1.53)
			(drill 1.02)
			(layers "*.Cu" "*.Mask")
			(remove_unused_layers no)
			(net 429 "/Ethernet/ETH4_P")
			(pinfunction "TRD4+")
			(pintype "passive")
		)
		(pad "9" thru_hole circle
			(at -3.048 -2.54 180)
			(size 1.53 1.53)
			(drill 1.02)
			(layers "*.Cu" "*.Mask")
			(remove_unused_layers no)
			(net 428 "/Ethernet/ETH4_N")
			(pinfunction "TRD4-")
			(pintype "passive")
		)
		(pad "10" thru_hole circle
			(at -7.112 -2.54 180)
			(size 1.53 1.53)
			(drill 1.02)
			(layers "*.Cu" "*.Mask")
			(remove_unused_layers no)
			(net 434 "/Ethernet/ETH1_N")
			(pinfunction "TRD1-")
			(pintype "passive")
		)
		(pad "11" thru_hole circle
			(at -9.144 -2.54 180)
			(size 1.53 1.53)
			(drill 1.02)
			(layers "*.Cu" "*.Mask")
			(remove_unused_layers no)
			(net 435 "/Ethernet/ETH1_P")
			(pinfunction "TRD1+")
			(pintype "passive")
		)
		(pad "12" thru_hole circle
			(at -11.176 -2.54 180)
			(size 1.53 1.53)
			(drill 1.02)
			(layers "*.Cu" "*.Mask")
			(remove_unused_layers no)
			(net 202 "Net-(J1-TRCT1)")
			(pinfunction "TRCT1")
			(pintype "passive")
		)
		(pad "13" thru_hole circle
			(at 1.945 13.97 180)
			(size 1.725 1.725)
			(drill 1.15)
			(layers "*.Cu" "*.Mask")
			(remove_unused_layers no)
			(net 575 "Net-(J1-Pad13)")
			(pintype "passive")
		)
		(pad "14" thru_hole circle
			(at 1.945 16.508 180)
			(size 1.725 1.725)
			(drill 1.15)
			(layers "*.Cu" "*.Mask")
			(remove_unused_layers no)
			(net 2 "VCC3V3")
			(pintype "passive")
		)
		(pad "15" thru_hole circle
			(at -12.106 13.97 180)
			(size 1.725 1.725)
			(drill 1.15)
			(layers "*.Cu" "*.Mask")
			(remove_unused_layers no)
			(net 574 "Net-(J1-Pad15)")
			(pintype "passive")
		)
		(pad "16" thru_hole circle
			(at -12.106 16.508 180)
			(size 1.725 1.725)
			(drill 1.15)
			(layers "*.Cu" "*.Mask")
			(remove_unused_layers no)
			(net 2 "VCC3V3")
			(pintype "passive")
		)
		(pad "SH" thru_hole circle
			(at -13.235 5.328 180)
			(size 2.1 2.1)
			(drill 1.4)
			(layers "*.Cu" "*.Mask")
			(remove_unused_layers no)
			(net 1 "GND")
			(pinfunction "SH")
			(pintype "passive")
		)
		(pad "SH" thru_hole circle
			(at 3.073 6.73 180)
			(size 2.1 2.1)
			(drill 1.4)
			(layers "*.Cu" "*.Mask")
			(remove_unused_layers no)
			(net 1 "GND")
			(pinfunction "SH")
			(pintype "passive")
		)
	)
	(footprint "antmicro-footprints:R_0402_1005Metric"
		(layer "F.Cu")
		(at 75.74 162.06 -90)
		(descr "Resistor SMD 0402")
		(tags "resistor SMD 0402")
		(property "Reference" "R48"
			(at -2.16 -8.36 90)
			(layer "F.SilkS")
			(effects
				(font
					(size 0.7 0.7)
					(thickness 0.15)
				)
				(justify right bottom)
			)
		)
		(property "Value" "R_357k_0402"
			(at 0 1.4 90)
			(layer "F.Fab")
			(effects
				(font
					(size 0.7 0.7)
					(thickness 0.15)
				)
				(justify right bottom)
			)
		)
		(property "Datasheet" "https://www.bourns.com/docs/product-datasheets/cr.pdf"
			(at 0 0 270)
			(layer "F.Fab")
			(hide yes)
			(effects
				(font
					(size 1.27 1.27)
					(thickness 0.15)
				)
			)
		)
		(property "Description" "SMD Chip Resistor"
			(at 0 0 270)
			(layer "F.Fab")
			(hide yes)
			(effects
				(font
					(size 1.27 1.27)
					(thickness 0.15)
				)
			)
		)
		(property "Author" "Antmicro"
			(at -86.32 237.8 0)
			(layer "F.Fab")
			(hide yes)
			(effects
				(font
					(size 1 1)
					(thickness 0.15)
				)
			)
		)
		(property "License" "Apache-2.0"
			(at -86.32 237.8 0)
			(layer "F.Fab")
			(hide yes)
			(effects
				(font
					(size 1 1)
					(thickness 0.15)
				)
			)
		)
		(property "MPN" "CR0402-FX-3573GLF"
			(at -86.32 237.8 0)
			(layer "F.Fab")
			(hide yes)
			(effects
				(font
					(size 1 1)
					(thickness 0.15)
				)
			)
		)
		(property "Manufacturer" "Bourns"
			(at -86.32 237.8 0)
			(layer "F.Fab")
			(hide yes)
			(effects
				(font
					(size 1 1)
					(thickness 0.15)
				)
			)
		)
		(property "Tolerance" "1%"
			(at -86.32 237.8 0)
			(layer "F.Fab")
			(hide yes)
			(effects
				(font
					(size 1 1)
					(thickness 0.15)
				)
			)
		)
		(property "Val" "357k"
			(at -86.32 237.8 0)
			(layer "F.Fab")
			(hide yes)
			(effects
				(font
					(size 1 1)
					(thickness 0.15)
				)
			)
		)
		(sheetname "/Interfaces/")
		(sheetfile "interfaces.kicad_sch")
		(attr smd)
		(fp_rect
			(start -0.925 -0.47)
			(end 0.925 0.47)
			(stroke
				(width 0.05)
				(type default)
			)
			(fill no)
			(layer "F.CrtYd")
		)
		(fp_rect
			(start -0.5 -0.25)
			(end 0.5 0.25)
			(stroke
				(width 0.15)
				(type solid)
			)
			(fill no)
			(layer "F.Fab")
		)
		(pad "1" smd roundrect
			(at -0.48 0 270)
			(size 0.59 0.64)
			(layers "F.Cu" "F.Mask" "F.Paste")
			(roundrect_rratio 0.25)
			(net 2 "VCC3V3")
			(pintype "passive")
		)
		(pad "2" smd roundrect
			(at 0.48 0 270)
			(size 0.59 0.64)
			(layers "F.Cu" "F.Mask" "F.Paste")
			(roundrect_rratio 0.25)
			(net 171 "I3C[1]_SCL_3V3")
			(pintype "passive")
		)
	)
	(footprint "antmicro-footprints:BGA-484_23x23mm_Layout22x22_P1mm_FGG484"
		(layer "F.Cu")
		(at 101.275 119.675 90)
		(property "Reference" "U14"
			(at 11.965 9.405 180)
			(layer "F.SilkS")
			(effects
				(font
					(size 0.7 0.7)
					(thickness 0.15)
				)
				(justify left bottom)
			)
		)
		(property "Value" "XC7A100T-FGG484"
			(at 0 13.1 90)
			(layer "F.Fab")
			(effects
				(font
					(size 0.7 0.7)
					(thickness 0.15)
				)
				(justify left bottom)
			)
		)
		(property "Datasheet" "https://docs.xilinx.com/v/u/en-US/ds181_Artix_7_Data_Sheet"
			(at 0 0 90)
			(layer "F.Fab")
			(hide yes)
			(effects
				(font
					(size 1.27 1.27)
					(thickness 0.15)
				)
			)
		)
		(property "Description" "Artix-7 Field Programmable Gate Array IC 210 324-LFBGA, CSPBGA"
			(at 0 0 90)
			(layer "F.Fab")
			(hide yes)
			(effects
				(font
					(size 1.27 1.27)
					(thickness 0.15)
				)
			)
		)
		(property "Author" "Antmicro"
			(at 220.95 18.4 0)
			(layer "F.Fab")
			(hide yes)
			(effects
				(font
					(size 1 1)
					(thickness 0.15)
				)
			)
		)
		(property "License" "Apache-2.0"
			(at 220.95 18.4 0)
			(layer "F.Fab")
			(hide yes)
			(effects
				(font
					(size 1 1)
					(thickness 0.15)
				)
			)
		)
		(property "MPN" "XC7A100T-FGG484"
			(at 220.95 18.4 0)
			(layer "F.Fab")
			(hide yes)
			(effects
				(font
					(size 1 1)
					(thickness 0.15)
				)
			)
		)
		(property "Manufacturer" "AMD-Xilinx"
			(at 220.95 18.4 0)
			(layer "F.Fab")
			(hide yes)
			(effects
				(font
					(size 1 1)
					(thickness 0.15)
				)
			)
		)
		(sheetname "/FPGA power supply/")
		(sheetfile "fpga-power-supply.kicad_sch")
		(solder_mask_margin 0.05)
		(attr smd)
		(fp_line
			(start 11.608 -11.61)
			(end 11.608 11.608)
			(stroke
				(width 0.15)
				(type solid)
			)
			(layer "F.SilkS")
		)
		(fp_line
			(start -11.61 -11.6)
			(end 11.608 -11.61)
			(stroke
				(width 0.15)
				(type solid)
			)
			(layer "F.SilkS")
		)
		(fp_line
			(start 11.608 11.608)
			(end -11.61 11.608)
			(stroke
				(width 0.15)
				(type solid)
			)
			(layer "F.SilkS")
		)
		(fp_line
			(start -11.61 11.608)
			(end -11.61 -11.6)
			(stroke
				(width 0.15)
				(type solid)
			)
			(layer "F.SilkS")
		)
		(fp_circle
			(center -11.8 -11.8)
			(end -11.75 -11.8)
			(stroke
				(width 0.15)
				(type solid)
			)
			(fill yes)
			(layer "F.SilkS")
		)
		(fp_rect
			(start -12 -12)
			(end 11.999 11.999)
			(stroke
				(width 0.05)
				(type solid)
			)
			(fill no)
			(layer "F.CrtYd")
		)
		(fp_line
			(start 11.499 -11.5)
			(end 11.499 11.499)
			(stroke
				(width 0.15)
				(type solid)
			)
			(layer "F.Fab")
		)
		(fp_line
			(start -10.5 -11.5)
			(end 11.499 -11.5)
			(stroke
				(width 0.15)
				(type solid)
			)
			(layer "F.Fab")
		)
		(fp_line
			(start -11.5 -10.5)
			(end -10.5 -11.5)
			(stroke
				(width 0.15)
				(type solid)
			)
			(layer "F.Fab")
		)
		(fp_line
			(start 11.499 11.499)
			(end -11.5 11.499)
			(stroke
				(width 0.15)
				(type solid)
			)
			(layer "F.Fab")
		)
		(fp_line
			(start -11.5 11.499)
			(end -11.5 -10.5)
			(stroke
				(width 0.15)
				(type solid)
			)
			(layer "F.Fab")
		)
		(pad "A1" smd circle
			(at -10.5 -10.5 90)
			(size 0.5 0.5)
			(layers "F.Cu" "F.Mask" "F.Paste")
			(net 178 "DDR3_DQ13")
			(pinfunction "IO_L1N_T0_AD4N_35")
			(pintype "bidirectional")
		)
		(pad "A2" smd circle
			(at -9.5 -10.5 90)
			(size 0.5 0.5)
			(layers "F.Cu" "F.Mask" "F.Paste")
			(net 1 "GND")
			(pinfunction "GND")
			(pintype "power_in")
		)
		(pad "A3" smd circle
			(at -8.5 -10.5 90)
			(size 0.5 0.5)
			(layers "F.Cu" "F.Mask" "F.Paste")
			(net 1 "GND")
			(pinfunction "GND")
			(pintype "passive")
		)
		(pad "A4" smd circle
			(at -7.5 -10.5 90)
			(size 0.5 0.5)
			(layers "F.Cu" "F.Mask" "F.Paste")
			(net 489 "/Interfaces/PCIE_BMC_TX_C_N")
			(pinfunction "MGTPTXN0_216")
			(pintype "bidirectional")
		)
		(pad "A5" smd circle
			(at -6.5 -10.5 90)
			(size 0.5 0.5)
			(layers "F.Cu" "F.Mask" "F.Paste")
			(net 1 "GND")
			(pinfunction "GND")
			(pintype "passive")
		)
		(pad "A6" smd circle
			(at -5.5 -10.5 90)
			(size 0.5 0.5)
			(layers "F.Cu" "F.Mask" "F.Paste")
			(net 535 "unconnected-(U14E-MGTPTXN2_216-PadA6)")
			(pinfunction "MGTPTXN2_216")
			(pintype "bidirectional+no_connect")
		)
		(pad "A7" smd circle
			(at -4.5 -10.5 90)
			(size 0.5 0.5)
			(layers "F.Cu" "F.Mask" "F.Paste")
			(net 1 "GND")
			(pinfunction "GND")
			(pintype "passive")
		)
		(pad "A8" smd circle
			(at -3.5 -10.5 90)
			(size 0.5 0.5)
			(layers "F.Cu" "F.Mask" "F.Paste")
			(net 382 "PCIE_BMC_RX_N")
			(pinfunction "MGTPRXN0_216")
			(pintype "bidirectional")
		)
		(pad "A9" smd circle
			(at -2.5 -10.5 90)
			(size 0.5 0.5)
			(layers "F.Cu" "F.Mask" "F.Paste")
			(net 1 "GND")
			(pinfunction "GND")
			(pintype "passive")
		)
		(pad "A10" smd circle
			(at -1.5 -10.5 90)
			(size 0.5 0.5)
			(layers "F.Cu" "F.Mask" "F.Paste")
			(net 536 "unconnected-(U14E-MGTPRXN2_216-PadA10)")
			(pinfunction "MGTPRXN2_216")
			(pintype "bidirectional+no_connect")
		)
		(pad "A11" smd circle
			(at -0.5 -10.5 90)
			(size 0.5 0.5)
			(layers "F.Cu" "F.Mask" "F.Paste")
			(net 1 "GND")
			(pinfunction "GND")
			(pintype "passive")
		)
		(pad "A12" smd circle
			(at 0.498 -10.5 90)
			(size 0.5 0.5)
			(layers "F.Cu" "F.Mask" "F.Paste")
			(net 1 "GND")
			(pinfunction "GND")
			(pintype "passive")
		)
		(pad "A13" smd circle
			(at 1.499 -10.5 90)
			(size 0.5 0.5)
			(layers "F.Cu" "F.Mask" "F.Paste")
			(net 78 "NCSI_TXEN")
			(pinfunction "IO_L10P_T1_16")
			(pintype "bidirectional")
		)
		(pad "A14" smd circle
			(at 2.499 -10.5 90)
			(size 0.5 0.5)
			(layers "F.Cu" "F.Mask" "F.Paste")
			(net 77 "NCSI_CRS_DV")
			(pinfunction "IO_L10N_T1_16")
			(pintype "bidirectional")
		)
		(pad "A15" smd circle
			(at 3.499 -10.5 90)
			(size 0.5 0.5)
			(layers "F.Cu" "F.Mask" "F.Paste")
			(net 82 "NCSI_RXD0")
			(pinfunction "IO_L9P_T1_DQS_16")
			(pintype "bidirectional")
		)
		(pad "A16" smd circle
			(at 4.498 -10.5 90)
			(size 0.5 0.5)
			(layers "F.Cu" "F.Mask" "F.Paste")
			(net 523 "SPI0_MOSI_R")
			(pinfunction "IO_L9N_T1_DQS_16")
			(pintype "bidirectional")
		)
		(pad "A17" smd circle
			(at 5.499 -10.5 90)
			(size 0.5 0.5)
			(layers "F.Cu" "F.Mask" "F.Paste")
			(net 2 "VCC3V3")
			(pinfunction "VCCO_16")
			(pintype "power_in")
		)
		(pad "A18" smd circle
			(at 6.499 -10.5 90)
			(size 0.5 0.5)
			(layers "F.Cu" "F.Mask" "F.Paste")
			(net 564 "ROT_SCLK")
			(pinfunction "IO_L17P_T2_16")
			(pintype "bidirectional")
		)
		(pad "A19" smd circle
			(at 7.499 -10.5 90)
			(size 0.5 0.5)
			(layers "F.Cu" "F.Mask" "F.Paste")
			(net 563 "ROT_RX")
			(pinfunction "IO_L17N_T2_16")
			(pintype "bidirectional")
		)
		(pad "A20" smd circle
			(at 8.499 -10.5 90)
			(size 0.5 0.5)
			(layers "F.Cu" "F.Mask" "F.Paste")
			(net 562 "ROT_TX")
			(pinfunction "IO_L16N_T2_16")
			(pintype "bidirectional")
		)
		(pad "A21" smd circle
			(at 9.499 -10.5 90)
			(size 0.5 0.5)
			(layers "F.Cu" "F.Mask" "F.Paste")
			(net 169 "I3C[0]_SCL_3V3")
			(pinfunction "IO_L21N_T3_DQS_16")
			(pintype "bidirectional")
		)
		(pad "A22" smd circle
			(at 10.499 -10.5 90)
			(size 0.5 0.5)
			(layers "F.Cu" "F.Mask" "F.Paste")
			(net 1 "GND")
			(pinfunction "GND")
			(pintype "passive")
		)
		(pad "AA1" smd circle
			(at -10.5 9.499 90)
			(size 0.5 0.5)
			(layers "F.Cu" "F.Mask" "F.Paste")
			(net 397 "SPARE0_R")
			(pinfunction "IO_L7P_T1_34")
			(pintype "bidirectional")
		)
		(pad "AA2" smd circle
			(at -9.5 9.499 90)
			(size 0.5 0.5)
			(layers "F.Cu" "F.Mask" "F.Paste")
			(net 1 "GND")
			(pinfunction "GND")
			(pintype "passive")
		)
		(pad "AA3" smd circle
			(at -8.5 9.499 90)
			(size 0.5 0.5)
			(layers "F.Cu" "F.Mask" "F.Paste")
			(net 468 "ULPI2_DATA1")
			(pinfunction "IO_L9N_T1_DQS_34")
			(pintype "bidirectional")
		)
		(pad "AA4" smd circle
			(at -7.5 9.499 90)
			(size 0.5 0.5)
			(layers "F.Cu" "F.Mask" "F.Paste")
			(net 465 "ULPI2_DATA4")
			(pinfunction "IO_L11N_T1_SRCC_34")
			(pintype "bidirectional")
		)
		(pad "AA5" smd circle
			(at -6.5 9.499 90)
			(size 0.5 0.5)
			(layers "F.Cu" "F.Mask" "F.Paste")
			(net 463 "ULPI2_DATA6")
			(pinfunction "IO_L10P_T1_34")
			(pintype "bidirectional")
		)
		(pad "AA6" smd circle
			(at -5.5 9.499 90)
			(size 0.5 0.5)
			(layers "F.Cu" "F.Mask" "F.Paste")
			(net 460 "ULPI2_STP")
			(pinfunction "IO_L18N_T2_34")
			(pintype "bidirectional")
		)
		(pad "AA7" smd circle
			(at -4.5 9.499 90)
			(size 0.5 0.5)
			(layers "F.Cu" "F.Mask" "F.Paste")
			(net 2 "VCC3V3")
			(pinfunction "VCCO_34")
			(pintype "passive")
		)
		(pad "AA8" smd circle
			(at -3.5 9.499 90)
			(size 0.5 0.5)
			(layers "F.Cu" "F.Mask" "F.Paste")
			(net 457 "ULPI2_RESET")
			(pinfunction "IO_L22P_T3_34")
			(pintype "bidirectional")
		)
		(pad "AA9" smd circle
			(at -2.5 9.499 90)
			(size 0.5 0.5)
			(layers "F.Cu" "F.Mask" "F.Paste")
			(net 537 "unconnected-(U14A-IO_L8P_T1_13-PadAA9)")
			(pinfunction "IO_L8P_T1_13")
			(pintype "bidirectional+no_connect")
		)
		(pad "AA10" smd circle
			(at -1.5 9.499 90)
			(size 0.5 0.5)
			(layers "F.Cu" "F.Mask" "F.Paste")
			(net 539 "unconnected-(U14A-IO_L9P_T1_DQS_13-PadAA10)")
			(pinfunction "IO_L9P_T1_DQS_13")
			(pintype "bidirectional+no_connect")
		)
		(pad "AA11" smd circle
			(at -0.5 9.499 90)
			(size 0.5 0.5)
			(layers "F.Cu" "F.Mask" "F.Paste")
			(net 540 "unconnected-(U14A-IO_L9N_T1_DQS_13-PadAA11)")
			(pinfunction "IO_L9N_T1_DQS_13")
			(pintype "bidirectional+no_connect")
		)
		(pad "AA12" smd circle
			(at 0.498 9.499 90)
			(size 0.5 0.5)
			(layers "F.Cu" "F.Mask" "F.Paste")
			(net 1 "GND")
			(pinfunction "GND")
			(pintype "passive")
		)
		(pad "AA13" smd circle
			(at 1.499 9.499 90)
			(size 0.5 0.5)
			(layers "F.Cu" "F.Mask" "F.Paste")
			(net 541 "unconnected-(U14A-IO_L3P_T0_DQS_13-PadAA13)")
			(pinfunction "IO_L3P_T0_DQS_13")
			(pintype "bidirectional+no_connect")
		)
		(pad "AA14" smd circle
			(at 2.499 9.499 90)
			(size 0.5 0.5)
			(layers "F.Cu" "F.Mask" "F.Paste")
			(net 542 "unconnected-(U14A-IO_L5N_T0_13-PadAA14)")
			(pinfunction "IO_L5N_T0_13")
			(pintype "bidirectional+no_connect")
		)
		(pad "AA15" smd circle
			(at 3.499 9.499 90)
			(size 0.5 0.5)
			(layers "F.Cu" "F.Mask" "F.Paste")
			(net 543 "unconnected-(U14A-IO_L4P_T0_13-PadAA15)")
			(pinfunction "IO_L4P_T0_13")
			(pintype "bidirectional+no_connect")
		)
		(pad "AA16" smd circle
			(at 4.498 9.499 90)
			(size 0.5 0.5)
			(layers "F.Cu" "F.Mask" "F.Paste")
			(net 544 "unconnected-(U14A-IO_L1N_T0_13-PadAA16)")
			(pinfunction "IO_L1N_T0_13")
			(pintype "bidirectional+no_connect")
		)
		(pad "AA17" smd circle
			(at 5.499 9.499 90)
			(size 0.5 0.5)
			(layers "F.Cu" "F.Mask" "F.Paste")
			(net 2 "VCC3V3")
			(pinfunction "VCCO_13")
			(pintype "passive")
		)
		(pad "AA18" smd circle
			(at 6.499 9.499 90)
			(size 0.5 0.5)
			(layers "F.Cu" "F.Mask" "F.Paste")
			(net 454 "ULPI1_DATA1")
			(pinfunction "IO_L17P_T2_A14_D30_14")
			(pintype "bidirectional")
		)
		(pad "AA19" smd circle
			(at 7.499 9.499 90)
			(size 0.5 0.5)
			(layers "F.Cu" "F.Mask" "F.Paste")
			(net 453 "ULPI1_DATA2")
			(pinfunction "IO_L15P_T2_DQS_RDWR_B_14")
			(pintype "bidirectional")
		)
		(pad "AA20" smd circle
			(at 8.499 9.499 90)
			(size 0.5 0.5)
			(layers "F.Cu" "F.Mask" "F.Paste")
			(net 451 "ULPI1_DATA4")
			(pinfunction "IO_L8P_T1_D11_14")
			(pintype "bidirectional")
		)
		(pad "AA21" smd circle
			(at 9.499 9.499 90)
			(size 0.5 0.5)
			(layers "F.Cu" "F.Mask" "F.Paste")
			(net 449 "ULPI1_DATA6")
			(pinfunction "IO_L8N_T1_D12_14")
			(pintype "bidirectional")
		)
		(pad "AA22" smd circle
			(at 10.499 9.499 90)
			(size 0.5 0.5)
			(layers "F.Cu" "F.Mask" "F.Paste")
			(net 1 "GND")
			(pinfunction "GND")
			(pintype "passive")
		)
		(pad "AB1" smd circle
			(at -10.5 10.499 90)
			(size 0.5 0.5)
			(layers "F.Cu" "F.Mask" "F.Paste")
			(net 398 "IRQ_N_R")
			(pinfunction "IO_L7N_T1_34")
			(pintype "bidirectional")
		)
		(pad "AB2" smd circle
			(at -9.5 10.499 90)
			(size 0.5 0.5)
			(layers "F.Cu" "F.Mask" "F.Paste")
			(net 469 "ULPI2_DATA0")
			(pinfunction "IO_L8N_T1_34")
			(pintype "bidirectional")
		)
		(pad "AB3" smd circle
			(at -8.5 10.499 90)
			(size 0.5 0.5)
			(layers "F.Cu" "F.Mask" "F.Paste")
			(net 467 "ULPI2_DATA2")
			(pinfunction "IO_L8P_T1_34")
			(pintype "bidirectional")
		)
		(pad "AB4" smd circle
			(at -7.5 10.499 90)
			(size 0.5 0.5)
			(layers "F.Cu" "F.Mask" "F.Paste")
			(net 2 "VCC3V3")
			(pinfunction "VCCO_34")
			(pintype "passive")
		)
		(pad "AB5" smd circle
			(at -6.5 10.499 90)
			(size 0.5 0.5)
			(layers "F.Cu" "F.Mask" "F.Paste")
			(net 464 "ULPI2_DATA5")
			(pinfunction "IO_L10N_T1_34")
			(pintype "bidirectional")
		)
		(pad "AB6" smd circle
			(at -5.5 10.499 90)
			(size 0.5 0.5)
			(layers "F.Cu" "F.Mask" "F.Paste")
			(net 462 "ULPI2_DATA7")
			(pinfunction "IO_L20N_T3_34")
			(pintype "bidirectional")
		)
		(pad "AB7" smd circle
			(at -4.5 10.499 90)
			(size 0.5 0.5)
			(layers "F.Cu" "F.Mask" "F.Paste")
			(net 459 "ULPI2_DIR")
			(pinfunction "IO_L20P_T3_34")
			(pintype "bidirectional")
		)
		(pad "AB8" smd circle
			(at -3.5 10.499 90)
			(size 0.5 0.5)
			(layers "F.Cu" "F.Mask" "F.Paste")
			(net 458 "ULPI2_NXT")
			(pinfunction "IO_L22N_T3_34")
			(pintype "bidirectional")
		)
		(pad "AB9" smd circle
			(at -2.5 10.499 90)
			(size 0.5 0.5)
			(layers "F.Cu" "F.Mask" "F.Paste")
			(net 1 "GND")
			(pinfunction "GND")
			(pintype "passive")
		)
		(pad "AB10" smd circle
			(at -1.5 10.499 90)
			(size 0.5 0.5)
			(layers "F.Cu" "F.Mask" "F.Paste")
			(net 545 "unconnected-(U14A-IO_L8N_T1_13-PadAB10)")
			(pinfunction "IO_L8N_T1_13")
			(pintype "bidirectional+no_connect")
		)
		(pad "AB11" smd circle
			(at -0.5 10.499 90)
			(size 0.5 0.5)
			(layers "F.Cu" "F.Mask" "F.Paste")
			(net 546 "unconnected-(U14A-IO_L7P_T1_13-PadAB11)")
			(pinfunction "IO_L7P_T1_13")
			(pintype "bidirectional+no_connect")
		)
		(pad "AB12" smd circle
			(at 0.498 10.499 90)
			(size 0.5 0.5)
			(layers "F.Cu" "F.Mask" "F.Paste")
			(net 547 "unconnected-(U14A-IO_L7N_T1_13-PadAB12)")
			(pinfunction "IO_L7N_T1_13")
			(pintype "bidirectional+no_connect")
		)
		(pad "AB13" smd circle
			(at 1.499 10.499 90)
			(size 0.5 0.5)
			(layers "F.Cu" "F.Mask" "F.Paste")
			(net 548 "unconnected-(U14A-IO_L3N_T0_DQS_13-PadAB13)")
			(pinfunction "IO_L3N_T0_DQS_13")
			(pintype "bidirectional+no_connect")
		)
		(pad "AB14" smd circle
			(at 2.499 10.499 90)
			(size 0.5 0.5)
			(layers "F.Cu" "F.Mask" "F.Paste")
			(net 2 "VCC3V3")
			(pinfunction "VCCO_13")
			(pintype "passive")
		)
		(pad "AB15" smd circle
			(at 3.499 10.499 90)
			(size 0.5 0.5)
			(layers "F.Cu" "F.Mask" "F.Paste")
			(net 549 "unconnected-(U14A-IO_L4N_T0_13-PadAB15)")
			(pinfunction "IO_L4N_T0_13")
			(pintype "bidirectional+no_connect")
		)
		(pad "AB16" smd circle
			(at 4.498 10.499 90)
			(size 0.5 0.5)
			(layers "F.Cu" "F.Mask" "F.Paste")
			(net 550 "unconnected-(U14A-IO_L2P_T0_13-PadAB16)")
			(pinfunction "IO_L2P_T0_13")
			(pintype "bidirectional+no_connect")
		)
		(pad "AB17" smd circle
			(at 5.499 10.499 90)
			(size 0.5 0.5)
			(layers "F.Cu" "F.Mask" "F.Paste")
			(net 551 "unconnected-(U14A-IO_L2N_T0_13-PadAB17)")
			(pinfunction "IO_L2N_T0_13")
			(pintype "bidirectional+no_connect")
		)
		(pad "AB18" smd circle
			(at 6.499 10.499 90)
			(size 0.5 0.5)
			(layers "F.Cu" "F.Mask" "F.Paste")
			(net 455 "ULPI1_DATA0")
			(pinfunction "IO_L17N_T2_A13_D29_14")
			(pintype "bidirectional")
		)
		(pad "AB19" smd circle
			(at 7.499 10.499 90)
			(size 0.5 0.5)
			(layers "F.Cu" "F.Mask" "F.Paste")
			(net 1 "GND")
			(pinfunction "GND")
			(pintype "passive")
		)
		(pad "AB20" smd circle
			(at 8.499 10.499 90)
			(size 0.5 0.5)
			(layers "F.Cu" "F.Mask" "F.Paste")
			(net 452 "ULPI1_DATA3")
			(pinfunction "IO_L15N_T2_DQS_DOUT_CSO_B_14")
			(pintype "bidirectional")
		)
		(pad "AB21" smd circle
			(at 9.499 10.499 90)
			(size 0.5 0.5)
			(layers "F.Cu" "F.Mask" "F.Paste")
			(net 450 "ULPI1_DATA5")
			(pinfunction "IO_L10P_T1_D14_14")
			(pintype "bidirectional")
		)
		(pad "AB22" smd circle
			(at 10.499 10.499 90)
			(size 0.5 0.5)
			(layers "F.Cu" "F.Mask" "F.Paste")
			(net 448 "ULPI1_DATA7")
			(pinfunction "IO_L10N_T1_D15_14")
			(pintype "bidirectional")
		)
		(pad "B1" smd circle
			(at -10.5 -9.5 90)
			(size 0.5 0.5)
			(layers "F.Cu" "F.Mask" "F.Paste")
			(net 177 "DDR3_DQ15")
			(pinfunction "IO_L1P_T0_AD4P_35")
			(pintype "bidirectional")
		)
		(pad "B2" smd circle
			(at -9.5 -9.5 90)
			(size 0.5 0.5)
			(layers "F.Cu" "F.Mask" "F.Paste")
			(net 180 "DDR3_DQ9")
			(pinfunction "IO_L2N_T0_AD12N_35")
			(pintype "bidirectional")
		)
		(pad "B3" smd circle
			(at -8.5 -9.5 90)
			(size 0.5 0.5)
			(layers "F.Cu" "F.Mask" "F.Paste")
			(net 1 "GND")
			(pinfunction "GND")
			(pintype "passive")
		)
		(pad "B4" smd circle
			(at -7.5 -9.5 90)
			(size 0.5 0.5)
			(layers "F.Cu" "F.Mask" "F.Paste")
			(net 490 "/Interfaces/PCIE_BMC_TX_C_P")
			(pinfunction "MGTPTXP0_216")
			(pintype "bidirectional")
		)
		(pad "B5" smd circle
			(at -6.5 -9.5 90)
			(size 0.5 0.5)
			(layers "F.Cu" "F.Mask" "F.Paste")
			(net 339 "VCC1V2")
			(pinfunction "MGTAVTT")
			(pintype "power_in")
		)
		(pad "B6" smd circle
			(at -5.5 -9.5 90)
			(size 0.5 0.5)
			(layers "F.Cu" "F.Mask" "F.Paste")
			(net 552 "unconnected-(U14E-MGTPTXP2_216-PadB6)")
			(pinfunction "MGTPTXP2_216")
			(pintype "bidirectional+no_connect")
		)
		(pad "B7" smd circle
			(at -4.5 -9.5 90)
			(size 0.5 0.5)
			(layers "F.Cu" "F.Mask" "F.Paste")
			(net 339 "VCC1V2")
			(pinfunction "MGTAVTT")
			(pintype "passive")
		)
		(pad "B8" smd circle
			(at -3.5 -9.5 90)
			(size 0.5 0.5)
			(layers "F.Cu" "F.Mask" "F.Paste")
			(net 381 "PCIE_BMC_RX_P")
			(pinfunction "MGTPRXP0_216")
			(pintype "bidirectional")
		)
		(pad "B9" smd circle
			(at -2.5 -9.5 90)
			(size 0.5 0.5)
			(layers "F.Cu" "F.Mask" "F.Paste")
			(net 339 "VCC1V2")
			(pinfunction "MGTAVTT")
			(pintype "passive")
		)
		(pad "B10" smd circle
			(at -1.5 -9.5 90)
			(size 0.5 0.5)
			(layers "F.Cu" "F.Mask" "F.Paste")
			(net 553 "unconnected-(U14E-MGTPRXP2_216-PadB10)")
			(pinfunction "MGTPRXP2_216")
			(pintype "bidirectional+no_connect")
		)
		(pad "B11" smd circle
			(at -0.5 -9.5 90)
			(size 0.5 0.5)
			(layers "F.Cu" "F.Mask" "F.Paste")
			(net 339 "VCC1V2")
			(pinfunction "MGTAVTT")
			(pintype "passive")
		)
		(pad "B12" smd circle
			(at 0.498 -9.5 90)
			(size 0.5 0.5)
			(layers "F.Cu" "F.Mask" "F.Paste")
			(net 1 "GND")
			(pinfunction "GND")
			(pintype "passive")
		)
		(pad "B13" smd circle
			(at 1.499 -9.5 90)
			(size 0.5 0.5)
			(layers "F.Cu" "F.Mask" "F.Paste")
			(net 76 "NCSI_CLK")
			(pinfunction "IO_L8N_T1_16")
			(pintype "bidirectional")
		)
		(pad "B14" smd circle
			(at 2.499 -9.5 90)
			(size 0.5 0.5)
			(layers "F.Cu" "F.Mask" "F.Paste")
			(net 2 "VCC3V3")
			(pinfunction "VCCO_16")
			(pintype "passive")
		)
		(pad "B15" smd circle
			(at 3.499 -9.5 90)
			(size 0.5 0.5)
			(layers "F.Cu" "F.Mask" "F.Paste")
			(net 83 "NCSI_RXD1")
			(pinfunction "IO_L7P_T1_16")
			(pintype "bidirectional")
		)
		(pad "B16" smd circle
			(at 4.498 -9.5 90)
			(size 0.5 0.5)
			(layers "F.Cu" "F.Mask" "F.Paste")
			(net 526 "SPI0_MISO_R")
			(pinfunction "IO_L7N_T1_16")
			(pintype "bidirectional")
		)
		(pad "B17" smd circle
			(at 5.499 -9.5 90)
			(size 0.5 0.5)
			(layers "F.Cu" "F.Mask" "F.Paste")
			(net 554 "unconnected-(U14B-IO_L11P_T1_SRCC_16-PadB17)")
			(pinfunction "IO_L11P_T1_SRCC_16")
			(pintype "bidirectional+no_connect")
		)
		(pad "B18" smd circle
			(at 6.499 -9.5 90)
			(size 0.5 0.5)
			(layers "F.Cu" "F.Mask" "F.Paste")
			(net 555 "unconnected-(U14B-IO_L11N_T1_SRCC_16-PadB18)")
			(pinfunction "IO_L11N_T1_SRCC_16")
			(pintype "bidirectional+no_connect")
		)
		(pad "B19" smd circle
			(at 7.499 -9.5 90)
			(size 0.5 0.5)
			(layers "F.Cu" "F.Mask" "F.Paste")
			(net 1 "GND")
			(pinfunction "GND")
			(pintype "passive")
		)
		(pad "B20" smd circle
			(at 8.499 -9.5 90)
			(size 0.5 0.5)
			(layers "F.Cu" "F.Mask" "F.Paste")
			(net 168 "I3C[0]_SDA_3V3")
			(pinfunction "IO_L16P_T2_16")
			(pintype "bidirectional")
		)
		(pad "B21" smd circle
			(at 9.499 -9.5 90)
			(size 0.5 0.5)
			(layers "F.Cu" "F.Mask" "F.Paste")
			(net 556 "unconnected-(U14B-IO_L21P_T3_DQS_16-PadB21)")
			(pinfunction "IO_L21P_T3_DQS_16")
			(pintype "bidirectional+no_connect")
		)
		(pad "B22" smd circle
			(at 10.499 -9.5 90)
			(size 0.5 0.5)
			(layers "F.Cu" "F.Mask" "F.Paste")
			(net 301 "ROT_RDY\\ROT_GPIO0")
			(pinfunction "IO_L20N_T3_16")
			(pintype "bidirectional")
		)
		(pad "C1" smd circle
			(at -10.5 -8.5 90)
			(size 0.5 0.5)
			(layers "F.Cu" "F.Mask" "F.Paste")
			(net 3 "VCC1V35")
			(pinfunction "VCCO_35")
			(pintype "power_in")
		)
		(pad "C2" smd circle
			(at -9.5 -8.5 90)
			(size 0.5 0.5)
			(layers "F.Cu" "F.Mask" "F.Paste")
			(net 182 "DDR3_DQ12")
			(pinfunction "IO_L2P_T0_AD12P_35")
			(pintype "bidirectional")
		)
		(pad "C3" smd circle
			(at -8.5 -8.5 90)
			(size 0.5 0.5)
			(layers "F.Cu" "F.Mask" "F.Paste")
			(net 1 "GND")
			(pinfunction "GND")
			(pintype "passive")
		)
		(pad "C4" smd circle
			(at -7.5 -8.5 90)
			(size 0.5 0.5)
			(layers "F.Cu" "F.Mask" "F.Paste")
			(net 339 "VCC1V2")
			(pinfunction "MGTAVTT")
			(pintype "passive")
		)
		(pad "C5" smd circle
			(at -6.5 -8.5 90)
			(size 0.5 0.5)
			(layers "F.Cu" "F.Mask" "F.Paste")
			(net 557 "unconnected-(U14E-MGTPTXN1_216-PadC5)")
			(pinfunction "MGTPTXN1_216")
			(pintype "bidirectional+no_connect")
		)
		(pad "C6" smd circle
			(at -5.5 -8.5 90)
			(size 0.5 0.5)
			(layers "F.Cu" "F.Mask" "F.Paste")
			(net 1 "GND")
			(pinfunction "GND")
			(pintype "passive")
		)
		(pad "C7" smd circle
			(at -4.5 -8.5 90)
			(size 0.5 0.5)
			(layers "F.Cu" "F.Mask" "F.Paste")
			(net 558 "unconnected-(U14E-MGTPTXN3_216-PadC7)")
			(pinfunction "MGTPTXN3_216")
			(pintype "bidirectional+no_connect")
		)
		(pad "C8" smd circle
			(at -3.5 -8.5 90)
			(size 0.5 0.5)
			(layers "F.Cu" "F.Mask" "F.Paste")
			(net 339 "VCC1V2")
			(pinfunction "MGTAVTT")
			(pintype "passive")
		)
		(pad "C9" smd circle
			(at -2.5 -8.5 90)
			(size 0.5 0.5)
			(layers "F.Cu" "F.Mask" "F.Paste")
			(net 567 "unconnected-(U14E-MGTPRXN3_216-PadC9)")
			(pinfunction "MGTPRXN3_216")
			(pintype "bidirectional+no_connect")
		)
		(pad "C10" smd circle
			(at -1.5 -8.5 90)
			(size 0.5 0.5)
			(layers "F.Cu" "F.Mask" "F.Paste")
			(net 1 "GND")
			(pinfunction "GND")
			(pintype "passive")
		)
		(pad "C11" smd circle
			(at -0.5 -8.5 90)
			(size 0.5 0.5)
			(layers "F.Cu" "F.Mask" "F.Paste")
			(net 568 "unconnected-(U14E-MGTPRXN1_216-PadC11)")
			(pinfunction "MGTPRXN1_216")
			(pintype "bidirectional+no_connect")
		)
		(pad "C12" smd circle
			(at 0.498 -8.5 90)
			(size 0.5 0.5)
			(layers "F.Cu" "F.Mask" "F.Paste")
			(net 1 "GND")
			(pinfunction "GND")
			(pintype "passive")
		)
		(pad "C13" smd circle
			(at 1.499 -8.5 90)
			(size 0.5 0.5)
			(layers "F.Cu" "F.Mask" "F.Paste")
			(net 45 "I2C[8]_SCL")
			(pinfunction "IO_L8P_T1_16")
			(pintype "bidirectional")
		)
		(pad "C14" smd circle
			(at 2.499 -8.5 90)
			(size 0.5 0.5)
			(layers "F.Cu" "F.Mask" "F.Paste")
			(net 46 "I2C[8]_SDA")
			(pinfunction "IO_L3P_T0_DQS_16")
			(pintype "bidirectional")
		)
		(pad "C15" smd circle
			(at 3.499 -8.5 90)
			(size 0.5 0.5)
			(layers "F.Cu" "F.Mask" "F.Paste")
			(net 81 "NCSI_RXER")
			(pinfunction "IO_L3N_T0_DQS_16")
			(pintype "bidirectional")
		)
		(pad "C16" smd circle
			(at 4.498 -8.5 90)
			(size 0.5 0.5)
			(layers "F.Cu" "F.Mask" "F.Paste")
			(net 1 "GND")
			(pinfunction "GND")
			(pintype "passive")
		)
		(pad "C17" smd circle
			(at 5.499 -8.5 90)
			(size 0.5 0.5)
			(layers "F.Cu" "F.Mask" "F.Paste")
			(net 569 "unconnected-(U14B-IO_L12N_T1_MRCC_16-PadC17)")
			(pinfunction "IO_L12N_T1_MRCC_16")
			(pintype "bidirectional+no_connect")
		)
		(pad "C18" smd circle
			(at 6.499 -8.5 90)
			(size 0.5 0.5)
			(layers "F.Cu" "F.Mask" "F.Paste")
			(net 503 "/FPGA banks 13-16/GCLK100")
			(pinfunction "IO_L13P_T2_MRCC_16")
			(pintype "bidirectional")
		)
		(pad "C19" smd circle
			(at 7.499 -8.5 90)
			(size 0.5 0.5)
			(layers "F.Cu" "F.Mask" "F.Paste")
			(net 173 "I3C[2]_SCL_3V3")
			(pinfunction "IO_L13N_T2_MRCC_16")
			(pintype "bidirectional")
		)
		(pad "C20" smd circle
			(at 8.499 -8.5 90)
			(size 0.5 0.5)
			(layers "F.Cu" "F.Mask" "F.Paste")
			(net 560 "ROT_MOSI")
			(pinfunction "IO_L19N_T3_VREF_16")
			(pintype "bidirectional")
		)
		(pad "C21" smd circle
			(at 9.499 -8.5 90)
			(size 0.5 0.5)
			(layers "F.Cu" "F.Mask" "F.Paste")
			(net 2 "VCC3V3")
			(pinfunction "VCCO_16")
			(pintype "passive")
		)
		(pad "C22" smd circle
			(at 10.499 -8.5 90)
			(size 0.5 0.5)
			(layers "F.Cu" "F.Mask" "F.Paste")
			(net 559 "ROT_MISO")
			(pinfunction "IO_L20P_T3_16")
			(pintype "bidirectional")
		)
		(pad "D1" smd circle
			(at -10.5 -7.5 90)
			(size 0.5 0.5)
			(layers "F.Cu" "F.Mask" "F.Paste")
			(net 474 "DDR3_DQS1_N")
			(pinfunction "IO_L3N_T0_DQS_AD5N_35")
			(pintype "bidirectional")
		)
		(pad "D2" smd circle
			(at -9.5 -7.5 90)
			(size 0.5 0.5)
			(layers "F.Cu" "F.Mask" "F.Paste")
			(net 184 "DDR3_DQ11")
			(pinfunction "IO_L4N_T0_35")
			(pintype "bidirectional")
		)
		(pad "D3" smd circle
			(at -8.5 -7.5 90)
			(size 0.5 0.5)
			(layers "F.Cu" "F.Mask" "F.Paste")
			(net 1 "GND")
			(pinfunction "GND")
			(pintype "passive")
		)
		(pad "D4" smd circle
			(at -7.5 -7.5 90)
			(size 0.5 0.5)
			(layers "F.Cu" "F.Mask" "F.Paste")
			(net 1 "GND")
			(pinfunction "GND")
			(pintype "passive")
		)
		(pad "D5" smd circle
			(at -6.5 -7.5 90)
			(size 0.5 0.5)
			(layers "F.Cu" "F.Mask" "F.Paste")
			(net 570 "unconnected-(U14E-MGTPTXP1_216-PadD5)")
			(pinfunction "MGTPTXP1_216")
			(pintype "bidirectional+no_connect")
		)
		(pad "D6" smd circle
			(at -5.5 -7.5 90)
			(size 0.5 0.5)
			(layers "F.Cu" "F.Mask" "F.Paste")
			(net 6 "VCC1V0")
			(pinfunction "MGTAVCC")
			(pintype "power_in")
		)
		(pad "D7" smd circle
			(at -4.5 -7.5 90)
			(size 0.5 0.5)
			(layers "F.Cu" "F.Mask" "F.Paste")
			(net 571 "unconnected-(U14E-MGTPTXP3_216-PadD7)")
			(pinfunction "MGTPTXP3_216")
			(pintype "bidirectional+no_connect")
		)
		(pad "D8" smd circle
			(at -3.5 -7.5 90)
			(size 0.5 0.5)
			(layers "F.Cu" "F.Mask" "F.Paste")
			(net 1 "GND")
			(pinfunction "GND")
			(pintype "passive")
		)
		(pad "D9" smd circle
			(at -2.5 -7.5 90)
			(size 0.5 0.5)
			(layers "F.Cu" "F.Mask" "F.Paste")
			(net 572 "unconnected-(U14E-MGTPRXP3_216-PadD9)")
			(pinfunction "MGTPRXP3_216")
			(pintype "bidirectional+no_connect")
		)
		(pad "D10" smd circle
			(at -1.5 -7.5 90)
			(size 0.5 0.5)
			(layers "F.Cu" "F.Mask" "F.Paste")
			(net 6 "VCC1V0")
			(pinfunction "MGTAVCC")
			(pintype "passive")
		)
		(pad "D11" smd circle
			(at -0.5 -7.5 90)
			(size 0.5 0.5)
			(layers "F.Cu" "F.Mask" "F.Paste")
			(net 587 "unconnected-(U14E-MGTPRXP1_216-PadD11)")
			(pinfunction "MGTPRXP1_216")
			(pintype "bidirectional+no_connect")
		)
		(pad "D12" smd circle
			(at 0.498 -7.5 90)
			(size 0.5 0.5)
			(layers "F.Cu" "F.Mask" "F.Paste")
			(net 1 "GND")
			(pinfunction "GND")
			(pintype "passive")
		)
		(pad "D13" smd circle
			(at 1.499 -7.5 90)
			(size 0.5 0.5)
			(layers "F.Cu" "F.Mask" "F.Paste")
			(net 1 "GND")
			(pinfunction "GND")
			(pintype "passive")
		)
		(pad "D14" smd circle
			(at 2.499 -7.5 90)
			(size 0.5 0.5)
			(layers "F.Cu" "F.Mask" "F.Paste")
			(net 79 "NCSI_TXD0")
			(pinfunction "IO_L6P_T0_16")
			(pintype "bidirectional")
		)
		(pad "D15" smd circle
			(at 3.499 -7.5 90)
			(size 0.5 0.5)
			(layers "F.Cu" "F.Mask" "F.Paste")
			(net 588 "unconnected-(U14B-IO_L6N_T0_VREF_16-PadD15)")
			(pinfunction "IO_L6N_T0_VREF_16")
			(pintype "bidirectional+no_connect")
		)
		(pad "D16" smd circle
			(at 4.498 -7.5 90)
			(size 0.5 0.5)
			(layers "F.Cu" "F.Mask" "F.Paste")
			(net 525 "SPI0_CS_N_R")
			(pinfunction "IO_L5N_T0_16")
			(pintype "bidirectional")
		)
		(pad "D17" smd circle
			(at 5.499 -7.5 90)
			(size 0.5 0.5)
			(layers "F.Cu" "F.Mask" "F.Paste")
			(net 39 "UART0_SCM_RX")
			(pinfunction "IO_L12P_T1_MRCC_16")
			(pintype "bidirectional")
		)
		(pad "D18" smd circle
			(at 6.499 -7.5 90)
			(size 0.5 0.5)
			(layers "F.Cu" "F.Mask" "F.Paste")
			(net 2 "VCC3V3")
			(pinfunction "VCCO_16")
			(pintype "passive")
		)
		(pad "D19" smd circle
			(at 7.499 -7.5 90)
			(size 0.5 0.5)
			(layers "F.Cu" "F.Mask" "F.Paste")
			(net 175 "I3C[3]_SCL_3V3")
			(pinfunction "IO_L14N_T2_SRCC_16")
			(pintype "bidirectional")
		)
		(pad "D20" smd circle
			(at 8.499 -7.5 90)
			(size 0.5 0.5)
			(layers "F.Cu" "F.Mask" "F.Paste")
			(net 171 "I3C[1]_SCL_3V3")
			(pinfunction "IO_L19P_T3_16")
			(pintype "bidirectional")
		)
		(pad "D21" smd circle
			(at 9.499 -7.5 90)
			(size 0.5 0.5)
			(layers "F.Cu" "F.Mask" "F.Paste")
			(net 593 "unconnected-(U14B-IO_L23N_T3_16-PadD21)")
			(pinfunction "IO_L23N_T3_16")
			(pintype "bidirectional+no_connect")
		)
		(pad "D22" smd circle
			(at 10.499 -7.5 90)
			(size 0.5 0.5)
			(layers "F.Cu" "F.Mask" "F.Paste")
			(net 561 "ROT_SS")
			(pinfunction "IO_L22N_T3_16")
			(pintype "bidirectional")
		)
		(pad "E1" smd circle
			(at -10.5 -6.5 90)
			(size 0.5 0.5)
			(layers "F.Cu" "F.Mask" "F.Paste")
			(net 475 "DDR3_DQS1_P")
			(pinfunction "IO_L3P_T0_DQS_AD5P_35")
			(pintype "bidirectional")
		)
		(pad "E2" smd circle
			(at -9.5 -6.5 90)
			(size 0.5 0.5)
			(layers "F.Cu" "F.Mask" "F.Paste")
			(net 179 "DDR3_DQ14")
			(pinfunction "IO_L4P_T0_35")
			(pintype "bidirectional")
		)
		(pad "E3" smd circle
			(at -8.5 -6.5 90)
			(size 0.5 0.5)
			(layers "F.Cu" "F.Mask" "F.Paste")
			(net 193 "DDR3_DQ8")
			(pinfunction "IO_L6N_T0_VREF_35")
			(pintype "bidirectional")
		)
		(pad "E4" smd circle
			(at -7.5 -6.5 90)
			(size 0.5 0.5)
			(layers "F.Cu" "F.Mask" "F.Paste")
			(net 1 "GND")
			(pinfunction "GND")
			(pintype "passive")
		)
		(pad "E5" smd circle
			(at -6.5 -6.5 90)
			(size 0.5 0.5)
			(layers "F.Cu" "F.Mask" "F.Paste")
			(net 1 "GND")
			(pinfunction "GND")
			(pintype "passive")
		)
		(pad "E6" smd circle
			(at -5.5 -6.5 90)
			(size 0.5 0.5)
			(layers "F.Cu" "F.Mask" "F.Paste")
			(net 380 "PCIE_BMC_CLK_100_N")
			(pinfunction "MGTREFCLK0N_216")
			(pintype "bidirectional")
		)
		(pad "E7" smd circle
			(at -4.5 -6.5 90)
			(size 0.5 0.5)
			(layers "F.Cu" "F.Mask" "F.Paste")
			(net 1 "GND")
			(pinfunction "GND")
			(pintype "passive")
		)
		(pad "E8" smd circle
			(at -3.5 -6.5 90)
			(size 0.5 0.5)
			(layers "F.Cu" "F.Mask" "F.Paste")
			(net 6 "VCC1V0")
			(pinfunction "MGTAVCC")
			(pintype "passive")
		)
		(pad "E9" smd circle
			(at -2.5 -6.5 90)
			(size 0.5 0.5)
			(layers "F.Cu" "F.Mask" "F.Paste")
			(net 1 "GND")
			(pinfunction "GND")
			(pintype "passive")
		)
		(pad "E10" smd circle
			(at -1.5 -6.5 90)
			(size 0.5 0.5)
			(layers "F.Cu" "F.Mask" "F.Paste")
			(net 594 "unconnected-(U14E-MGTREFCLK1N_216-PadE10)")
			(pinfunction "MGTREFCLK1N_216")
			(pintype "bidirectional+no_connect")
		)
		(pad "E11" smd circle
			(at -0.5 -6.5 90)
			(size 0.5 0.5)
			(layers "F.Cu" "F.Mask" "F.Paste")
			(net 1 "GND")
			(pinfunction "GND")
			(pintype "passive")
		)
		(pad "E12" smd circle
			(at 0.498 -6.5 90)
			(size 0.5 0.5)
			(layers "F.Cu" "F.Mask" "F.Paste")
			(net 5 "VCC1V8")
			(pinfunction "VCCBATT")
			(pintype "power_in")
		)
		(pad "E13" smd circle
			(at 1.499 -6.5 90)
			(size 0.5 0.5)
			(layers "F.Cu" "F.Mask" "F.Paste")
			(net 24 "I2C[7]_SDA")
			(pinfunction "IO_L4P_T0_16")
			(pintype "bidirectional")
		)
		(pad "E14" smd circle
			(at 2.499 -6.5 90)
			(size 0.5 0.5)
			(layers "F.Cu" "F.Mask" "F.Paste")
			(net 80 "NCSI_TXD1")
			(pinfunction "IO_L4N_T0_16")
			(pintype "bidirectional")
		)
		(pad "E15" smd circle
			(at 3.499 -6.5 90)
			(size 0.5 0.5)
			(layers "F.Cu" "F.Mask" "F.Paste")
			(net 2 "VCC3V3")
			(pinfunction "VCCO_16")
			(pintype "passive")
		)
		(pad "E16" smd circle
			(at 4.498 -6.5 90)
			(size 0.5 0.5)
			(layers "F.Cu" "F.Mask" "F.Paste")
			(net 524 "SPI0_CLK_R")
			(pinfunction "IO_L5P_T0_16")
			(pintype "bidirectional")
		)
		(pad "E17" smd circle
			(at 5.499 -6.5 90)
			(size 0.5 0.5)
			(layers "F.Cu" "F.Mask" "F.Paste")
			(net 35 "UART0_SCM_TX")
			(pinfunction "IO_L2N_T0_16")
			(pintype "bidirectional")
		)
		(pad "E18" smd circle
			(at 6.499 -6.5 90)
			(size 0.5 0.5)
			(layers "F.Cu" "F.Mask" "F.Paste")
			(net 595 "unconnected-(U14B-IO_L15N_T2_DQS_16-PadE18)")
			(pinfunction "IO_L15N_T2_DQS_16")
			(pintype "bidirectional+no_connect")
		)
		(pad "E19" smd circle
			(at 7.499 -6.5 90)
			(size 0.5 0.5)
			(layers "F.Cu" "F.Mask" "F.Paste")
			(net 596 "unconnected-(U14B-IO_L14P_T2_SRCC_16-PadE19)")
			(pinfunction "IO_L14P_T2_SRCC_16")
			(pintype "bidirectional+no_connect")
		)
		(pad "E20" smd circle
			(at 8.499 -6.5 90)
			(size 0.5 0.5)
			(layers "F.Cu" "F.Mask" "F.Paste")
			(net 1 "GND")
			(pinfunction "GND")
			(pintype "passive")
		)
		(pad "E21" smd circle
			(at 9.499 -6.5 90)
			(size 0.5 0.5)
			(layers "F.Cu" "F.Mask" "F.Paste")
			(net 521 "PRSNT0_N_R")
			(pinfunction "IO_L23P_T3_16")
			(pintype "bidirectional")
		)
		(pad "E22" smd circle
			(at 10.499 -6.5 90)
			(size 0.5 0.5)
			(layers "F.Cu" "F.Mask" "F.Paste")
			(net 522 "VIRTUAL_RESEAT_R")
			(pinfunction "IO_L22P_T3_16")
			(pintype "bidirectional")
		)
		(pad "F1" smd circle
			(at -10.5 -5.5 90)
			(size 0.5 0.5)
			(layers "F.Cu" "F.Mask" "F.Paste")
			(net 181 "DDR3_DM1")
			(pinfunction "IO_L5N_T0_AD13N_35")
			(pintype "bidirectional")
		)
		(pad "F2" smd circle
			(at -9.5 -5.5 90)
			(size 0.5 0.5)
			(layers "F.Cu" "F.Mask" "F.Paste")
			(net 3 "VCC1V35")
			(pinfunction "VCCO_35")
			(pintype "passive")
		)
		(pad "F3" smd circle
			(at -8.5 -5.5 90)
			(size 0.5 0.5)
			(layers "F.Cu" "F.Mask" "F.Paste")
			(net 183 "DDR3_DQ10")
			(pinfunction "IO_L6P_T0_35")
			(pintype "bidirectional")
		)
		(pad "F4" smd circle
			(at -7.5 -5.5 90)
			(size 0.5 0.5)
			(layers "F.Cu" "F.Mask" "F.Paste")
			(net 598 "unconnected-(U14C-IO_0_35-PadF4)")
			(pinfunction "IO_0_35")
			(pintype "bidirectional+no_connect")
		)
		(pad "F5" smd circle
			(at -6.5 -5.5 90)
			(size 0.5 0.5)
			(layers "F.Cu" "F.Mask" "F.Paste")
			(net 1 "GND")
			(pinfunction "GND")
			(pintype "passive")
		)
		(pad "F6" smd circle
			(at -5.5 -5.5 90)
			(size 0.5 0.5)
			(layers "F.Cu" "F.Mask" "F.Paste")
			(net 379 "PCIE_BMC_CLK_100_P")
			(pinfunction "MGTREFCLK0P_216")
			(pintype "bidirectional")
		)
		(pad "F7" smd circle
			(at -4.5 -5.5 90)
			(size 0.5 0.5)
			(layers "F.Cu" "F.Mask" "F.Paste")
			(net 6 "VCC1V0")
			(pinfunction "MGTAVCC")
			(pintype "passive")
		)
		(pad "F8" smd circle
			(at -3.5 -5.5 90)
			(size 0.5 0.5)
			(layers "F.Cu" "F.Mask" "F.Paste")
			(net 533 "Net-(U14E-MGTRREF_216)")
			(pinfunction "MGTRREF_216")
			(pintype "passive")
		)
		(pad "F9" smd circle
			(at -2.5 -5.5 90)
			(size 0.5 0.5)
			(layers "F.Cu" "F.Mask" "F.Paste")
			(net 6 "VCC1V0")
			(pinfunction "MGTAVCC")
			(pintype "passive")
		)
		(pad "F10" smd circle
			(at -1.5 -5.5 90)
			(size 0.5 0.5)
			(layers "F.Cu" "F.Mask" "F.Paste")
			(net 599 "unconnected-(U14E-MGTREFCLK1P_216-PadF10)")
			(pinfunction "MGTREFCLK1P_216")
			(pintype "bidirectional+no_connect")
		)
		(pad "F11" smd circle
			(at -0.5 -5.5 90)
			(size 0.5 0.5)
			(layers "F.Cu" "F.Mask" "F.Paste")
			(net 1 "GND")
			(pinfunction "GND")
			(pintype "passive")
		)
		(pad "F12" smd circle
			(at 0.498 -5.5 90)
			(size 0.5 0.5)
			(layers "F.Cu" "F.Mask" "F.Paste")
			(net 2 "VCC3V3")
			(pinfunction "VCCO_0")
			(pintype "power_in")
		)
		(pad "F13" smd circle
			(at 1.499 -5.5 90)
			(size 0.5 0.5)
			(layers "F.Cu" "F.Mask" "F.Paste")
			(net 20 "I2C[7]_SCL")
			(pinfunction "IO_L1P_T0_16")
			(pintype "bidirectional")
		)
		(pad "F14" smd circle
			(at 2.499 -5.5 90)
			(size 0.5 0.5)
			(layers "F.Cu" "F.Mask" "F.Paste")
			(net 600 "unconnected-(U14B-IO_L1N_T0_16-PadF14)")
			(pinfunction "IO_L1N_T0_16")
			(pintype "bidirectional+no_connect")
		)
		(pad "F15" smd circle
			(at 3.499 -5.5 90)
			(size 0.5 0.5)
			(layers "F.Cu" "F.Mask" "F.Paste")
			(net 601 "unconnected-(U14B-IO_0_16-PadF15)")
			(pinfunction "IO_0_16")
			(pintype "bidirectional+no_connect")
		)
		(pad "F16" smd circle
			(at 4.498 -5.5 90)
			(size 0.5 0.5)
			(layers "F.Cu" "F.Mask" "F.Paste")
			(net 602 "unconnected-(U14B-IO_L2P_T0_16-PadF16)")
			(pinfunction "IO_L2P_T0_16")
			(pintype "bidirectional+no_connect")
		)
		(pad "F17" smd circle
			(at 5.499 -5.5 90)
			(size 0.5 0.5)
			(layers "F.Cu" "F.Mask" "F.Paste")
			(net 1 "GND")
			(pinfunction "GND")
			(pintype "passive")
		)
		(pad "F18" smd circle
			(at 6.499 -5.5 90)
			(size 0.5 0.5)
			(layers "F.Cu" "F.Mask" "F.Paste")
			(net 174 "I3C[3]_SDA_3V3")
			(pinfunction "IO_L15P_T2_DQS_16")
			(pintype "bidirectional")
		)
		(pad "F19" smd circle
			(at 7.499 -5.5 90)
			(size 0.5 0.5)
			(layers "F.Cu" "F.Mask" "F.Paste")
			(net 172 "I3C[2]_SDA_3V3")
			(pinfunction "IO_L18P_T2_16")
			(pintype "bidirectional")
		)
		(pad "F20" smd circle
			(at 8.499 -5.5 90)
			(size 0.5 0.5)
			(layers "F.Cu" "F.Mask" "F.Paste")
			(net 170 "I3C[1]_SDA_3V3")
			(pinfunction "IO_L18N_T2_16")
			(pintype "bidirectional")
		)
		(pad "F21" smd circle
			(at 9.499 -5.5 90)
			(size 0.5 0.5)
			(layers "F.Cu" "F.Mask" "F.Paste")
			(net 565 "ROT_GPIO2")
			(pinfunction "IO_25_16")
			(pintype "bidirectional")
		)
		(pad "F22" smd circle
			(at 10.499 -5.5 90)
			(size 0.5 0.5)
			(layers "F.Cu" "F.Mask" "F.Paste")
			(net 2 "VCC3V3")
			(pinfunction "VCCO_16")
			(pintype "passive")
		)
		(pad "G1" smd circle
			(at -10.5 -4.5 90)
			(size 0.5 0.5)
			(layers "F.Cu" "F.Mask" "F.Paste")
			(net 191 "DDR3_RESET")
			(pinfunction "IO_L5P_T0_AD13P_35")
			(pintype "bidirectional")
		)
		(pad "G2" smd circle
			(at -9.5 -4.5 90)
			(size 0.5 0.5)
			(layers "F.Cu" "F.Mask" "F.Paste")
			(net 194 "DDR3_DQ0")
			(pinfunction "IO_L8N_T1_AD14N_35")
			(pintype "bidirectional")
		)
		(pad "G3" smd circle
			(at -8.5 -4.5 90)
			(size 0.5 0.5)
			(layers "F.Cu" "F.Mask" "F.Paste")
			(net 176 "DDR3_DM0")
			(pinfunction "IO_L11N_T1_SRCC_35")
			(pintype "bidirectional")
		)
		(pad "G4" smd circle
			(at -7.5 -4.5 90)
			(size 0.5 0.5)
			(layers "F.Cu" "F.Mask" "F.Paste")
			(net 603 "unconnected-(U14C-IO_L12N_T1_MRCC_35-PadG4)")
			(pinfunction "IO_L12N_T1_MRCC_35")
			(pintype "bidirectional+no_connect")
		)
		(pad "G5" smd circle
			(at -6.5 -4.5 90)
			(size 0.5 0.5)
			(layers "F.Cu" "F.Mask" "F.Paste")
			(net 1 "GND")
			(pinfunction "GND")
			(pintype "passive")
		)
		(pad "G6" smd circle
			(at -5.5 -4.5 90)
			(size 0.5 0.5)
			(layers "F.Cu" "F.Mask" "F.Paste")
			(net 1 "GND")
			(pinfunction "GND")
			(pintype "passive")
		)
		(pad "G7" smd circle
			(at -4.5 -4.5 90)
			(size 0.5 0.5)
			(layers "F.Cu" "F.Mask" "F.Paste")
			(net 1 "GND")
			(pinfunction "GND")
			(pintype "passive")
		)
		(pad "G8" smd circle
			(at -3.5 -4.5 90)
			(size 0.5 0.5)
			(layers "F.Cu" "F.Mask" "F.Paste")
			(net 1 "GND")
			(pinfunction "GND")
			(pintype "passive")
		)
		(pad "G9" smd circle
			(at -2.5 -4.5 90)
			(size 0.5 0.5)
			(layers "F.Cu" "F.Mask" "F.Paste")
			(net 1 "GND")
			(pinfunction "GND")
			(pintype "passive")
		)
		(pad "G10" smd circle
			(at -1.5 -4.5 90)
			(size 0.5 0.5)
			(layers "F.Cu" "F.Mask" "F.Paste")
			(net 1 "GND")
			(pinfunction "GND")
			(pintype "passive")
		)
		(pad "G11" smd circle
			(at -0.5 -4.5 90)
			(size 0.5 0.5)
			(layers "F.Cu" "F.Mask" "F.Paste")
			(net 220 "DONE")
			(pinfunction "DONE_0")
			(pintype "bidirectional")
		)
		(pad "G12" smd circle
			(at 0.498 -4.5 90)
			(size 0.5 0.5)
			(layers "F.Cu" "F.Mask" "F.Paste")
			(net 1 "GND")
			(pinfunction "GND")
			(pintype "passive")
		)
		(pad "G13" smd circle
			(at 1.499 -4.5 90)
			(size 0.5 0.5)
			(layers "F.Cu" "F.Mask" "F.Paste")
			(net 29 "I2C[6]_SDA")
			(pinfunction "IO_L1N_T0_AD0N_15")
			(pintype "bidirectional")
		)
		(pad "G14" smd circle
			(at 2.499 -4.5 90)
			(size 0.5 0.5)
			(layers "F.Cu" "F.Mask" "F.Paste")
			(net 1 "GND")
			(pinfunction "GND")
			(pintype "passive")
		)
		(pad "G15" smd circle
			(at 3.499 -4.5 90)
			(size 0.5 0.5)
			(layers "F.Cu" "F.Mask" "F.Paste")
			(net 69 "ESPI_CS1_N")
			(pinfunction "IO_L2P_T0_AD8P_15")
			(pintype "bidirectional")
		)
		(pad "G16" smd circle
			(at 4.498 -4.5 90)
			(size 0.5 0.5)
			(layers "F.Cu" "F.Mask" "F.Paste")
			(net 604 "unconnected-(U14B-IO_L2N_T0_AD8N_15-PadG16)")
			(pinfunction "IO_L2N_T0_AD8N_15")
			(pintype "bidirectional+no_connect")
		)
		(pad "G17" smd circle
			(at 5.499 -4.5 90)
			(size 0.5 0.5)
			(layers "F.Cu" "F.Mask" "F.Paste")
			(net 592 "TPM_PIRQ#")
			(pinfunction "IO_L4P_T0_15")
			(pintype "bidirectional")
		)
		(pad "G18" smd circle
			(at 6.499 -4.5 90)
			(size 0.5 0.5)
			(layers "F.Cu" "F.Mask" "F.Paste")
			(net 589 "TPM_PP")
			(pinfunction "IO_L4N_T0_15")
			(pintype "bidirectional")
		)
		(pad "G19" smd circle
			(at 7.499 -4.5 90)
			(size 0.5 0.5)
			(layers "F.Cu" "F.Mask" "F.Paste")
			(net 2 "VCC3V3")
			(pinfunction "VCCO_15")
			(pintype "power_in")
		)
		(pad "G20" smd circle
			(at 8.499 -4.5 90)
			(size 0.5 0.5)
			(layers "F.Cu" "F.Mask" "F.Paste")
			(net 425 "RGMII_TXD0")
			(pinfunction "IO_L8N_T1_AD10N_15")
			(pintype "bidirectional")
		)
		(pad "G21" smd circle
			(at 9.499 -4.5 90)
			(size 0.5 0.5)
			(layers "F.Cu" "F.Mask" "F.Paste")
			(net 605 "unconnected-(U14B-IO_L24P_T3_16-PadG21)")
			(pinfunction "IO_L24P_T3_16")
			(pintype "bidirectional+no_connect")
		)
		(pad "G22" smd circle
			(at 10.499 -4.5 90)
			(size 0.5 0.5)
			(layers "F.Cu" "F.Mask" "F.Paste")
			(net 566 "ROT_GPIO1")
			(pinfunction "IO_L24N_T3_16")
			(pintype "bidirectional")
		)
		(pad "H1" smd circle
			(at -10.5 -3.5 90)
			(size 0.5 0.5)
			(layers "F.Cu" "F.Mask" "F.Paste")
			(net 1 "GND")
			(pinfunction "GND")
			(pintype "passive")
		)
		(pad "H2" smd circle
			(at -9.5 -3.5 90)
			(size 0.5 0.5)
			(layers "F.Cu" "F.Mask" "F.Paste")
			(net 192 "DDR3_DQ6")
			(pinfunction "IO_L8P_T1_AD14P_35")
			(pintype "bidirectional")
		)
		(pad "H3" smd circle
			(at -8.5 -3.5 90)
			(size 0.5 0.5)
			(layers "F.Cu" "F.Mask" "F.Paste")
			(net 186 "DDR3_DQ5")
			(pinfunction "IO_L11P_T1_SRCC_35")
			(pintype "bidirectional")
		)
		(pad "H4" smd circle
			(at -7.5 -3.5 90)
			(size 0.5 0.5)
			(layers "F.Cu" "F.Mask" "F.Paste")
			(net 188 "DDR3_DQ1")
			(pinfunction "IO_L12P_T1_MRCC_35")
			(pintype "bidirectional")
		)
		(pad "H5" smd circle
			(at -6.5 -3.5 90)
			(size 0.5 0.5)
			(layers "F.Cu" "F.Mask" "F.Paste")
			(net 187 "DDR3_DQ2")
			(pinfunction "IO_L10N_T1_AD15N_35")
			(pintype "bidirectional")
		)
		(pad "H6" smd circle
			(at -5.5 -3.5 90)
			(size 0.5 0.5)
			(layers "F.Cu" "F.Mask" "F.Paste")
			(net 3 "VCC1V35")
			(pinfunction "VCCO_35")
			(pintype "passive")
		)
		(pad "H7" smd circle
			(at -4.5 -3.5 90)
			(size 0.5 0.5)
			(layers "F.Cu" "F.Mask" "F.Paste")
			(net 1 "GND")
			(pinfunction "GND")
			(pintype "passive")
		)
		(pad "H8" smd circle
			(at -3.5 -3.5 90)
			(size 0.5 0.5)
			(layers "F.Cu" "F.Mask" "F.Paste")
			(net 6 "VCC1V0")
			(pinfunction "VCCINT")
			(pintype "power_in")
		)
		(pad "H9" smd circle
			(at -2.5 -3.5 90)
			(size 0.5 0.5)
			(layers "F.Cu" "F.Mask" "F.Paste")
			(net 1 "GND")
			(pinfunction "GND")
			(pintype "passive")
		)
		(pad "H10" smd circle
			(at -1.5 -3.5 90)
			(size 0.5 0.5)
			(layers "F.Cu" "F.Mask" "F.Paste")
			(net 6 "VCC1V0")
			(pinfunction "VCCINT")
			(pintype "passive")
		)
		(pad "H11" smd circle
			(at -0.5 -3.5 90)
			(size 0.5 0.5)
			(layers "F.Cu" "F.Mask" "F.Paste")
			(net 1 "GND")
			(pinfunction "GND")
			(pintype "passive")
		)
		(pad "H12" smd circle
			(at 0.498 -3.5 90)
			(size 0.5 0.5)
			(layers "F.Cu" "F.Mask" "F.Paste")
			(net 5 "VCC1V8")
			(pinfunction "VCCAUX")
			(pintype "power_in")
		)
		(pad "H13" smd circle
			(at 1.499 -3.5 90)
			(size 0.5 0.5)
			(layers "F.Cu" "F.Mask" "F.Paste")
			(net 28 "I2C[6]_SCL")
			(pinfunction "IO_L1P_T0_AD0P_15")
			(pintype "bidirectional")
		)
		(pad "H14" smd circle
			(at 2.499 -3.5 90)
			(size 0.5 0.5)
			(layers "F.Cu" "F.Mask" "F.Paste")
			(net 606 "unconnected-(U14B-IO_L3N_T0_DQS_AD1N_15-PadH14)")
			(pinfunction "IO_L3N_T0_DQS_AD1N_15")
			(pintype "bidirectional+no_connect")
		)
		(pad "H15" smd circle
			(at 3.499 -3.5 90)
			(size 0.5 0.5)
			(layers "F.Cu" "F.Mask" "F.Paste")
			(net 607 "unconnected-(U14B-IO_L5N_T0_AD9N_15-PadH15)")
			(pinfunction "IO_L5N_T0_AD9N_15")
			(pintype "bidirectional+no_connect")
		)
		(pad "H16" smd circle
			(at 4.498 -3.5 90)
			(size 0.5 0.5)
			(layers "F.Cu" "F.Mask" "F.Paste")
			(net 2 "VCC3V3")
			(pinfunction "VCCO_15")
			(pintype "passive")
		)
		(pad "H17" smd circle
			(at 5.499 -3.5 90)
			(size 0.5 0.5)
			(layers "F.Cu" "F.Mask" "F.Paste")
			(net 608 "unconnected-(U14B-IO_L6P_T0_15-PadH17)")
			(pinfunction "IO_L6P_T0_15")
			(pintype "bidirectional+no_connect")
		)
		(pad "H18" smd circle
			(at 6.499 -3.5 90)
			(size 0.5 0.5)
			(layers "F.Cu" "F.Mask" "F.Paste")
			(net 63 "ESPI_ALERT_N")
			(pinfunction "IO_L6N_T0_VREF_15")
			(pintype "bidirectional")
		)
		(pad "H19" smd circle
			(at 7.499 -3.5 90)
			(size 0.5 0.5)
			(layers "F.Cu" "F.Mask" "F.Paste")
			(net 413 "RGMII_REF_CLK")
			(pinfunction "IO_L12N_T1_MRCC_15")
			(pintype "bidirectional")
		)
		(pad "H20" smd circle
			(at 8.499 -3.5 90)
			(size 0.5 0.5)
			(layers "F.Cu" "F.Mask" "F.Paste")
			(net 424 "RGMII_TXD1")
			(pinfunction "IO_L8P_T1_AD10P_15")
			(pintype "bidirectional")
		)
		(pad "H21" smd circle
			(at 9.499 -3.5 90)
			(size 0.5 0.5)
			(layers "F.Cu" "F.Mask" "F.Paste")
			(net 1 "GND")
			(pinfunction "GND")
			(pintype "passive")
		)
		(pad "H22" smd circle
			(at 10.499 -3.5 90)
			(size 0.5 0.5)
			(layers "F.Cu" "F.Mask" "F.Paste")
			(net 423 "RGMII_TXD2")
			(pinfunction "IO_L7N_T1_AD2N_15")
			(pintype "bidirectional")
		)
		(pad "J1" smd circle
			(at -10.5 -2.5 90)
			(size 0.5 0.5)
			(layers "F.Cu" "F.Mask" "F.Paste")
			(net 190 "DDR3_DQ3")
			(pinfunction "IO_L7N_T1_AD6N_35")
			(pintype "bidirectional")
		)
		(pad "J2" smd circle
			(at -9.5 -2.5 90)
			(size 0.5 0.5)
			(layers "F.Cu" "F.Mask" "F.Paste")
			(net 476 "DDR3_DQS0_N")
			(pinfunction "IO_L9N_T1_DQS_AD7N_35")
			(pintype "bidirectional")
		)
		(pad "J3" smd circle
			(at -8.5 -2.5 90)
			(size 0.5 0.5)
			(layers "F.Cu" "F.Mask" "F.Paste")
			(net 3 "VCC1V35")
			(pinfunction "VCCO_35")
			(pintype "passive")
		)
		(pad "J4" smd circle
			(at -7.5 -2.5 90)
			(size 0.5 0.5)
			(layers "F.Cu" "F.Mask" "F.Paste")
			(net 162 "DDR3_RAS")
			(pinfunction "IO_L13N_T2_MRCC_35")
			(pintype "bidirectional")
		)
		(pad "J5" smd circle
			(at -6.5 -2.5 90)
			(size 0.5 0.5)
			(layers "F.Cu" "F.Mask" "F.Paste")
			(net 185 "DDR3_DQ7")
			(pinfunction "IO_L10P_T1_AD15P_35")
			(pintype "bidirectional")
		)
		(pad "J6" smd circle
			(at -5.5 -2.5 90)
			(size 0.5 0.5)
			(layers "F.Cu" "F.Mask" "F.Paste")
			(net 160 "DDR3_CKE")
			(pinfunction "IO_L17N_T2_35")
			(pintype "bidirectional")
		)
		(pad "J7" smd circle
			(at -4.5 -2.5 90)
			(size 0.5 0.5)
			(layers "F.Cu" "F.Mask" "F.Paste")
			(net 6 "VCC1V0")
			(pinfunction "VCCINT")
			(pintype "passive")
		)
		(pad "J8" smd circle
			(at -3.5 -2.5 90)
			(size 0.5 0.5)
			(layers "F.Cu" "F.Mask" "F.Paste")
			(net 1 "GND")
			(pinfunction "GND")
			(pintype "passive")
		)
		(pad "J9" smd circle
			(at -2.5 -2.5 90)
			(size 0.5 0.5)
			(layers "F.Cu" "F.Mask" "F.Paste")
			(net 6 "VCC1V0")
			(pinfunction "VCCINT")
			(pintype "passive")
		)
		(pad "J10" smd circle
			(at -1.5 -2.5 90)
			(size 0.5 0.5)
			(layers "F.Cu" "F.Mask" "F.Paste")
			(net 1 "GND")
			(pinfunction "GND")
			(pintype "passive")
		)
		(pad "J11" smd circle
			(at -0.5 -2.5 90)
			(size 0.5 0.5)
			(layers "F.Cu" "F.Mask" "F.Paste")
			(net 6 "VCC1V0")
			(pinfunction "VCCBRAM")
			(pintype "power_in")
		)
		(pad "J12" smd circle
			(at 0.498 -2.5 90)
			(size 0.5 0.5)
			(layers "F.Cu" "F.Mask" "F.Paste")
			(net 1 "GND")
			(pinfunction "GND")
			(pintype "passive")
		)
		(pad "J13" smd circle
			(at 1.499 -2.5 90)
			(size 0.5 0.5)
			(layers "F.Cu" "F.Mask" "F.Paste")
			(net 2 "VCC3V3")
			(pinfunction "VCCO_15")
			(pintype "passive")
		)
		(pad "J14" smd circle
			(at 2.499 -2.5 90)
			(size 0.5 0.5)
			(layers "F.Cu" "F.Mask" "F.Paste")
			(net 25 "I2C[2]_SDA")
			(pinfunction "IO_L3P_T0_DQS_AD1P_15")
			(pintype "bidirectional")
		)
		(pad "J15" smd circle
			(at 3.499 -2.5 90)
			(size 0.5 0.5)
			(layers "F.Cu" "F.Mask" "F.Paste")
			(net 32 "I2C[0]_SDA")
			(pinfunction "IO_L5P_T0_AD9P_15")
			(pintype "bidirectional")
		)
		(pad "J16" smd circle
			(at 4.498 -2.5 90)
			(size 0.5 0.5)
			(layers "F.Cu" "F.Mask" "F.Paste")
			(net 31 "I2C[0]_SCL")
			(pinfunction "IO_0_15")
			(pintype "bidirectional")
		)
		(pad "J17" smd circle
			(at 5.499 -2.5 90)
			(size 0.5 0.5)
			(layers "F.Cu" "F.Mask" "F.Paste")
			(net 609 "unconnected-(U14B-IO_L21N_T3_DQS_A18_15-PadJ17)")
			(pinfunction "IO_L21N_T3_DQS_A18_15")
			(pintype "bidirectional+no_connect")
		)
		(pad "J18" smd circle
			(at 6.499 -2.5 90)
			(size 0.5 0.5)
			(layers "F.Cu" "F.Mask" "F.Paste")
			(net 1 "GND")
			(pinfunction "GND")
			(pintype "passive")
		)
		(pad "J19" smd circle
			(at 7.499 -2.5 90)
			(size 0.5 0.5)
			(layers "F.Cu" "F.Mask" "F.Paste")
			(net 421 "RGMII_TX_CLK")
			(pinfunction "IO_L12P_T1_MRCC_15")
			(pintype "bidirectional")
		)
		(pad "J20" smd circle
			(at 8.499 -2.5 90)
			(size 0.5 0.5)
			(layers "F.Cu" "F.Mask" "F.Paste")
			(net 610 "unconnected-(U14B-IO_L11P_T1_SRCC_15-PadJ20)")
			(pinfunction "IO_L11P_T1_SRCC_15")
			(pintype "bidirectional+no_connect")
		)
		(pad "J21" smd circle
			(at 9.499 -2.5 90)
			(size 0.5 0.5)
			(layers "F.Cu" "F.Mask" "F.Paste")
			(net 422 "RGMII_TXD3")
			(pinfunction "IO_L11N_T1_SRCC_15")
			(pintype "bidirectional")
		)
		(pad "J22" smd circle
			(at 10.499 -2.5 90)
			(size 0.5 0.5)
			(layers "F.Cu" "F.Mask" "F.Paste")
			(net 427 "RGMII_TX_DV")
			(pinfunction "IO_L7P_T1_AD2P_15")
			(pintype "bidirectional")
		)
		(pad "K1" smd circle
			(at -10.5 -1.5 90)
			(size 0.5 0.5)
			(layers "F.Cu" "F.Mask" "F.Paste")
			(net 189 "DDR3_DQ4")
			(pinfunction "IO_L7P_T1_AD6P_35")
			(pintype "bidirectional")
		)
		(pad "K2" smd circle
			(at -9.5 -1.5 90)
			(size 0.5 0.5)
			(layers "F.Cu" "F.Mask" "F.Paste")
			(net 477 "DDR3_DQS0_P")
			(pinfunction "IO_L9P_T1_DQS_AD7P_35")
			(pintype "bidirectional")
		)
		(pad "K3" smd circle
			(at -8.5 -1.5 90)
			(size 0.5 0.5)
			(layers "F.Cu" "F.Mask" "F.Paste")
			(net 166 "DDR3_CAS")
			(pinfunction "IO_L14N_T2_SRCC_35")
			(pintype "bidirectional")
		)
		(pad "K4" smd circle
			(at -7.5 -1.5 90)
			(size 0.5 0.5)
			(layers "F.Cu" "F.Mask" "F.Paste")
			(net 161 "DDR3_ODT")
			(pinfunction "IO_L13P_T2_MRCC_35")
			(pintype "bidirectional")
		)
		(pad "K5" smd circle
			(at -6.5 -1.5 90)
			(size 0.5 0.5)
			(layers "F.Cu" "F.Mask" "F.Paste")
			(net 1 "GND")
			(pinfunction "GND")
			(pintype "passive")
		)
		(pad "K6" smd circle
			(at -5.5 -1.5 90)
			(size 0.5 0.5)
			(layers "F.Cu" "F.Mask" "F.Paste")
			(net 155 "DDR3_BA1")
			(pinfunction "IO_L17P_T2_35")
			(pintype "bidirectional")
		)
		(pad "K7" smd circle
			(at -4.5 -1.5 90)
			(size 0.5 0.5)
			(layers "F.Cu" "F.Mask" "F.Paste")
			(net 1 "GND")
			(pinfunction "GND")
			(pintype "passive")
		)
		(pad "K8" smd circle
			(at -3.5 -1.5 90)
			(size 0.5 0.5)
			(layers "F.Cu" "F.Mask" "F.Paste")
			(net 6 "VCC1V0")
			(pinfunction "VCCINT")
			(pintype "passive")
		)
		(pad "K9" smd circle
			(at -2.5 -1.5 90)
			(size 0.5 0.5)
			(layers "F.Cu" "F.Mask" "F.Paste")
			(net 1 "GND")
			(pinfunction "GND_ADC")
			(pintype "power_in")
		)
		(pad "K10" smd circle
			(at -1.5 -1.5 90)
			(size 0.5 0.5)
			(layers "F.Cu" "F.Mask" "F.Paste")
			(net 5 "VCC1V8")
			(pinfunction "VCCADC")
			(pintype "power_in")
		)
		(pad "K11" smd circle
			(at -0.5 -1.5 90)
			(size 0.5 0.5)
			(layers "F.Cu" "F.Mask" "F.Paste")
			(net 1 "GND")
			(pinfunction "GND")
			(pintype "passive")
		)
		(pad "K12" smd circle
			(at 0.498 -1.5 90)
			(size 0.5 0.5)
			(layers "F.Cu" "F.Mask" "F.Paste")
			(net 5 "VCC1V8")
			(pinfunction "VCCAUX")
			(pintype "passive")
		)
		(pad "K13" smd circle
			(at 1.499 -1.5 90)
			(size 0.5 0.5)
			(layers "F.Cu" "F.Mask" "F.Paste")
			(net 30 "I2C[4]_SCL")
			(pinfunction "IO_L19P_T3_A22_15")
			(pintype "bidirectional")
		)
		(pad "K14" smd circle
			(at 2.499 -1.5 90)
			(size 0.5 0.5)
			(layers "F.Cu" "F.Mask" "F.Paste")
			(net 19 "I2C[3]_SCL")
			(pinfunction "IO_L19N_T3_A21_VREF_15")
			(pintype "bidirectional")
		)
		(pad "K15" smd circle
			(at 3.499 -1.5 90)
			(size 0.5 0.5)
			(layers "F.Cu" "F.Mask" "F.Paste")
			(net 1 "GND")
			(pinfunction "GND")
			(pintype "passive")
		)
		(pad "K16" smd circle
			(at 4.498 -1.5 90)
			(size 0.5 0.5)
			(layers "F.Cu" "F.Mask" "F.Paste")
			(net 67 "ESPI_IO2")
			(pinfunction "IO_L23N_T3_FWE_B_15")
			(pintype "bidirectional")
		)
		(pad "K17" smd circle
			(at 5.499 -1.5 90)
			(size 0.5 0.5)
			(layers "F.Cu" "F.Mask" "F.Paste")
			(net 65 "ESPI_IO0")
			(pinfunction "IO_L21P_T3_DQS_15")
			(pintype "bidirectional")
		)
		(pad "K18" smd circle
			(at 6.499 -1.5 90)
			(size 0.5 0.5)
			(layers "F.Cu" "F.Mask" "F.Paste")
			(net 62 "ESPI_CS0_N")
			(pinfunction "IO_L13P_T2_MRCC_15")
			(pintype "bidirectional")
		)
		(pad "K19" smd circle
			(at 7.499 -1.5 90)
			(size 0.5 0.5)
			(layers "F.Cu" "F.Mask" "F.Paste")
			(net 412 "RGMII_RX_CLK")
			(pinfunction "IO_L13N_T2_MRCC_15")
			(pintype "bidirectional")
		)
		(pad "K20" smd circle
			(at 8.499 -1.5 90)
			(size 0.5 0.5)
			(layers "F.Cu" "F.Mask" "F.Paste")
			(net 2 "VCC3V3")
			(pinfunction "VCCO_15")
			(pintype "passive")
		)
		(pad "K21" smd circle
			(at 9.499 -1.5 90)
			(size 0.5 0.5)
			(layers "F.Cu" "F.Mask" "F.Paste")
			(net 409 "RGMII_RXD2")
			(pinfunction "IO_L9P_T1_DQS_AD3P_15")
			(pintype "bidirectional")
		)
		(pad "K22" smd circle
			(at 10.499 -1.5 90)
			(size 0.5 0.5)
			(layers "F.Cu" "F.Mask" "F.Paste")
			(net 410 "RGMII_RXD3")
			(pinfunction "IO_L9N_T1_DQS_AD3N_15")
			(pintype "bidirectional")
		)
		(pad "L1" smd circle
			(at -10.5 -0.5 90)
			(size 0.5 0.5)
			(layers "F.Cu" "F.Mask" "F.Paste")
			(net 153 "DDR3_WE")
			(pinfunction "IO_L15N_T2_DQS_35")
			(pintype "bidirectional")
		)
		(pad "L2" smd circle
			(at -9.5 -0.5 90)
			(size 0.5 0.5)
			(layers "F.Cu" "F.Mask" "F.Paste")
			(net 1 "GND")
			(pinfunction "GND")
			(pintype "passive")
		)
		(pad "L3" smd circle
			(at -8.5 -0.5 90)
			(size 0.5 0.5)
			(layers "F.Cu" "F.Mask" "F.Paste")
			(net 164 "DDR3_BA0")
			(pinfunction "IO_L14P_T2_SRCC_35")
			(pintype "bidirectional")
		)
		(pad "L4" smd circle
			(at -7.5 -0.5 90)
			(size 0.5 0.5)
			(layers "F.Cu" "F.Mask" "F.Paste")
			(net 152 "DDR3_BA2")
			(pinfunction "IO_L18N_T2_35")
			(pintype "bidirectional")
		)
		(pad "L5" smd circle
			(at -6.5 -0.5 90)
			(size 0.5 0.5)
			(layers "F.Cu" "F.Mask" "F.Paste")
			(net 154 "DDR3_A10")
			(pinfunction "IO_L18P_T2_35")
			(pintype "bidirectional")
		)
		(pad "L6" smd circle
			(at -5.5 -0.5 90)
			(size 0.5 0.5)
			(layers "F.Cu" "F.Mask" "F.Paste")
			(net 159 "DDR3_A4")
			(pinfunction "IO_25_35")
			(pintype "bidirectional")
		)
		(pad "L7" smd circle
			(at -4.5 -0.5 90)
			(size 0.5 0.5)
			(layers "F.Cu" "F.Mask" "F.Paste")
			(net 6 "VCC1V0")
			(pinfunction "VCCINT")
			(pintype "passive")
		)
		(pad "L8" smd circle
			(at -3.5 -0.5 90)
			(size 0.5 0.5)
			(layers "F.Cu" "F.Mask" "F.Paste")
			(net 1 "GND")
			(pinfunction "GND")
			(pintype "passive")
		)
		(pad "L9" smd circle
			(at -2.5 -0.5 90)
			(size 0.5 0.5)
			(layers "F.Cu" "F.Mask" "F.Paste")
			(net 1 "GND")
			(pinfunction "VREFN_0")
			(pintype "bidirectional")
		)
		(pad "L10" smd circle
			(at -1.5 -0.5 90)
			(size 0.5 0.5)
			(layers "F.Cu" "F.Mask" "F.Paste")
			(net 1 "GND")
			(pinfunction "VP_0")
			(pintype "bidirectional")
		)
		(pad "L11" smd circle
			(at -0.5 -0.5 90)
			(size 0.5 0.5)
			(layers "F.Cu" "F.Mask" "F.Paste")
			(net 6 "VCC1V0")
			(pinfunction "VCCBRAM")
			(pintype "passive")
		)
		(pad "L12" smd circle
			(at 0.498 -0.5 90)
			(size 0.5 0.5)
			(layers "F.Cu" "F.Mask" "F.Paste")
			(net 320 "ROT_QSPI_SCK")
			(pinfunction "CCLK_0")
			(pintype "bidirectional")
		)
		(pad "L13" smd circle
			(at 1.499 -0.5 90)
			(size 0.5 0.5)
			(layers "F.Cu" "F.Mask" "F.Paste")
			(net 27 "I2C[4]_SDA")
			(pinfunction "IO_L20N_T3_A19_15")
			(pintype "bidirectional")
		)
		(pad "L14" smd circle
			(at 2.499 -0.5 90)
			(size 0.5 0.5)
			(layers "F.Cu" "F.Mask" "F.Paste")
			(net 26 "I2C[2]_SCL")
			(pinfunction "IO_L22P_T3_A17_15")
			(pintype "bidirectional")
		)
		(pad "L15" smd circle
			(at 3.499 -0.5 90)
			(size 0.5 0.5)
			(layers "F.Cu" "F.Mask" "F.Paste")
			(net 22 "I2C[1]_SCL")
			(pinfunction "IO_L22N_T3_A16_15")
			(pintype "bidirectional")
		)
		(pad "L16" smd circle
			(at 4.498 -0.5 90)
			(size 0.5 0.5)
			(layers "F.Cu" "F.Mask" "F.Paste")
			(net 68 "ESPI_IO3")
			(pinfunction "IO_L23P_T3_FOE_B_15")
			(pintype "bidirectional")
		)
		(pad "L17" smd circle
			(at 5.499 -0.5 90)
			(size 0.5 0.5)
			(layers "F.Cu" "F.Mask" "F.Paste")
			(net 2 "VCC3V3")
			(pinfunction "VCCO_15")
			(pintype "passive")
		)
		(pad "L18" smd circle
			(at 6.499 -0.5 90)
			(size 0.5 0.5)
			(layers "F.Cu" "F.Mask" "F.Paste")
			(net 61 "ESPI_CLK")
			(pinfunction "IO_L16N_T2_A27_15")
			(pintype "bidirectional")
		)
		(pad "L19" smd circle
			(at 7.499 -0.5 90)
			(size 0.5 0.5)
			(layers "F.Cu" "F.Mask" "F.Paste")
			(net 611 "unconnected-(U14B-IO_L14P_T2_SRCC_15-PadL19)")
			(pinfunction "IO_L14P_T2_SRCC_15")
			(pintype "bidirectional+no_connect")
		)
		(pad "L20" smd circle
			(at 8.499 -0.5 90)
			(size 0.5 0.5)
			(layers "F.Cu" "F.Mask" "F.Paste")
			(net 407 "RGMII_RXD0")
			(pinfunction "IO_L14N_T2_SRCC_15")
			(pintype "bidirectional")
		)
		(pad "L21" smd circle
			(at 9.499 -0.5 90)
			(size 0.5 0.5)
			(layers "F.Cu" "F.Mask" "F.Paste")
			(net 408 "RGMII_RXD1")
			(pinfunction "IO_L10N_T1_AD11N_15")
			(pintype "bidirectional")
		)
		(pad "L22" smd circle
			(at 10.499 -0.5 90)
			(size 0.5 0.5)
			(layers "F.Cu" "F.Mask" "F.Paste")
			(net 1 "GND")
			(pinfunction "GND")
			(pintype "passive")
		)
		(pad "M1" smd circle
			(at -10.5 0.498 90)
			(size 0.5 0.5)
			(layers "F.Cu" "F.Mask" "F.Paste")
			(net 165 "DDR3_A3")
			(pinfunction "IO_L15P_T2_DQS_35")
			(pintype "bidirectional")
		)
		(pad "M2" smd circle
			(at -9.5 0.498 90)
			(size 0.5 0.5)
			(layers "F.Cu" "F.Mask" "F.Paste")
			(net 158 "DDR3_A0")
			(pinfunction "IO_L16N_T2_35")
			(pintype "bidirectional")
		)
		(pad "M3" smd circle
			(at -8.5 0.498 90)
			(size 0.5 0.5)
			(layers "F.Cu" "F.Mask" "F.Paste")
			(net 147 "DDR3_A2")
			(pinfunction "IO_L16P_T2_35")
			(pintype "bidirectional")
		)
		(pad "M4" smd circle
			(at -7.5 0.498 90)
			(size 0.5 0.5)
			(layers "F.Cu" "F.Mask" "F.Paste")
			(net 3 "VCC1V35")
			(pinfunction "VCCO_35")
			(pintype "passive")
		)
		(pad "M5" smd circle
			(at -6.5 0.498 90)
			(size 0.5 0.5)
			(layers "F.Cu" "F.Mask" "F.Paste")
			(net 157 "DDR3_A1")
			(pinfunction "IO_L23N_T3_35")
			(pintype "bidirectional")
		)
		(pad "M6" smd circle
			(at -5.5 0.498 90)
			(size 0.5 0.5)
			(layers "F.Cu" "F.Mask" "F.Paste")
			(net 145 "DDR3_A8")
			(pinfunction "IO_L23P_T3_35")
			(pintype "bidirectional")
		)
		(pad "M7" smd circle
			(at -4.5 0.498 90)
			(size 0.5 0.5)
			(layers "F.Cu" "F.Mask" "F.Paste")
			(net 1 "GND")
			(pinfunction "GND")
			(pintype "passive")
		)
		(pad "M8" smd circle
			(at -3.5 0.498 90)
			(size 0.5 0.5)
			(layers "F.Cu" "F.Mask" "F.Paste")
			(net 6 "VCC1V0")
			(pinfunction "VCCINT")
			(pintype "passive")
		)
		(pad "M9" smd circle
			(at -2.5 0.498 90)
			(size 0.5 0.5)
			(layers "F.Cu" "F.Mask" "F.Paste")
			(net 1 "GND")
			(pinfunction "VN_0")
			(pintype "bidirectional")
		)
		(pad "M10" smd circle
			(at -1.5 0.498 90)
			(size 0.5 0.5)
			(layers "F.Cu" "F.Mask" "F.Paste")
			(net 1 "GND")
			(pinfunction "VREFP_0")
			(pintype "bidirectional")
		)
		(pad "M11" smd circle
			(at -0.5 0.498 90)
			(size 0.5 0.5)
			(layers "F.Cu" "F.Mask" "F.Paste")
			(net 1 "GND")
			(pinfunction "GND")
			(pintype "passive")
		)
		(pad "M12" smd circle
			(at 0.498 0.498 90)
			(size 0.5 0.5)
			(layers "F.Cu" "F.Mask" "F.Paste")
			(net 5 "VCC1V8")
			(pinfunction "VCCAUX")
			(pintype "passive")
		)
		(pad "M13" smd circle
			(at 1.499 0.498 90)
			(size 0.5 0.5)
			(layers "F.Cu" "F.Mask" "F.Paste")
			(net 21 "I2C[3]_SDA")
			(pinfunction "IO_L20P_T3_A20_15")
			(pintype "bidirectional")
		)
		(pad "M14" smd circle
			(at 2.499 0.498 90)
			(size 0.5 0.5)
			(layers "F.Cu" "F.Mask" "F.Paste")
			(net 2 "VCC3V3")
			(pinfunction "VCCO_14")
			(pintype "passive")
		)
		(pad "M15" smd circle
			(at 3.499 0.498 90)
			(size 0.5 0.5)
			(layers "F.Cu" "F.Mask" "F.Paste")
			(net 23 "I2C[1]_SDA")
			(pinfunction "IO_L24P_T3_RS1_15")
			(pintype "bidirectional")
		)
		(pad "M16" smd circle
			(at 4.498 0.498 90)
			(size 0.5 0.5)
			(layers "F.Cu" "F.Mask" "F.Paste")
			(net 66 "ESPI_IO1")
			(pinfunction "IO_L24N_T3_RS0_15")
			(pintype "bidirectional")
		)
		(pad "M17" smd circle
			(at 5.499 0.498 90)
			(size 0.5 0.5)
			(layers "F.Cu" "F.Mask" "F.Paste")
			(net 64 "ESPI_RESET_N")
			(pinfunction "IO_25_15")
			(pintype "bidirectional")
		)
		(pad "M18" smd circle
			(at 6.499 0.498 90)
			(size 0.5 0.5)
			(layers "F.Cu" "F.Mask" "F.Paste")
			(net 612 "unconnected-(U14B-IO_L16P_T2_A28_15-PadM18)")
			(pinfunction "IO_L16P_T2_A28_15")
			(pintype "bidirectional+no_connect")
		)
		(pad "M19" smd circle
			(at 7.499 0.498 90)
			(size 0.5 0.5)
			(layers "F.Cu" "F.Mask" "F.Paste")
			(net 1 "GND")
			(pinfunction "GND")
			(pintype "passive")
		)
		(pad "M20" smd circle
			(at 8.499 0.498 90)
			(size 0.5 0.5)
			(layers "F.Cu" "F.Mask" "F.Paste")
			(net 613 "unconnected-(U14B-IO_L18N_T2_A23_15-PadM20)")
			(pinfunction "IO_L18N_T2_A23_15")
			(pintype "bidirectional+no_connect")
		)
		(pad "M21" smd circle
			(at 9.499 0.498 90)
			(size 0.5 0.5)
			(layers "F.Cu" "F.Mask" "F.Paste")
			(net 142 "ETH_MDIO")
			(pinfunction "IO_L10P_T1_AD11P_15")
			(pintype "bidirectional")
		)
		(pad "M22" smd circle
			(at 10.499 0.498 90)
			(size 0.5 0.5)
			(layers "F.Cu" "F.Mask" "F.Paste")
			(net 411 "RGMII_RX_DV")
			(pinfunction "IO_L15N_T2_DQS_ADV_B_15")
			(pintype "bidirectional")
		)
		(pad "N1" smd circle
			(at -10.5 1.499 90)
			(size 0.5 0.5)
			(layers "F.Cu" "F.Mask" "F.Paste")
			(net 3 "VCC1V35")
			(pinfunction "VCCO_35")
			(pintype "passive")
		)
		(pad "N2" smd circle
			(at -9.5 1.499 90)
			(size 0.5 0.5)
			(layers "F.Cu" "F.Mask" "F.Paste")
			(net 148 "DDR3_A7")
			(pinfunction "IO_L22N_T3_35")
			(pintype "bidirectional")
		)
		(pad "N3" smd circle
			(at -8.5 1.499 90)
			(size 0.5 0.5)
			(layers "F.Cu" "F.Mask" "F.Paste")
			(net 146 "DDR3_A6")
			(pinfunction "IO_L19N_T3_VREF_35")
			(pintype "bidirectional")
		)
		(pad "N4" smd circle
			(at -7.5 1.499 90)
			(size 0.5 0.5)
			(layers "F.Cu" "F.Mask" "F.Paste")
			(net 156 "DDR3_A12")
			(pinfunction "IO_L19P_T3_35")
			(pintype "bidirectional")
		)
		(pad "N5" smd circle
			(at -6.5 1.499 90)
			(size 0.5 0.5)
			(layers "F.Cu" "F.Mask" "F.Paste")
			(net 150 "DDR3_A11")
			(pinfunction "IO_L24N_T3_35")
			(pintype "bidirectional")
		)
		(pad "N6" smd circle
			(at -5.5 1.499 90)
			(size 0.5 0.5)
			(layers "F.Cu" "F.Mask" "F.Paste")
			(net 1 "GND")
			(pinfunction "GND")
			(pintype "passive")
		)
		(pad "N7" smd circle
			(at -4.5 1.499 90)
			(size 0.5 0.5)
			(layers "F.Cu" "F.Mask" "F.Paste")
			(net 6 "VCC1V0")
			(pinfunction "VCCINT")
			(pintype "passive")
		)
		(pad "N8" smd circle
			(at -3.5 1.499 90)
			(size 0.5 0.5)
			(layers "F.Cu" "F.Mask" "F.Paste")
			(net 1 "GND")
			(pinfunction "GND")
			(pintype "passive")
		)
		(pad "N9" smd circle
			(at -2.5 1.499 90)
			(size 0.5 0.5)
			(layers "F.Cu" "F.Mask" "F.Paste")
			(net 1 "GND")
			(pinfunction "DXN_0")
			(pintype "bidirectional")
		)
		(pad "N10" smd circle
			(at -1.5 1.499 90)
			(size 0.5 0.5)
			(layers "F.Cu" "F.Mask" "F.Paste")
			(net 1 "GND")
			(pinfunction "DXP_0")
			(pintype "bidirectional")
		)
		(pad "N11" smd circle
			(at -0.5 1.499 90)
			(size 0.5 0.5)
			(layers "F.Cu" "F.Mask" "F.Paste")
			(net 6 "VCC1V0")
			(pinfunction "VCCBRAM")
			(pintype "passive")
		)
		(pad "N12" smd circle
			(at 0.498 1.499 90)
			(size 0.5 0.5)
			(layers "F.Cu" "F.Mask" "F.Paste")
			(net 221 "PROGRAM")
			(pinfunction "PROGRAM_B_0")
			(pintype "bidirectional")
		)
		(pad "N13" smd circle
			(at 1.499 1.499 90)
			(size 0.5 0.5)
			(layers "F.Cu" "F.Mask" "F.Paste")
			(net 18 "I2C[5]_SCL")
			(pinfunction "IO_L23P_T3_A03_D19_14")
			(pintype "bidirectional")
		)
		(pad "N14" smd circle
			(at 2.499 1.499 90)
			(size 0.5 0.5)
			(layers "F.Cu" "F.Mask" "F.Paste")
			(net 17 "I2C[5]_SDA")
			(pinfunction "IO_L23N_T3_A02_D18_14")
			(pintype "bidirectional")
		)
		(pad "N15" smd circle
			(at 3.499 1.499 90)
			(size 0.5 0.5)
			(layers "F.Cu" "F.Mask" "F.Paste")
			(net 614 "unconnected-(U14A-IO_25_14-PadN15)")
			(pinfunction "IO_25_14")
			(pintype "bidirectional+no_connect")
		)
		(pad "N16" smd circle
			(at 4.498 1.499 90)
			(size 0.5 0.5)
			(layers "F.Cu" "F.Mask" "F.Paste")
			(net 1 "GND")
			(pinfunction "GND")
			(pintype "passive")
		)
		(pad "N17" smd circle
			(at 5.499 1.499 90)
			(size 0.5 0.5)
			(layers "F.Cu" "F.Mask" "F.Paste")
			(net 615 "unconnected-(U14A-IO_L21P_T3_DQS_14-PadN17)")
			(pinfunction "IO_L21P_T3_DQS_14")
			(pintype "bidirectional+no_connect")
		)
		(pad "N18" smd circle
			(at 6.499 1.499 90)
			(size 0.5 0.5)
			(layers "F.Cu" "F.Mask" "F.Paste")
			(net 414 "ETH_~{RESET}")
			(pinfunction "IO_L17P_T2_A26_15")
			(pintype "bidirectional")
		)
		(pad "N19" smd circle
			(at 7.499 1.499 90)
			(size 0.5 0.5)
			(layers "F.Cu" "F.Mask" "F.Paste")
			(net 616 "unconnected-(U14B-IO_L17N_T2_A25_15-PadN19)")
			(pinfunction "IO_L17N_T2_A25_15")
			(pintype "bidirectional+no_connect")
		)
		(pad "N20" smd circle
			(at 8.499 1.499 90)
			(size 0.5 0.5)
			(layers "F.Cu" "F.Mask" "F.Paste")
			(net 420 "ETH_INT_N")
			(pinfunction "IO_L18P_T2_A24_15")
			(pintype "bidirectional")
		)
		(pad "N21" smd circle
			(at 9.499 1.499 90)
			(size 0.5 0.5)
			(layers "F.Cu" "F.Mask" "F.Paste")
			(net 2 "VCC3V3")
			(pinfunction "VCCO_15")
			(pintype "passive")
		)
		(pad "N22" smd circle
			(at 10.499 1.499 90)
			(size 0.5 0.5)
			(layers "F.Cu" "F.Mask" "F.Paste")
			(net 141 "ETH_MDC")
			(pinfunction "IO_L15P_T2_DQS_15")
			(pintype "bidirectional")
		)
		(pad "P1" smd circle
			(at -10.5 2.499 90)
			(size 0.5 0.5)
			(layers "F.Cu" "F.Mask" "F.Paste")
			(net 167 "DDR3_A5")
			(pinfunction "IO_L20N_T3_35")
			(pintype "bidirectional")
		)
		(pad "P2" smd circle
			(at -9.5 2.499 90)
			(size 0.5 0.5)
			(layers "F.Cu" "F.Mask" "F.Paste")
			(net 151 "DDR3_A13")
			(pinfunction "IO_L22P_T3_35")
			(pintype "bidirectional")
		)
		(pad "P3" smd circle
			(at -8.5 2.499 90)
			(size 0.5 0.5)
			(layers "F.Cu" "F.Mask" "F.Paste")
			(net 1 "GND")
			(pinfunction "GND")
			(pintype "passive")
		)
		(pad "P4" smd circle
			(at -7.5 2.499 90)
			(size 0.5 0.5)
			(layers "F.Cu" "F.Mask" "F.Paste")
			(net 478 "DDR3_CLK_N")
			(pinfunction "IO_L21N_T3_DQS_35")
			(pintype "bidirectional")
		)
		(pad "P5" smd circle
			(at -6.5 2.499 90)
			(size 0.5 0.5)
			(layers "F.Cu" "F.Mask" "F.Paste")
			(net 479 "DDR3_CLK_P")
			(pinfunction "IO_L21P_T3_DQS_35")
			(pintype "bidirectional")
		)
		(pad "P6" smd circle
			(at -5.5 2.499 90)
			(size 0.5 0.5)
			(layers "F.Cu" "F.Mask" "F.Paste")
			(net 144 "DDR3_A14")
			(pinfunction "IO_L24P_T3_35")
			(pintype "bidirectional")
		)
		(pad "P7" smd circle
			(at -4.5 2.499 90)
			(size 0.5 0.5)
			(layers "F.Cu" "F.Mask" "F.Paste")
			(net 1 "GND")
			(pinfunction "GND")
			(pintype "passive")
		)
		(pad "P8" smd circle
			(at -3.5 2.499 90)
			(size 0.5 0.5)
			(layers "F.Cu" "F.Mask" "F.Paste")
			(net 6 "VCC1V0")
			(pinfunction "VCCINT")
			(pintype "passive")
		)
		(pad "P9" smd circle
			(at -2.5 2.499 90)
			(size 0.5 0.5)
			(layers "F.Cu" "F.Mask" "F.Paste")
			(net 1 "GND")
			(pinfunction "GND")
			(pintype "passive")
		)
		(pad "P10" smd circle
			(at -1.5 2.499 90)
			(size 0.5 0.5)
			(layers "F.Cu" "F.Mask" "F.Paste")
			(net 6 "VCC1V0")
			(pinfunction "VCCINT")
			(pintype "passive")
		)
		(pad "P11" smd circle
			(at -0.5 2.499 90)
			(size 0.5 0.5)
			(layers "F.Cu" "F.Mask" "F.Paste")
			(net 1 "GND")
			(pinfunction "GND")
			(pintype "passive")
		)
		(pad "P12" smd circle
			(at 0.498 2.499 90)
			(size 0.5 0.5)
			(layers "F.Cu" "F.Mask" "F.Paste")
			(net 5 "VCC1V8")
			(pinfunction "VCCAUX")
			(pintype "passive")
		)
		(pad "P13" smd circle
			(at 1.499 2.499 90)
			(size 0.5 0.5)
			(layers "F.Cu" "F.Mask" "F.Paste")
			(net 1 "GND")
			(pinfunction "GND")
			(pintype "passive")
		)
		(pad "P14" smd circle
			(at 2.499 2.499 90)
			(size 0.5 0.5)
			(layers "F.Cu" "F.Mask" "F.Paste")
			(net 617 "unconnected-(U14A-IO_L19P_T3_A10_D26_14-PadP14)")
			(pinfunction "IO_L19P_T3_A10_D26_14")
			(pintype "bidirectional+no_connect")
		)
		(pad "P15" smd circle
			(at 3.499 2.499 90)
			(size 0.5 0.5)
			(layers "F.Cu" "F.Mask" "F.Paste")
			(net 618 "unconnected-(U14A-IO_L22P_T3_A05_D21_14-PadP15)")
			(pinfunction "IO_L22P_T3_A05_D21_14")
			(pintype "bidirectional+no_connect")
		)
		(pad "P16" smd circle
			(at 4.498 2.499 90)
			(size 0.5 0.5)
			(layers "F.Cu" "F.Mask" "F.Paste")
			(net 586 "HPM_STBY_RDY_R")
			(pinfunction "IO_L24P_T3_A01_D17_14")
			(pintype "bidirectional")
		)
		(pad "P17" smd circle
			(at 5.499 2.499 90)
			(size 0.5 0.5)
			(layers "F.Cu" "F.Mask" "F.Paste")
			(net 321 "MMC_DAT0")
			(pinfunction "IO_L21N_T3_DQS_A06_D22_14")
			(pintype "bidirectional")
		)
		(pad "P18" smd circle
			(at 6.499 2.499 90)
			(size 0.5 0.5)
			(layers "F.Cu" "F.Mask" "F.Paste")
			(net 2 "VCC3V3")
			(pinfunction "VCCO_14")
			(pintype "passive")
		)
		(pad "P19" smd circle
			(at 7.499 2.499 90)
			(size 0.5 0.5)
			(layers "F.Cu" "F.Mask" "F.Paste")
			(net 624 "DBG_UART_RX")
			(pinfunction "IO_L5P_T0_D06_14")
			(pintype "bidirectional")
		)
		(pad "P20" smd circle
			(at 8.499 2.499 90)
			(size 0.5 0.5)
			(layers "F.Cu" "F.Mask" "F.Paste")
			(net 619 "unconnected-(U14A-IO_0_14-PadP20)")
			(pinfunction "IO_0_14")
			(pintype "bidirectional+no_connect")
		)
		(pad "P21" smd circle
			(at 9.499 2.499 90)
			(size 0.5 0.5)
			(layers "F.Cu" "F.Mask" "F.Paste")
			(net 332 "ROT_QSPI_DQ2")
			(pinfunction "IO_L2P_T0_D02_14")
			(pintype "bidirectional")
		)
		(pad "P22" smd circle
			(at 10.499 2.499 90)
			(size 0.5 0.5)
			(layers "F.Cu" "F.Mask" "F.Paste")
			(net 335 "ROT_QSPI_DQ0")
			(pinfunction "IO_L1P_T0_D00_MOSI_14")
			(pintype "bidirectional")
		)
		(pad "R1" smd circle
			(at -10.5 3.499 90)
			(size 0.5 0.5)
			(layers "F.Cu" "F.Mask" "F.Paste")
			(net 149 "DDR3_A9")
			(pinfunction "IO_L20P_T3_35")
			(pintype "bidirectional")
		)
		(pad "R2" smd circle
			(at -9.5 3.499 90)
			(size 0.5 0.5)
			(layers "F.Cu" "F.Mask" "F.Paste")
			(net 98 "QSPI1_CS0_N")
			(pinfunction "IO_L3N_T0_DQS_34")
			(pintype "bidirectional")
		)
		(pad "R3" smd circle
			(at -8.5 3.499 90)
			(size 0.5 0.5)
			(layers "F.Cu" "F.Mask" "F.Paste")
			(net 99 "QSPI1_D0")
			(pinfunction "IO_L3P_T0_DQS_34")
			(pintype "bidirectional")
		)
		(pad "R4" smd circle
			(at -7.5 3.499 90)
			(size 0.5 0.5)
			(layers "F.Cu" "F.Mask" "F.Paste")
			(net 97 "QSPI1_CLK")
			(pinfunction "IO_L13P_T2_MRCC_34")
			(pintype "bidirectional")
		)
		(pad "R5" smd circle
			(at -6.5 3.499 90)
			(size 0.5 0.5)
			(layers "F.Cu" "F.Mask" "F.Paste")
			(net 2 "VCC3V3")
			(pinfunction "VCCO_34")
			(pintype "passive")
		)
		(pad "R6" smd circle
			(at -5.5 3.499 90)
			(size 0.5 0.5)
			(layers "F.Cu" "F.Mask" "F.Paste")
			(net 620 "unconnected-(U14C-IO_L17P_T2_34-PadR6)")
			(pinfunction "IO_L17P_T2_34")
			(pintype "bidirectional+no_connect")
		)
		(pad "R7" smd circle
			(at -4.5 3.499 90)
			(size 0.5 0.5)
			(layers "F.Cu" "F.Mask" "F.Paste")
			(net 6 "VCC1V0")
			(pinfunction "VCCINT")
			(pintype "passive")
		)
		(pad "R8" smd circle
			(at -3.5 3.499 90)
			(size 0.5 0.5)
			(layers "F.Cu" "F.Mask" "F.Paste")
			(net 1 "GND")
			(pinfunction "GND")
			(pintype "passive")
		)
		(pad "R9" smd circle
			(at -2.5 3.499 90)
			(size 0.5 0.5)
			(layers "F.Cu" "F.Mask" "F.Paste")
			(net 6 "VCC1V0")
			(pinfunction "VCCINT")
			(pintype "passive")
		)
		(pad "R10" smd circle
			(at -1.5 3.499 90)
			(size 0.5 0.5)
			(layers "F.Cu" "F.Mask" "F.Paste")
			(net 1 "GND")
			(pinfunction "GND")
			(pintype "passive")
		)
		(pad "R11" smd circle
			(at -0.5 3.499 90)
			(size 0.5 0.5)
			(layers "F.Cu" "F.Mask" "F.Paste")
			(net 5 "VCC1V8")
			(pinfunction "VCCAUX")
			(pintype "passive")
		)
		(pad "R12" smd circle
			(at 0.498 3.499 90)
			(size 0.5 0.5)
			(layers "F.Cu" "F.Mask" "F.Paste")
			(net 1 "GND")
			(pinfunction "GND")
			(pintype "passive")
		)
		(pad "R13" smd circle
			(at 1.499 3.499 90)
			(size 0.5 0.5)
			(layers "F.Cu" "F.Mask" "F.Paste")
			(net 13 "JTAG_TDI")
			(pinfunction "TDI_0")
			(pintype "bidirectional")
		)
		(pad "R14" smd circle
			(at 2.499 3.499 90)
			(size 0.5 0.5)
			(layers "F.Cu" "F.Mask" "F.Paste")
			(net 621 "unconnected-(U14A-IO_L19N_T3_A09_D25_VREF_14-PadR14)")
			(pinfunction "IO_L19N_T3_A09_D25_VREF_14")
			(pintype "bidirectional+no_connect")
		)
		(pad "R15" smd circle
			(at 3.499 3.499 90)
			(size 0.5 0.5)
			(layers "F.Cu" "F.Mask" "F.Paste")
			(net 2 "VCC3V3")
			(pinfunction "VCCO_14")
			(pintype "passive")
		)
		(pad "R16" smd circle
			(at 4.498 3.499 90)
			(size 0.5 0.5)
			(layers "F.Cu" "F.Mask" "F.Paste")
			(net 622 "unconnected-(U14A-IO_L22N_T3_A04_D20_14-PadR16)")
			(pinfunction "IO_L22N_T3_A04_D20_14")
			(pintype "bidirectional+no_connect")
		)
		(pad "R17" smd circle
			(at 5.499 3.499 90)
			(size 0.5 0.5)
			(layers "F.Cu" "F.Mask" "F.Paste")
			(net 328 "MMC_DAT7")
			(pinfunction "IO_L24N_T3_A00_D16_14")
			(pintype "bidirectional")
		)
		(pad "R18" smd circle
			(at 6.499 3.499 90)
			(size 0.5 0.5)
			(layers "F.Cu" "F.Mask" "F.Paste")
			(net 323 "MMC_DAT2")
			(pinfunction "IO_L20P_T3_A08_D24_14")
			(pintype "bidirectional")
		)
		(pad "R19" smd circle
			(at 7.499 3.499 90)
			(size 0.5 0.5)
			(layers "F.Cu" "F.Mask" "F.Paste")
			(net 626 "DBG_UART_TX")
			(pinfunction "IO_L5N_T0_D07_14")
			(pintype "bidirectional")
		)
		(pad "R20" smd circle
			(at 8.499 3.499 90)
			(size 0.5 0.5)
			(layers "F.Cu" "F.Mask" "F.Paste")
			(net 1 "GND")
			(pinfunction "GND")
			(pintype "passive")
		)
		(pad "R21" smd circle
			(at 9.499 3.499 90)
			(size 0.5 0.5)
			(layers "F.Cu" "F.Mask" "F.Paste")
			(net 333 "ROT_QSPI_DQ3")
			(pinfunction "IO_L2N_T0_D03_14")
			(pintype "bidirectional")
		)
		(pad "R22" smd circle
			(at 10.499 3.499 90)
			(size 0.5 0.5)
			(layers "F.Cu" "F.Mask" "F.Paste")
			(net 336 "ROT_QSPI_DQ1")
			(pinfunction "IO_L1N_T0_D01_DIN_14")
			(pintype "bidirectional")
		)
		(pad "T1" smd circle
			(at -10.5 4.498 90)
			(size 0.5 0.5)
			(layers "F.Cu" "F.Mask" "F.Paste")
			(net 102 "QSPI1_D3")
			(pinfunction "IO_L1P_T0_34")
			(pintype "bidirectional")
		)
		(pad "T2" smd circle
			(at -9.5 4.498 90)
			(size 0.5 0.5)
			(layers "F.Cu" "F.Mask" "F.Paste")
			(net 2 "VCC3V3")
			(pinfunction "VCCO_34")
			(pintype "passive")
		)
		(pad "T3" smd circle
			(at -8.5 4.498 90)
			(size 0.5 0.5)
			(layers "F.Cu" "F.Mask" "F.Paste")
			(net 101 "QSPI1_D2")
			(pinfunction "IO_0_34")
			(pintype "bidirectional")
		)
		(pad "T4" smd circle
			(at -7.5 4.498 90)
			(size 0.5 0.5)
			(layers "F.Cu" "F.Mask" "F.Paste")
			(net 100 "QSPI1_D1")
			(pinfunction "IO_L13N_T2_MRCC_34")
			(pintype "bidirectional")
		)
		(pad "T5" smd circle
			(at -6.5 4.498 90)
			(size 0.5 0.5)
			(layers "F.Cu" "F.Mask" "F.Paste")
			(net 37 "I2C[9]_SCL")
			(pinfunction "IO_L14P_T2_SRCC_34")
			(pintype "bidirectional")
		)
		(pad "T6" smd circle
			(at -5.5 4.498 90)
			(size 0.5 0.5)
			(layers "F.Cu" "F.Mask" "F.Paste")
			(net 38 "I2C[9]_SDA")
			(pinfunction "IO_L17N_T2_34")
			(pintype "bidirectional")
		)
		(pad "T7" smd circle
			(at -4.5 4.498 90)
			(size 0.5 0.5)
			(layers "F.Cu" "F.Mask" "F.Paste")
			(net 1 "GND")
			(pinfunction "GND")
			(pintype "passive")
		)
		(pad "T8" smd circle
			(at -3.5 4.498 90)
			(size 0.5 0.5)
			(layers "F.Cu" "F.Mask" "F.Paste")
			(net 6 "VCC1V0")
			(pinfunction "VCCINT")
			(pintype "passive")
		)
		(pad "T9" smd circle
			(at -2.5 4.498 90)
			(size 0.5 0.5)
			(layers "F.Cu" "F.Mask" "F.Paste")
			(net 1 "GND")
			(pinfunction "GND")
			(pintype "passive")
		)
		(pad "T10" smd circle
			(at -1.5 4.498 90)
			(size 0.5 0.5)
			(layers "F.Cu" "F.Mask" "F.Paste")
			(net 6 "VCC1V0")
			(pinfunction "VCCINT")
			(pintype "passive")
		)
		(pad "T11" smd circle
			(at -0.5 4.498 90)
			(size 0.5 0.5)
			(layers "F.Cu" "F.Mask" "F.Paste")
			(net 1 "GND")
			(pinfunction "GND")
			(pintype "passive")
		)
		(pad "T12" smd circle
			(at 0.498 4.498 90)
			(size 0.5 0.5)
			(layers "F.Cu" "F.Mask" "F.Paste")
			(net 2 "VCC3V3")
			(pinfunction "VCCO_0")
			(pintype "passive")
		)
		(pad "T13" smd circle
			(at 1.499 4.498 90)
			(size 0.5 0.5)
			(layers "F.Cu" "F.Mask" "F.Paste")
			(net 16 "JTAG_TMS")
			(pinfunction "TMS_0")
			(pintype "bidirectional")
		)
		(pad "T14" smd circle
			(at 2.499 4.498 90)
			(size 0.5 0.5)
			(layers "F.Cu" "F.Mask" "F.Paste")
			(net 623 "unconnected-(U14A-IO_L15P_T2_DQS_13-PadT14)")
			(pinfunction "IO_L15P_T2_DQS_13")
			(pintype "bidirectional+no_connect")
		)
		(pad "T15" smd circle
			(at 3.499 4.498 90)
			(size 0.5 0.5)
			(layers "F.Cu" "F.Mask" "F.Paste")
			(net 625 "unconnected-(U14A-IO_L15N_T2_DQS_13-PadT15)")
			(pinfunction "IO_L15N_T2_DQS_13")
			(pintype "bidirectional+no_connect")
		)
		(pad "T16" smd circle
			(at 4.498 4.498 90)
			(size 0.5 0.5)
			(layers "F.Cu" "F.Mask" "F.Paste")
			(net 627 "unconnected-(U14A-IO_L17P_T2_13-PadT16)")
			(pinfunction "IO_L17P_T2_13")
			(pintype "bidirectional+no_connect")
		)
		(pad "T17" smd circle
			(at 5.499 4.498 90)
			(size 0.5 0.5)
			(layers "F.Cu" "F.Mask" "F.Paste")
			(net 1 "GND")
			(pinfunction "GND")
			(pintype "passive")
		)
		(pad "T18" smd circle
			(at 6.499 4.498 90)
			(size 0.5 0.5)
			(layers "F.Cu" "F.Mask" "F.Paste")
			(net 327 "MMC_DAT6")
			(pinfunction "IO_L20N_T3_A07_D23_14")
			(pintype "bidirectional")
		)
		(pad "T19" smd circle
			(at 7.499 4.498 90)
			(size 0.5 0.5)
			(layers "F.Cu" "F.Mask" "F.Paste")
			(net 344 "Net-(U14A-IO_L6P_T0_FCS_B_14)")
			(pinfunction "IO_L6P_T0_FCS_B_14")
			(pintype "bidirectional")
		)
		(pad "T20" smd circle
			(at 8.499 4.498 90)
			(size 0.5 0.5)
			(layers "F.Cu" "F.Mask" "F.Paste")
			(net 316 "USR_LED0")
			(pinfunction "IO_L6N_T0_D08_VREF_14")
			(pintype "bidirectional")
		)
		(pad "T21" smd circle
			(at 9.499 4.498 90)
			(size 0.5 0.5)
			(layers "F.Cu" "F.Mask" "F.Paste")
			(net 33 "UART1_SCM_RX")
			(pinfunction "IO_L4P_T0_D04_14")
			(pintype "bidirectional")
		)
		(pad "T22" smd circle
			(at 10.499 4.498 90)
			(size 0.5 0.5)
			(layers "F.Cu" "F.Mask" "F.Paste")
			(net 2 "VCC3V3")
			(pinfunction "VCCO_14")
			(pintype "passive")
		)
		(pad "U1" smd circle
			(at -10.5 5.499 90)
			(size 0.5 0.5)
			(layers "F.Cu" "F.Mask" "F.Paste")
			(net 388 "HPM_STBY_RST_N_R")
			(pinfunction "IO_L1N_T0_34")
			(pintype "bidirectional")
		)
		(pad "U2" smd circle
			(at -9.5 5.499 90)
			(size 0.5 0.5)
			(layers "F.Cu" "F.Mask" "F.Paste")
			(net 389 "SYS_PWRBTN_N_R")
			(pinfunction "IO_L2P_T0_34")
			(pintype "bidirectional")
		)
		(pad "U3" smd circle
			(at -8.5 5.499 90)
			(size 0.5 0.5)
			(layers "F.Cu" "F.Mask" "F.Paste")
			(net 387 "HPM_FW_RECOVERY_R")
			(pinfunction "IO_L6P_T0_34")
			(pintype "bidirectional")
		)
		(pad "U4" smd circle
			(at -7.5 5.499 90)
			(size 0.5 0.5)
			(layers "F.Cu" "F.Mask" "F.Paste")
			(net 1 "GND")
			(pinfunction "GND")
			(pintype "passive")
		)
		(pad "U5" smd circle
			(at -6.5 5.499 90)
			(size 0.5 0.5)
			(layers "F.Cu" "F.Mask" "F.Paste")
			(net 94 "SGPIO_RESET_N")
			(pinfunction "IO_L14N_T2_SRCC_34")
			(pintype "bidirectional")
		)
		(pad "U6" smd circle
			(at -5.5 5.499 90)
			(size 0.5 0.5)
			(layers "F.Cu" "F.Mask" "F.Paste")
			(net 42 "I2C[10]_SCL")
			(pinfunction "IO_L16P_T2_34")
			(pintype "bidirectional")
		)
		(pad "U7" smd circle
			(at -4.5 5.499 90)
			(size 0.5 0.5)
			(layers "F.Cu" "F.Mask" "F.Paste")
			(net 95 "SGPIO_INTR_N")
			(pinfunction "IO_25_34")
			(pintype "bidirectional")
		)
		(pad "U8" smd circle
			(at -3.5 5.499 90)
			(size 0.5 0.5)
			(layers "F.Cu" "F.Mask" "F.Paste")
			(net 342 "Net-(U14D-CFGBVS_0)")
			(pinfunction "CFGBVS_0")
			(pintype "bidirectional")
		)
		(pad "U9" smd circle
			(at -2.5 5.499 90)
			(size 0.5 0.5)
			(layers "F.Cu" "F.Mask" "F.Paste")
			(net 259 "/FPGA banks 34-35 & CFG/MODE2")
			(pinfunction "M2_0")
			(pintype "bidirectional")
		)
		(pad "U10" smd circle
			(at -1.5 5.499 90)
			(size 0.5 0.5)
			(layers "F.Cu" "F.Mask" "F.Paste")
			(net 268 "/FPGA banks 34-35 & CFG/MODE1")
			(pinfunction "M1_0")
			(pintype "bidirectional")
		)
		(pad "U11" smd circle
			(at -0.5 5.499 90)
			(size 0.5 0.5)
			(layers "F.Cu" "F.Mask" "F.Paste")
			(net 267 "/FPGA banks 34-35 & CFG/MODE0")
			(pinfunction "M0_0")
			(pintype "bidirectional")
		)
		(pad "U12" smd circle
			(at 0.498 5.499 90)
			(size 0.5 0.5)
			(layers "F.Cu" "F.Mask" "F.Paste")
			(net 222 "INIT")
			(pinfunction "INIT_B_0")
			(pintype "bidirectional")
		)
		(pad "U13" smd circle
			(at 1.499 5.499 90)
			(size 0.5 0.5)
			(layers "F.Cu" "F.Mask" "F.Paste")
			(net 14 "JTAG_TDO")
			(pinfunction "TDO_0")
			(pintype "bidirectional")
		)
		(pad "U14" smd circle
			(at 2.499 5.499 90)
			(size 0.5 0.5)
			(layers "F.Cu" "F.Mask" "F.Paste")
			(net 1 "GND")
			(pinfunction "GND")
			(pintype "passive")
		)
		(pad "U15" smd circle
			(at 3.499 5.499 90)
			(size 0.5 0.5)
			(layers "F.Cu" "F.Mask" "F.Paste")
			(net 628 "unconnected-(U14A-IO_L14P_T2_SRCC_13-PadU15)")
			(pinfunction "IO_L14P_T2_SRCC_13")
			(pintype "bidirectional+no_connect")
		)
		(pad "U16" smd circle
			(at 4.498 5.499 90)
			(size 0.5 0.5)
			(layers "F.Cu" "F.Mask" "F.Paste")
			(net 629 "unconnected-(U14A-IO_L17N_T2_13-PadU16)")
			(pinfunction "IO_L17N_T2_13")
			(pintype "bidirectional+no_connect")
		)
		(pad "U17" smd circle
			(at 5.499 5.499 90)
			(size 0.5 0.5)
			(layers "F.Cu" "F.Mask" "F.Paste")
			(net 326 "MMC_DAT5")
			(pinfunction "IO_L18P_T2_A12_D28_14")
			(pintype "bidirectional")
		)
		(pad "U18" smd circle
			(at 6.499 5.499 90)
			(size 0.5 0.5)
			(layers "F.Cu" "F.Mask" "F.Paste")
			(net 325 "MMC_DAT4")
			(pinfunction "IO_L18N_T2_A11_D27_14")
			(pintype "bidirectional")
		)
		(pad "U19" smd circle
			(at 7.499 5.499 90)
			(size 0.5 0.5)
			(layers "F.Cu" "F.Mask" "F.Paste")
			(net 2 "VCC3V3")
			(pinfunction "VCCO_14")
			(pintype "passive")
		)
		(pad "U20" smd circle
			(at 8.499 5.499 90)
			(size 0.5 0.5)
			(layers "F.Cu" "F.Mask" "F.Paste")
			(net 317 "USR_LED1")
			(pinfunction "IO_L11P_T1_SRCC_14")
			(pintype "bidirectional")
		)
		(pad "U21" smd circle
			(at 9.499 5.499 90)
			(size 0.5 0.5)
			(layers "F.Cu" "F.Mask" "F.Paste")
			(net 40 "UART1_SCM_TX")
			(pinfunction "IO_L4N_T0_D05_14")
			(pintype "bidirectional")
		)
		(pad "U22" smd circle
			(at 10.499 5.499 90)
			(size 0.5 0.5)
			(layers "F.Cu" "F.Mask" "F.Paste")
			(net 260 "/FPGA banks 13-16/PUDC_B")
			(pinfunction "IO_L3P_T0_DQS_PUDC_B_14")
			(pintype "bidirectional")
		)
		(pad "V1" smd circle
			(at -10.5 6.499 90)
			(size 0.5 0.5)
			(layers "F.Cu" "F.Mask" "F.Paste")
			(net 1 "GND")
			(pinfunction "GND")
			(pintype "passive")
		)
		(pad "V2" smd circle
			(at -9.5 6.499 90)
			(size 0.5 0.5)
			(layers "F.Cu" "F.Mask" "F.Paste")
			(net 391 "DBP_PREQ_N_R")
			(pinfunction "IO_L2N_T0_34")
			(pintype "bidirectional")
		)
		(pad "V3" smd circle
			(at -8.5 6.499 90)
			(size 0.5 0.5)
			(layers "F.Cu" "F.Mask" "F.Paste")
			(net 390 "SYS_PWROK_R")
			(pinfunction "IO_L6N_T0_VREF_34")
			(pintype "bidirectional")
		)
		(pad "V4" smd circle
			(at -7.5 6.499 90)
			(size 0.5 0.5)
			(layers "F.Cu" "F.Mask" "F.Paste")
			(net 461 "ULPI2_CLKOUT")
			(pinfunction "IO_L12P_T1_MRCC_34")
			(pintype "bidirectional")
		)
		(pad "V5" smd circle
			(at -6.5 6.499 90)
			(size 0.5 0.5)
			(layers "F.Cu" "F.Mask" "F.Paste")
			(net 86 "SGPIO0_DO")
			(pinfunction "IO_L16N_T2_34")
			(pintype "bidirectional")
		)
		(pad "V6" smd circle
			(at -5.5 6.499 90)
			(size 0.5 0.5)
			(layers "F.Cu" "F.Mask" "F.Paste")
			(net 2 "VCC3V3")
			(pinfunction "VCCO_34")
			(pintype "passive")
		)
		(pad "V7" smd circle
			(at -4.5 6.499 90)
			(size 0.5 0.5)
			(layers "F.Cu" "F.Mask" "F.Paste")
			(net 89 "SGPIO0_LD")
			(pinfunction "IO_L19P_T3_34")
			(pintype "bidirectional")
		)
		(pad "V8" smd circle
			(at -3.5 6.499 90)
			(size 0.5 0.5)
			(layers "F.Cu" "F.Mask" "F.Paste")
			(net 44 "I2C[12]_SCL")
			(pinfunction "IO_L21N_T3_DQS_34")
			(pintype "bidirectional")
		)
		(pad "V9" smd circle
			(at -2.5 6.499 90)
			(size 0.5 0.5)
			(layers "F.Cu" "F.Mask" "F.Paste")
			(net 43 "I2C[12]_SDA")
			(pinfunction "IO_L21P_T3_DQS_34")
			(pintype "bidirectional")
		)
		(pad "V10" smd circle
			(at -1.5 6.499 90)
			(size 0.5 0.5)
			(layers "F.Cu" "F.Mask" "F.Paste")
			(net 630 "unconnected-(U14A-IO_L10P_T1_13-PadV10)")
			(pinfunction "IO_L10P_T1_13")
			(pintype "bidirectional+no_connect")
		)
		(pad "V11" smd circle
			(at -0.5 6.499 90)
			(size 0.5 0.5)
			(layers "F.Cu" "F.Mask" "F.Paste")
			(net 1 "GND")
			(pinfunction "GND")
			(pintype "passive")
		)
		(pad "V12" smd circle
			(at 0.498 6.499 90)
			(size 0.5 0.5)
			(layers "F.Cu" "F.Mask" "F.Paste")
			(net 15 "JTAG_TCK")
			(pinfunction "TCK_0")
			(pintype "bidirectional")
		)
		(pad "V13" smd circle
			(at 1.499 6.499 90)
			(size 0.5 0.5)
			(layers "F.Cu" "F.Mask" "F.Paste")
			(net 631 "unconnected-(U14A-IO_L13P_T2_MRCC_13-PadV13)")
			(pinfunction "IO_L13P_T2_MRCC_13")
			(pintype "bidirectional+no_connect")
		)
		(pad "V14" smd circle
			(at 2.499 6.499 90)
			(size 0.5 0.5)
			(layers "F.Cu" "F.Mask" "F.Paste")
			(net 632 "unconnected-(U14A-IO_L13N_T2_MRCC_13-PadV14)")
			(pinfunction "IO_L13N_T2_MRCC_13")
			(pintype "bidirectional+no_connect")
		)
		(pad "V15" smd circle
			(at 3.499 6.499 90)
			(size 0.5 0.5)
			(layers "F.Cu" "F.Mask" "F.Paste")
			(net 633 "unconnected-(U14A-IO_L14N_T2_SRCC_13-PadV15)")
			(pinfunction "IO_L14N_T2_SRCC_13")
			(pintype "bidirectional+no_connect")
		)
		(pad "V16" smd circle
			(at 4.498 6.499 90)
			(size 0.5 0.5)
			(layers "F.Cu" "F.Mask" "F.Paste")
			(net 2 "VCC3V3")
			(pinfunction "VCCO_13")
			(pintype "passive")
		)
		(pad "V17" smd circle
			(at 5.499 6.499 90)
			(size 0.5 0.5)
			(layers "F.Cu" "F.Mask" "F.Paste")
			(net 585 "HPM_STBY_EN_R")
			(pinfunction "IO_L16P_T2_CSI_B_14")
			(pintype "bidirectional")
		)
		(pad "V18" smd circle
			(at 6.499 6.499 90)
			(size 0.5 0.5)
			(layers "F.Cu" "F.Mask" "F.Paste")
			(net 324 "MMC_DAT3")
			(pinfunction "IO_L14P_T2_SRCC_14")
			(pintype "bidirectional")
		)
		(pad "V19" smd circle
			(at 7.499 6.499 90)
			(size 0.5 0.5)
			(layers "F.Cu" "F.Mask" "F.Paste")
			(net 331 "MMC_RSTN")
			(pinfunction "IO_L14N_T2_SRCC_14")
			(pintype "bidirectional")
		)
		(pad "V20" smd circle
			(at 8.499 6.499 90)
			(size 0.5 0.5)
			(layers "F.Cu" "F.Mask" "F.Paste")
			(net 442 "ULPI1_RESET")
			(pinfunction "IO_L11N_T1_SRCC_14")
			(pintype "bidirectional")
		)
		(pad "V21" smd circle
			(at 9.499 6.499 90)
			(size 0.5 0.5)
			(layers "F.Cu" "F.Mask" "F.Paste")
			(net 1 "GND")
			(pinfunction "GND")
			(pintype "passive")
		)
		(pad "V22" smd circle
			(at 10.499 6.499 90)
			(size 0.5 0.5)
			(layers "F.Cu" "F.Mask" "F.Paste")
			(net 591 "TPM_RST")
			(pinfunction "IO_L3N_T0_DQS_EMCCLK_14")
			(pintype "bidirectional")
		)
		(pad "W1" smd circle
			(at -10.5 7.499 90)
			(size 0.5 0.5)
			(layers "F.Cu" "F.Mask" "F.Paste")
			(net 393 "RST_PLTRST_BUF_N_R")
			(pinfunction "IO_L5P_T0_34")
			(pintype "bidirectional")
		)
		(pad "W2" smd circle
			(at -9.5 7.499 90)
			(size 0.5 0.5)
			(layers "F.Cu" "F.Mask" "F.Paste")
			(net 392 "DBP_PRDY_N_R")
			(pinfunction "IO_L4P_T0_34")
			(pintype "bidirectional")
		)
		(pad "W3" smd circle
			(at -8.5 7.499 90)
			(size 0.5 0.5)
			(layers "F.Cu" "F.Mask" "F.Paste")
			(net 2 "VCC3V3")
			(pinfunction "VCCO_34")
			(pintype "power_in")
		)
		(pad "W4" smd circle
			(at -7.5 7.499 90)
			(size 0.5 0.5)
			(layers "F.Cu" "F.Mask" "F.Paste")
			(net 88 "SGPIO0_DI")
			(pinfunction "IO_L12N_T1_MRCC_34")
			(pintype "bidirectional")
		)
		(pad "W5" smd circle
			(at -6.5 7.499 90)
			(size 0.5 0.5)
			(layers "F.Cu" "F.Mask" "F.Paste")
			(net 87 "SGPIO0_CLK")
			(pinfunction "IO_L15N_T2_DQS_34")
			(pintype "bidirectional")
		)
		(pad "W6" smd circle
			(at -5.5 7.499 90)
			(size 0.5 0.5)
			(layers "F.Cu" "F.Mask" "F.Paste")
			(net 41 "I2C[10]_SDA")
			(pinfunction "IO_L15P_T2_DQS_34")
			(pintype "bidirectional")
		)
		(pad "W7" smd circle
			(at -4.5 7.499 90)
			(size 0.5 0.5)
			(layers "F.Cu" "F.Mask" "F.Paste")
			(net 34 "I2C[11]_SCL")
			(pinfunction "IO_L19N_T3_VREF_34")
			(pintype "bidirectional")
		)
		(pad "W8" smd circle
			(at -3.5 7.499 90)
			(size 0.5 0.5)
			(layers "F.Cu" "F.Mask" "F.Paste")
			(net 1 "GND")
			(pinfunction "GND")
			(pintype "passive")
		)
		(pad "W9" smd circle
			(at -2.5 7.499 90)
			(size 0.5 0.5)
			(layers "F.Cu" "F.Mask" "F.Paste")
			(net 36 "I2C[11]_SDA")
			(pinfunction "IO_L24P_T3_34")
			(pintype "bidirectional")
		)
		(pad "W10" smd circle
			(at -1.5 7.499 90)
			(size 0.5 0.5)
			(layers "F.Cu" "F.Mask" "F.Paste")
			(net 634 "unconnected-(U14A-IO_L10N_T1_13-PadW10)")
			(pinfunction "IO_L10N_T1_13")
			(pintype "bidirectional+no_connect")
		)
		(pad "W11" smd circle
			(at -0.5 7.499 90)
			(size 0.5 0.5)
			(layers "F.Cu" "F.Mask" "F.Paste")
			(net 635 "unconnected-(U14A-IO_L12P_T1_MRCC_13-PadW11)")
			(pinfunction "IO_L12P_T1_MRCC_13")
			(pintype "bidirectional+no_connect")
		)
		(pad "W12" smd circle
			(at 0.498 7.499 90)
			(size 0.5 0.5)
			(layers "F.Cu" "F.Mask" "F.Paste")
			(net 636 "unconnected-(U14A-IO_L12N_T1_MRCC_13-PadW12)")
			(pinfunction "IO_L12N_T1_MRCC_13")
			(pintype "bidirectional+no_connect")
		)
		(pad "W13" smd circle
			(at 1.499 7.499 90)
			(size 0.5 0.5)
			(layers "F.Cu" "F.Mask" "F.Paste")
			(net 2 "VCC3V3")
			(pinfunction "VCCO_13")
			(pintype "passive")
		)
		(pad "W14" smd circle
			(at 2.499 7.499 90)
			(size 0.5 0.5)
			(layers "F.Cu" "F.Mask" "F.Paste")
			(net 637 "unconnected-(U14A-IO_L6P_T0_13-PadW14)")
			(pinfunction "IO_L6P_T0_13")
			(pintype "bidirectional+no_connect")
		)
		(pad "W15" smd circle
			(at 3.499 7.499 90)
			(size 0.5 0.5)
			(layers "F.Cu" "F.Mask" "F.Paste")
			(net 638 "unconnected-(U14A-IO_L16P_T2_13-PadW15)")
			(pinfunction "IO_L16P_T2_13")
			(pintype "bidirectional+no_connect")
		)
		(pad "W16" smd circle
			(at 4.498 7.499 90)
			(size 0.5 0.5)
			(layers "F.Cu" "F.Mask" "F.Paste")
			(net 639 "unconnected-(U14A-IO_L16N_T2_13-PadW16)")
			(pinfunction "IO_L16N_T2_13")
			(pintype "bidirectional+no_connect")
		)
		(pad "W17" smd circle
			(at 5.499 7.499 90)
			(size 0.5 0.5)
			(layers "F.Cu" "F.Mask" "F.Paste")
			(net 322 "MMC_DAT1")
			(pinfunction "IO_L16N_T2_A15_D31_14")
			(pintype "bidirectional")
		)
		(pad "W18" smd circle
			(at 6.499 7.499 90)
			(size 0.5 0.5)
			(layers "F.Cu" "F.Mask" "F.Paste")
			(net 1 "GND")
			(pinfunction "GND")
			(pintype "passive")
		)
		(pad "W19" smd circle
			(at 7.499 7.499 90)
			(size 0.5 0.5)
			(layers "F.Cu" "F.Mask" "F.Paste")
			(net 447 "ULPI1_CLKOUT")
			(pinfunction "IO_L12P_T1_MRCC_14")
			(pintype "bidirectional")
		)
		(pad "W20" smd circle
			(at 8.499 7.499 90)
			(size 0.5 0.5)
			(layers "F.Cu" "F.Mask" "F.Paste")
			(net 318 "USR_LED2")
			(pinfunction "IO_L12N_T1_MRCC_14")
			(pintype "bidirectional")
		)
		(pad "W21" smd circle
			(at 9.499 7.499 90)
			(size 0.5 0.5)
			(layers "F.Cu" "F.Mask" "F.Paste")
			(net 445 "ULPI1_DIR")
			(pinfunction "IO_L7P_T1_D09_14")
			(pintype "bidirectional")
		)
		(pad "W22" smd circle
			(at 10.499 7.499 90)
			(size 0.5 0.5)
			(layers "F.Cu" "F.Mask" "F.Paste")
			(net 444 "ULPI1_NXT")
			(pinfunction "IO_L7N_T1_D10_14")
			(pintype "bidirectional")
		)
		(pad "Y1" smd circle
			(at -10.5 8.499 90)
			(size 0.5 0.5)
			(layers "F.Cu" "F.Mask" "F.Paste")
			(net 395 "RoT_CPU_RST_N_R")
			(pinfunction "IO_L5N_T0_34")
			(pintype "bidirectional")
		)
		(pad "Y2" smd circle
			(at -9.5 8.499 90)
			(size 0.5 0.5)
			(layers "F.Cu" "F.Mask" "F.Paste")
			(net 394 "SPARE1_R")
			(pinfunction "IO_L4N_T0_34")
			(pintype "bidirectional")
		)
		(pad "Y3" smd circle
			(at -8.5 8.499 90)
			(size 0.5 0.5)
			(layers "F.Cu" "F.Mask" "F.Paste")
			(net 396 "CHASI#_R")
			(pinfunction "IO_L9P_T1_DQS_34")
			(pintype "bidirectional")
		)
		(pad "Y4" smd circle
			(at -7.5 8.499 90)
			(size 0.5 0.5)
			(layers "F.Cu" "F.Mask" "F.Paste")
			(net 466 "ULPI2_DATA3")
			(pinfunction "IO_L11P_T1_SRCC_34")
			(pintype "bidirectional")
		)
		(pad "Y5" smd circle
			(at -6.5 8.499 90)
			(size 0.5 0.5)
			(layers "F.Cu" "F.Mask" "F.Paste")
			(net 1 "GND")
			(pinfunction "GND")
			(pintype "passive")
		)
		(pad "Y6" smd circle
			(at -5.5 8.499 90)
			(size 0.5 0.5)
			(layers "F.Cu" "F.Mask" "F.Paste")
			(net 90 "SGPIO1_DO")
			(pinfunction "IO_L18P_T2_34")
			(pintype "bidirectional")
		)
		(pad "Y7" smd circle
			(at -4.5 8.499 90)
			(size 0.5 0.5)
			(layers "F.Cu" "F.Mask" "F.Paste")
			(net 91 "RSVD2")
			(pinfunction "IO_L23N_T3_34")
			(pintype "bidirectional")
		)
		(pad "Y8" smd circle
			(at -3.5 8.499 90)
			(size 0.5 0.5)
			(layers "F.Cu" "F.Mask" "F.Paste")
			(net 92 "SGPIO1_DI")
			(pinfunction "IO_L23P_T3_34")
			(pintype "bidirectional")
		)
		(pad "Y9" smd circle
			(at -2.5 8.499 90)
			(size 0.5 0.5)
			(layers "F.Cu" "F.Mask" "F.Paste")
			(net 93 "SGPIO1_LD")
			(pinfunction "IO_L24N_T3_34")
			(pintype "bidirectional")
		)
		(pad "Y10" smd circle
			(at -1.5 8.499 90)
			(size 0.5 0.5)
			(layers "F.Cu" "F.Mask" "F.Paste")
			(net 2 "VCC3V3")
			(pinfunction "VCCO_13")
			(pintype "power_in")
		)
		(pad "Y11" smd circle
			(at -0.5 8.499 90)
			(size 0.5 0.5)
			(layers "F.Cu" "F.Mask" "F.Paste")
			(net 640 "unconnected-(U14A-IO_L11P_T1_SRCC_13-PadY11)")
			(pinfunction "IO_L11P_T1_SRCC_13")
			(pintype "bidirectional+no_connect")
		)
		(pad "Y12" smd circle
			(at 0.498 8.499 90)
			(size 0.5 0.5)
			(layers "F.Cu" "F.Mask" "F.Paste")
			(net 641 "unconnected-(U14A-IO_L11N_T1_SRCC_13-PadY12)")
			(pinfunction "IO_L11N_T1_SRCC_13")
			(pintype "bidirectional+no_connect")
		)
		(pad "Y13" smd circle
			(at 1.499 8.499 90)
			(size 0.5 0.5)
			(layers "F.Cu" "F.Mask" "F.Paste")
			(net 642 "unconnected-(U14A-IO_L5P_T0_13-PadY13)")
			(pinfunction "IO_L5P_T0_13")
			(pintype "bidirectional+no_connect")
		)
		(pad "Y14" smd circle
			(at 2.499 8.499 90)
			(size 0.5 0.5)
			(layers "F.Cu" "F.Mask" "F.Paste")
			(net 643 "unconnected-(U14A-IO_L6N_T0_VREF_13-PadY14)")
			(pinfunction "IO_L6N_T0_VREF_13")
			(pintype "bidirectional+no_connect")
		)
		(pad "Y15" smd circle
			(at 3.499 8.499 90)
			(size 0.5 0.5)
			(layers "F.Cu" "F.Mask" "F.Paste")
			(net 1 "GND")
			(pinfunction "GND")
			(pintype "passive")
		)
		(pad "Y16" smd circle
			(at 4.498 8.499 90)
			(size 0.5 0.5)
			(layers "F.Cu" "F.Mask" "F.Paste")
			(net 644 "unconnected-(U14A-IO_L1P_T0_13-PadY16)")
			(pinfunction "IO_L1P_T0_13")
			(pintype "bidirectional+no_connect")
		)
		(pad "Y17" smd circle
			(at 5.499 8.499 90)
			(size 0.5 0.5)
			(layers "F.Cu" "F.Mask" "F.Paste")
			(net 645 "unconnected-(U14A-IO_0_13-PadY17)")
			(pinfunction "IO_0_13")
			(pintype "bidirectional+no_connect")
		)
		(pad "Y18" smd circle
			(at 6.499 8.499 90)
			(size 0.5 0.5)
			(layers "F.Cu" "F.Mask" "F.Paste")
			(net 330 "MMC_CLK")
			(pinfunction "IO_L13P_T2_MRCC_14")
			(pintype "bidirectional")
		)
		(pad "Y19" smd circle
			(at 7.499 8.499 90)
			(size 0.5 0.5)
			(layers "F.Cu" "F.Mask" "F.Paste")
			(net 329 "MMC_CMD")
			(pinfunction "IO_L13N_T2_MRCC_14")
			(pintype "bidirectional")
		)
		(pad "Y20" smd circle
			(at 8.499 8.499 90)
			(size 0.5 0.5)
			(layers "F.Cu" "F.Mask" "F.Paste")
			(net 2 "VCC3V3")
			(pinfunction "VCCO_14")
			(pintype "power_in")
		)
		(pad "Y21" smd circle
			(at 9.499 8.499 90)
			(size 0.5 0.5)
			(layers "F.Cu" "F.Mask" "F.Paste")
			(net 590 "TPM_GPIO")
			(pinfunction "IO_L9P_T1_DQS_14")
			(pintype "bidirectional")
		)
		(pad "Y22" smd circle
			(at 10.499 8.499 90)
			(size 0.5 0.5)
			(layers "F.Cu" "F.Mask" "F.Paste")
			(net 446 "ULPI1_STP")
			(pinfunction "IO_L9N_T1_DQS_D13_14")
			(pintype "bidirectional")
		)
	)
	(footprint "antmicro-footprints:R_0402_1005Metric"
		(layer "F.Cu")
		(at 89.975 105.475)
		(descr "Resistor SMD 0402")
		(tags "resistor SMD 0402")
		(property "Reference" "R14"
			(at 0.725 0.425 0)
			(layer "F.SilkS")
			(effects
				(font
					(size 0.7 0.7)
					(thickness 0.15)
				)
				(justify left bottom)
			)
		)
		(property "Value" "R_0R_0402"
			(at 0 1.4 0)
			(layer "F.Fab")
			(effects
				(font
					(size 0.7 0.7)
					(thickness 0.15)
				)
				(justify left bottom)
			)
		)
		(property "Datasheet" "https://industrial.panasonic.com/cdbs/www-data/pdf/RDA0000/AOA0000C301.pdf"
			(at 0 0 0)
			(layer "F.Fab")
			(hide yes)
			(effects
				(font
					(size 1.27 1.27)
					(thickness 0.15)
				)
			)
		)
		(property "Description" "SMD Chip Resistor, Jumper, 0 ohm, 100 mW, 0402 [1005 Metric], Thick Film, General Purpose"
			(at 0 0 0)
			(layer "F.Fab")
			(hide yes)
			(effects
				(font
					(size 1.27 1.27)
					(thickness 0.15)
				)
			)
		)
		(property "Author" "Antmicro"
			(at 0 0 0)
			(layer "F.Fab")
			(hide yes)
			(effects
				(font
					(size 1 1)
					(thickness 0.15)
				)
			)
		)
		(property "Current" "1A"
			(at 0 0 0)
			(layer "F.Fab")
			(hide yes)
			(effects
				(font
					(size 1 1)
					(thickness 0.15)
				)
			)
		)
		(property "License" "Apache-2.0"
			(at 0 0 0)
			(layer "F.Fab")
			(hide yes)
			(effects
				(font
					(size 1 1)
					(thickness 0.15)
				)
			)
		)
		(property "MPN" "ERJ2GE0R00X"
			(at 0 0 0)
			(layer "F.Fab")
			(hide yes)
			(effects
				(font
					(size 1 1)
					(thickness 0.15)
				)
			)
		)
		(property "Manufacturer" "Panasonic"
			(at 0 0 0)
			(layer "F.Fab")
			(hide yes)
			(effects
				(font
					(size 1 1)
					(thickness 0.15)
				)
			)
		)
		(property "Tolerance" "~"
			(at 0 0 0)
			(layer "F.Fab")
			(hide yes)
			(effects
				(font
					(size 1 1)
					(thickness 0.15)
				)
			)
		)
		(property "Val" "0R"
			(at 0 0 0)
			(layer "F.Fab")
			(hide yes)
			(effects
				(font
					(size 1 1)
					(thickness 0.15)
				)
			)
		)
		(sheetname "/Power supply/")
		(sheetfile "power-supply.kicad_sch")
		(attr smd)
		(fp_rect
			(start -0.925 -0.47)
			(end 0.925 0.47)
			(stroke
				(width 0.05)
				(type default)
			)
			(fill no)
			(layer "F.CrtYd")
		)
		(fp_rect
			(start -0.5 -0.25)
			(end 0.5 0.25)
			(stroke
				(width 0.15)
				(type solid)
			)
			(fill no)
			(layer "F.Fab")
		)
		(pad "1" smd roundrect
			(at -0.48 0)
			(size 0.59 0.64)
			(layers "F.Cu" "F.Mask" "F.Paste")
			(roundrect_rratio 0.25)
			(net 314 "Net-(U10-EN)")
			(pintype "passive")
		)
		(pad "2" smd roundrect
			(at 0.48 0)
			(size 0.59 0.64)
			(layers "F.Cu" "F.Mask" "F.Paste")
			(roundrect_rratio 0.25)
			(net 297 "/Power supply/VCCIO_EN")
			(pintype "passive")
		)
	)
	(footprint "antmicro-footprints:R_0402_1005Metric"
		(layer "F.Cu")
		(at 89.975 98.075)
		(descr "Resistor SMD 0402")
		(tags "resistor SMD 0402")
		(property "Reference" "R15"
			(at 0.725 0.425 0)
			(layer "F.SilkS")
			(effects
				(font
					(size 0.7 0.7)
					(thickness 0.15)
				)
				(justify left bottom)
			)
		)
		(property "Value" "R_0R_0402"
			(at 0 1.4 0)
			(layer "F.Fab")
			(effects
				(font
					(size 0.7 0.7)
					(thickness 0.15)
				)
				(justify left bottom)
			)
		)
		(property "Datasheet" "https://industrial.panasonic.com/cdbs/www-data/pdf/RDA0000/AOA0000C301.pdf"
			(at 0 0 0)
			(layer "F.Fab")
			(hide yes)
			(effects
				(font
					(size 1.27 1.27)
					(thickness 0.15)
				)
			)
		)
		(property "Description" "SMD Chip Resistor, Jumper, 0 ohm, 100 mW, 0402 [1005 Metric], Thick Film, General Purpose"
			(at 0 0 0)
			(layer "F.Fab")
			(hide yes)
			(effects
				(font
					(size 1.27 1.27)
					(thickness 0.15)
				)
			)
		)
		(property "Author" "Antmicro"
			(at 0 0 0)
			(layer "F.Fab")
			(hide yes)
			(effects
				(font
					(size 1 1)
					(thickness 0.15)
				)
			)
		)
		(property "Current" "1A"
			(at 0 0 0)
			(layer "F.Fab")
			(hide yes)
			(effects
				(font
					(size 1 1)
					(thickness 0.15)
				)
			)
		)
		(property "License" "Apache-2.0"
			(at 0 0 0)
			(layer "F.Fab")
			(hide yes)
			(effects
				(font
					(size 1 1)
					(thickness 0.15)
				)
			)
		)
		(property "MPN" "ERJ2GE0R00X"
			(at 0 0 0)
			(layer "F.Fab")
			(hide yes)
			(effects
				(font
					(size 1 1)
					(thickness 0.15)
				)
			)
		)
		(property "Manufacturer" "Panasonic"
			(at 0 0 0)
			(layer "F.Fab")
			(hide yes)
			(effects
				(font
					(size 1 1)
					(thickness 0.15)
				)
			)
		)
		(property "Tolerance" "~"
			(at 0 0 0)
			(layer "F.Fab")
			(hide yes)
			(effects
				(font
					(size 1 1)
					(thickness 0.15)
				)
			)
		)
		(property "Val" "0R"
			(at 0 0 0)
			(layer "F.Fab")
			(hide yes)
			(effects
				(font
					(size 1 1)
					(thickness 0.15)
				)
			)
		)
		(sheetname "/Power supply/")
		(sheetfile "power-supply.kicad_sch")
		(attr smd)
		(fp_rect
			(start -0.925 -0.47)
			(end 0.925 0.47)
			(stroke
				(width 0.05)
				(type default)
			)
			(fill no)
			(layer "F.CrtYd")
		)
		(fp_rect
			(start -0.5 -0.25)
			(end 0.5 0.25)
			(stroke
				(width 0.15)
				(type solid)
			)
			(fill no)
			(layer "F.Fab")
		)
		(pad "1" smd roundrect
			(at -0.48 0)
			(size 0.59 0.64)
			(layers "F.Cu" "F.Mask" "F.Paste")
			(roundrect_rratio 0.25)
			(net 315 "Net-(U11-EN)")
			(pintype "passive")
		)
		(pad "2" smd roundrect
			(at 0.48 0)
			(size 0.59 0.64)
			(layers "F.Cu" "F.Mask" "F.Paste")
			(roundrect_rratio 0.25)
			(net 296 "/Power supply/VCCAUX_EN")
			(pintype "passive")
		)
	)
	(footprint "antmicro-footprints:R_0402_1005Metric"
		(layer "F.Cu")
		(at 89.975 83.375)
		(descr "Resistor SMD 0402")
		(tags "resistor SMD 0402")
		(property "Reference" "R16"
			(at 0.825 0.325 0)
			(layer "F.SilkS")
			(effects
				(font
					(size 0.7 0.7)
					(thickness 0.15)
				)
				(justify left bottom)
			)
		)
		(property "Value" "R_0R_0402"
			(at 0 1.4 0)
			(layer "F.Fab")
			(effects
				(font
					(size 0.7 0.7)
					(thickness 0.15)
				)
				(justify left bottom)
			)
		)
		(property "Datasheet" "https://industrial.panasonic.com/cdbs/www-data/pdf/RDA0000/AOA0000C301.pdf"
			(at 0 0 0)
			(layer "F.Fab")
			(hide yes)
			(effects
				(font
					(size 1.27 1.27)
					(thickness 0.15)
				)
			)
		)
		(property "Description" "SMD Chip Resistor, Jumper, 0 ohm, 100 mW, 0402 [1005 Metric], Thick Film, General Purpose"
			(at 0 0 0)
			(layer "F.Fab")
			(hide yes)
			(effects
				(font
					(size 1.27 1.27)
					(thickness 0.15)
				)
			)
		)
		(property "Author" "Antmicro"
			(at 0 0 0)
			(layer "F.Fab")
			(hide yes)
			(effects
				(font
					(size 1 1)
					(thickness 0.15)
				)
			)
		)
		(property "Current" "1A"
			(at 0 0 0)
			(layer "F.Fab")
			(hide yes)
			(effects
				(font
					(size 1 1)
					(thickness 0.15)
				)
			)
		)
		(property "License" "Apache-2.0"
			(at 0 0 0)
			(layer "F.Fab")
			(hide yes)
			(effects
				(font
					(size 1 1)
					(thickness 0.15)
				)
			)
		)
		(property "MPN" "ERJ2GE0R00X"
			(at 0 0 0)
			(layer "F.Fab")
			(hide yes)
			(effects
				(font
					(size 1 1)
					(thickness 0.15)
				)
			)
		)
		(property "Manufacturer" "Panasonic"
			(at 0 0 0)
			(layer "F.Fab")
			(hide yes)
			(effects
				(font
					(size 1 1)
					(thickness 0.15)
				)
			)
		)
		(property "Tolerance" "~"
			(at 0 0 0)
			(layer "F.Fab")
			(hide yes)
			(effects
				(font
					(size 1 1)
					(thickness 0.15)
				)
			)
		)
		(property "Val" "0R"
			(at 0 0 0)
			(layer "F.Fab")
			(hide yes)
			(effects
				(font
					(size 1 1)
					(thickness 0.15)
				)
			)
		)
		(sheetname "/Power supply/")
		(sheetfile "power-supply.kicad_sch")
		(attr smd)
		(fp_rect
			(start -0.925 -0.47)
			(end 0.925 0.47)
			(stroke
				(width 0.05)
				(type default)
			)
			(fill no)
			(layer "F.CrtYd")
		)
		(fp_rect
			(start -0.5 -0.25)
			(end 0.5 0.25)
			(stroke
				(width 0.15)
				(type solid)
			)
			(fill no)
			(layer "F.Fab")
		)
		(pad "1" smd roundrect
			(at -0.48 0)
			(size 0.59 0.64)
			(layers "F.Cu" "F.Mask" "F.Paste")
			(roundrect_rratio 0.25)
			(net 319 "Net-(U12-EN)")
			(pintype "passive")
		)
		(pad "2" smd roundrect
			(at 0.48 0)
			(size 0.59 0.64)
			(layers "F.Cu" "F.Mask" "F.Paste")
			(roundrect_rratio 0.25)
			(net 295 "/Power supply/VCCINT_EN")
			(pintype "passive")
		)
	)
	(footprint "antmicro-footprints:R_0402_1005Metric"
		(layer "F.Cu")
		(at 89.975 90.775)
		(descr "Resistor SMD 0402")
		(tags "resistor SMD 0402")
		(property "Reference" "R138"
			(at 0.725 0.425 0)
			(layer "F.SilkS")
			(effects
				(font
					(size 0.7 0.7)
					(thickness 0.15)
				)
				(justify left bottom)
			)
		)
		(property "Value" "R_0R_0402"
			(at 0 1.4 0)
			(layer "F.Fab")
			(effects
				(font
					(size 0.7 0.7)
					(thickness 0.15)
				)
				(justify left bottom)
			)
		)
		(property "Datasheet" "https://industrial.panasonic.com/cdbs/www-data/pdf/RDA0000/AOA0000C301.pdf"
			(at 0 0 0)
			(layer "F.Fab")
			(hide yes)
			(effects
				(font
					(size 1.27 1.27)
					(thickness 0.15)
				)
			)
		)
		(property "Description" "SMD Chip Resistor, Jumper, 0 ohm, 100 mW, 0402 [1005 Metric], Thick Film, General Purpose"
			(at 0 0 0)
			(layer "F.Fab")
			(hide yes)
			(effects
				(font
					(size 1.27 1.27)
					(thickness 0.15)
				)
			)
		)
		(property "Author" "Antmicro"
			(at 0 0 0)
			(layer "F.Fab")
			(hide yes)
			(effects
				(font
					(size 1 1)
					(thickness 0.15)
				)
			)
		)
		(property "Current" "1A"
			(at 0 0 0)
			(layer "F.Fab")
			(hide yes)
			(effects
				(font
					(size 1 1)
					(thickness 0.15)
				)
			)
		)
		(property "License" "Apache-2.0"
			(at 0 0 0)
			(layer "F.Fab")
			(hide yes)
			(effects
				(font
					(size 1 1)
					(thickness 0.15)
				)
			)
		)
		(property "MPN" "ERJ2GE0R00X"
			(at 0 0 0)
			(layer "F.Fab")
			(hide yes)
			(effects
				(font
					(size 1 1)
					(thickness 0.15)
				)
			)
		)
		(property "Manufacturer" "Panasonic"
			(at 0 0 0)
			(layer "F.Fab")
			(hide yes)
			(effects
				(font
					(size 1 1)
					(thickness 0.15)
				)
			)
		)
		(property "Tolerance" "~"
			(at 0 0 0)
			(layer "F.Fab")
			(hide yes)
			(effects
				(font
					(size 1 1)
					(thickness 0.15)
				)
			)
		)
		(property "Val" "0R"
			(at 0 0 0)
			(layer "F.Fab")
			(hide yes)
			(effects
				(font
					(size 1 1)
					(thickness 0.15)
				)
			)
		)
		(sheetname "/Power supply/")
		(sheetfile "power-supply.kicad_sch")
		(attr smd)
		(fp_rect
			(start -0.925 -0.47)
			(end 0.925 0.47)
			(stroke
				(width 0.05)
				(type default)
			)
			(fill no)
			(layer "F.CrtYd")
		)
		(fp_rect
			(start -0.5 -0.25)
			(end 0.5 0.25)
			(stroke
				(width 0.15)
				(type solid)
			)
			(fill no)
			(layer "F.Fab")
		)
		(pad "1" smd roundrect
			(at -0.48 0)
			(size 0.59 0.64)
			(layers "F.Cu" "F.Mask" "F.Paste")
			(roundrect_rratio 0.25)
			(net 343 "Net-(U13-EN)")
			(pintype "passive")
		)
		(pad "2" smd roundrect
			(at 0.48 0)
			(size 0.59 0.64)
			(layers "F.Cu" "F.Mask" "F.Paste")
			(roundrect_rratio 0.25)
			(net 297 "/Power supply/VCCIO_EN")
			(pintype "passive")
		)
	)
	(footprint "antmicro-footprints:SOIC-8_5.3x5.3x2mm_P1.27mm"
		(layer "F.Cu")
		(at 66.47 137.795 90)
		(descr "8-Pin SOIC 208-mil")
		(property "Reference" "U4"
			(at -0.0015 -3.2 90)
			(layer "F.SilkS")
			(effects
				(font
					(size 0.7 0.7)
					(thickness 0.15)
				)
				(justify left bottom)
			)
		)
		(property "Value" "W25Q32JW_SOIC-8"
			(at 0 3.8 90)
			(layer "F.Fab")
			(effects
				(font
					(size 0.7 0.7)
					(thickness 0.15)
				)
				(justify left bottom)
			)
		)
		(property "Datasheet" "https://www.mouser.com/datasheet/2/949/w25q32jw_spi_revf_09042018-1489621.pdf"
			(at 0 0 90)
			(layer "F.Fab")
			(hide yes)
			(effects
				(font
					(size 1.27 1.27)
					(thickness 0.15)
				)
			)
		)
		(property "Description" "FLASH - NOR Memory IC 32Mbit SPI - Quad I/O 133 MHz 8-SOIC"
			(at 0 0 90)
			(layer "F.Fab")
			(hide yes)
			(effects
				(font
					(size 1.27 1.27)
					(thickness 0.15)
				)
			)
		)
		(property "Author" "Antmicro"
			(at 204.265 71.325 0)
			(layer "F.Fab")
			(hide yes)
			(effects
				(font
					(size 1 1)
					(thickness 0.15)
				)
			)
		)
		(property "License" "Apache-2.0"
			(at 204.265 71.325 0)
			(layer "F.Fab")
			(hide yes)
			(effects
				(font
					(size 1 1)
					(thickness 0.15)
				)
			)
		)
		(property "MPN" "W25Q32JWSSIQ"
			(at 204.265 71.325 0)
			(layer "F.Fab")
			(hide yes)
			(effects
				(font
					(size 1 1)
					(thickness 0.15)
				)
			)
		)
		(property "Manufacturer" "Winbond"
			(at 204.265 71.325 0)
			(layer "F.Fab")
			(hide yes)
			(effects
				(font
					(size 1 1)
					(thickness 0.15)
				)
			)
		)
		(sheetname "/RoT/")
		(sheetfile "rot.kicad_sch")
		(attr smd)
		(fp_line
			(start -2.8 -2.641)
			(end -4.4 -2.641)
			(stroke
				(width 0.15)
				(type solid)
			)
			(layer "F.SilkS")
		)
		(fp_circle
			(center -4.85 -1.905)
			(end -4.8 -1.855)
			(stroke
				(width 0.15)
				(type solid)
			)
			(fill yes)
			(layer "F.SilkS")
		)
		(fp_rect
			(start 4.675 -3)
			(end -4.675 3)
			(stroke
				(width 0.05)
				(type solid)
			)
			(fill no)
			(layer "F.CrtYd")
		)
		(fp_line
			(start 2.64 -2.641)
			(end 2.64 2.64)
			(stroke
				(width 0.15)
				(type solid)
			)
			(layer "F.Fab")
		)
		(fp_line
			(start -2.641 -2.641)
			(end 2.64 -2.641)
			(stroke
				(width 0.15)
				(type solid)
			)
			(layer "F.Fab")
		)
		(fp_line
			(start -2.641 -1.371)
			(end -1.371 -2.641)
			(stroke
				(width 0.15)
				(type solid)
			)
			(layer "F.Fab")
		)
		(fp_line
			(start 2.64 2.64)
			(end -2.641 2.64)
			(stroke
				(width 0.15)
				(type solid)
			)
			(layer "F.Fab")
		)
		(fp_line
			(start -2.641 2.64)
			(end -2.641 -2.641)
			(stroke
				(width 0.15)
				(type solid)
			)
			(layer "F.Fab")
		)
		(pad "1" smd roundrect
			(at -3.601 -1.905 180)
			(size 0.65 1.65)
			(layers "F.Cu" "F.Mask" "F.Paste")
			(roundrect_rratio 0.25)
			(net 140 "QSPIA2_CS_N")
			(pinfunction "~{CS}")
			(pintype "input")
		)
		(pad "2" smd roundrect
			(at -3.601 -0.635 180)
			(size 0.65 1.65)
			(layers "F.Cu" "F.Mask" "F.Paste")
			(roundrect_rratio 0.25)
			(net 137 "QSPIA2_D1")
			(pinfunction "SO/IO1")
			(pintype "bidirectional")
		)
		(pad "3" smd roundrect
			(at -3.601 0.633 180)
			(size 0.65 1.65)
			(layers "F.Cu" "F.Mask" "F.Paste")
			(roundrect_rratio 0.25)
			(net 138 "QSPIA2_D2")
			(pinfunction "~{WP}/IO2")
			(pintype "bidirectional")
		)
		(pad "4" smd roundrect
			(at -3.601 1.904 180)
			(size 0.65 1.65)
			(layers "F.Cu" "F.Mask" "F.Paste")
			(roundrect_rratio 0.25)
			(net 1 "GND")
			(pinfunction "VSS")
			(pintype "power_in")
		)
		(pad "5" smd roundrect
			(at 3.6 1.904 180)
			(size 0.65 1.65)
			(layers "F.Cu" "F.Mask" "F.Paste")
			(roundrect_rratio 0.25)
			(net 136 "QSPIA2_D0")
			(pinfunction "SI/IO0")
			(pintype "bidirectional")
		)
		(pad "6" smd roundrect
			(at 3.6 0.633 180)
			(size 0.65 1.65)
			(layers "F.Cu" "F.Mask" "F.Paste")
			(roundrect_rratio 0.25)
			(net 130 "QSPIA_CLK")
			(pinfunction "SCLK")
			(pintype "input")
		)
		(pad "7" smd roundrect
			(at 3.6 -0.635 180)
			(size 0.65 1.65)
			(layers "F.Cu" "F.Mask" "F.Paste")
			(roundrect_rratio 0.25)
			(net 139 "QSPIA2_D3")
			(pinfunction "~{HOLD}/IO3")
			(pintype "bidirectional")
		)
		(pad "8" smd roundrect
			(at 3.6 -1.905 180)
			(size 0.65 1.65)
			(layers "F.Cu" "F.Mask" "F.Paste")
			(roundrect_rratio 0.25)
			(net 2 "VCC3V3")
			(pinfunction "VCC")
			(pintype "power_in")
		)
	)
	(footprint "antmicro-footprints:LED_0603_1608Metric_G"
		(layer "F.Cu")
		(at 141.025 61.165 90)
		(descr "LED SMD 0603 Green")
		(tags "LED SMD 0603 Green")
		(property "Reference" "D12"
			(at -1.435 4.775 90)
			(layer "F.SilkS")
			(effects
				(font
					(size 0.7 0.7)
					(thickness 0.15)
				)
				(justify left bottom)
			)
		)
		(property "Value" "LED_G_0603_LG_L29K-G2J1-24-Z"
			(at 0 1.6 90)
			(layer "F.Fab")
			(effects
				(font
					(size 0.7 0.7)
					(thickness 0.15)
				)
				(justify left bottom)
			)
		)
		(property "Datasheet" "https://look.ams-osram.com/m/19ee86b3ae0ee95b/original/LG-L29K.pdf"
			(at 0 0 90)
			(layer "F.Fab")
			(hide yes)
			(effects
				(font
					(size 1.27 1.27)
					(thickness 0.15)
				)
			)
		)
		(property "Description" "LED, Green, SMD, 0603, 20 mA, 1.7 V, 570 nm"
			(at 0 0 90)
			(layer "F.Fab")
			(hide yes)
			(effects
				(font
					(size 1.27 1.27)
					(thickness 0.15)
				)
			)
		)
		(property "Author" "Antmicro"
			(at 202.19 -79.86 0)
			(layer "F.Fab")
			(hide yes)
			(effects
				(font
					(size 1 1)
					(thickness 0.15)
				)
			)
		)
		(property "Color" "Green"
			(at 202.19 -79.86 0)
			(layer "F.Fab")
			(hide yes)
			(effects
				(font
					(size 1 1)
					(thickness 0.15)
				)
			)
		)
		(property "License" "Apache-2.0"
			(at 202.19 -79.86 0)
			(layer "F.Fab")
			(hide yes)
			(effects
				(font
					(size 1 1)
					(thickness 0.15)
				)
			)
		)
		(property "MPN" "LG L29K-G2J1-24-Z"
			(at 202.19 -79.86 0)
			(layer "F.Fab")
			(hide yes)
			(effects
				(font
					(size 1 1)
					(thickness 0.15)
				)
			)
		)
		(property "Manufacturer" "OSRAM"
			(at 202.19 -79.86 0)
			(layer "F.Fab")
			(hide yes)
			(effects
				(font
					(size 1 1)
					(thickness 0.15)
				)
			)
		)
		(sheetname "/FPGA banks 34-35 & CFG/")
		(sheetfile "fpga-banks-34-25-cfg.kicad_sch")
		(attr smd)
		(fp_line
			(start 0.22 -0.35)
			(end -0.22 -0.35)
			(stroke
				(width 0.15)
				(type solid)
			)
			(layer "F.SilkS")
		)
		(fp_line
			(start -1.18 -0.319)
			(end -1.18 0.321)
			(stroke
				(width 0.15)
				(type solid)
			)
			(layer "F.SilkS")
		)
		(fp_line
			(start 0.105328 0.001008)
			(end 0.24 0.001)
			(stroke
				(width 0.1)
				(type solid)
			)
			(layer "F.SilkS")
		)
		(fp_line
			(start -0.094672 0.001008)
			(end 0.105328 -0.198992)
			(stroke
				(width 0.1)
				(type solid)
			)
			(layer "F.SilkS")
		)
		(fp_line
			(start -0.094672 0.001008)
			(end -0.24 0.001008)
			(stroke
				(width 0.1)
				(type solid)
			)
			(layer "F.SilkS")
		)
		(fp_line
			(start 0.105328 0.201008)
			(end 0.105328 -0.198992)
			(stroke
				(width 0.1)
				(type solid)
			)
			(layer "F.SilkS")
		)
		(fp_line
			(start 0.105328 0.201008)
			(end -0.094672 0.001008)
			(stroke
				(width 0.1)
				(type solid)
			)
			(layer "F.SilkS")
		)
		(fp_line
			(start -0.094672 0.201008)
			(end -0.094672 -0.198992)
			(stroke
				(width 0.1)
				(type solid)
			)
			(layer "F.SilkS")
		)
		(fp_line
			(start 0.22 0.35)
			(end -0.22 0.35)
			(stroke
				(width 0.15)
				(type solid)
			)
			(layer "F.SilkS")
		)
		(fp_rect
			(start 1.25 0.65)
			(end -1.25 -0.65)
			(stroke
				(width 0.05)
				(type solid)
			)
			(fill no)
			(layer "F.CrtYd")
		)
		(fp_line
			(start 0.201 -0.202)
			(end -0.101 0)
			(stroke
				(width 0.15)
				(type solid)
			)
			(layer "F.Fab")
		)
		(fp_line
			(start -0.199 -0.202)
			(end -0.199 0.1)
			(stroke
				(width 0.15)
				(type solid)
			)
			(layer "F.Fab")
		)
		(fp_line
			(start 0.599 0)
			(end 0.201 0)
			(stroke
				(width 0.15)
				(type solid)
			)
			(layer "F.Fab")
		)
		(fp_line
			(start 0.201 0)
			(end 0.201 -0.202)
			(stroke
				(width 0.15)
				(type solid)
			)
			(layer "F.Fab")
		)
		(fp_line
			(start -0.101 0)
			(end 0.201 0.2)
			(stroke
				(width 0.15)
				(type solid)
			)
			(layer "F.Fab")
		)
		(fp_line
			(start -0.199 0)
			(end -0.597 0)
			(stroke
				(width 0.15)
				(type solid)
			)
			(layer "F.Fab")
		)
		(fp_line
			(start 0.201 0.2)
			(end 0.201 0)
			(stroke
				(width 0.15)
				(type solid)
			)
			(layer "F.Fab")
		)
		(fp_line
			(start -0.199 0.2)
			(end -0.199 0.1)
			(stroke
				(width 0.15)
				(type solid)
			)
			(layer "F.Fab")
		)
		(fp_rect
			(start 0.848 0.4)
			(end -0.85 -0.402)
			(stroke
				(width 0.15)
				(type solid)
			)
			(fill no)
			(layer "F.Fab")
		)
		(pad "1" smd roundrect
			(at -0.7 0 270)
			(size 0.8 1)
			(layers "F.Cu" "F.Mask" "F.Paste")
			(roundrect_rratio 0.2)
			(net 305 "Net-(D12-C)")
			(pinfunction "C")
			(pintype "passive")
		)
		(pad "2" smd roundrect
			(at 0.7 0 270)
			(size 0.8 1)
			(layers "F.Cu" "F.Mask" "F.Paste")
			(roundrect_rratio 0.2)
			(net 307 "Net-(D12-A)")
			(pinfunction "A")
			(pintype "passive")
		)
	)
	(footprint "antmicro-footprints:LED_0603_1608Metric_G"
		(layer "F.Cu")
		(at 143.04 61.165 90)
		(descr "LED SMD 0603 Green")
		(tags "LED SMD 0603 Green")
		(property "Reference" "D13"
			(at -1.435 3.86 90)
			(layer "F.SilkS")
			(effects
				(font
					(size 0.7 0.7)
					(thickness 0.15)
				)
				(justify left bottom)
			)
		)
		(property "Value" "LED_G_0603_LG_L29K-G2J1-24-Z"
			(at 0 1.6 90)
			(layer "F.Fab")
			(effects
				(font
					(size 0.7 0.7)
					(thickness 0.15)
				)
				(justify left bottom)
			)
		)
		(property "Datasheet" "https://look.ams-osram.com/m/19ee86b3ae0ee95b/original/LG-L29K.pdf"
			(at 0 0 90)
			(layer "F.Fab")
			(hide yes)
			(effects
				(font
					(size 1.27 1.27)
					(thickness 0.15)
				)
			)
		)
		(property "Description" "LED, Green, SMD, 0603, 20 mA, 1.7 V, 570 nm"
			(at 0 0 90)
			(layer "F.Fab")
			(hide yes)
			(effects
				(font
					(size 1.27 1.27)
					(thickness 0.15)
				)
			)
		)
		(property "Author" "Antmicro"
			(at 204.205 -81.875 0)
			(layer "F.Fab")
			(hide yes)
			(effects
				(font
					(size 1 1)
					(thickness 0.15)
				)
			)
		)
		(property "Color" "Green"
			(at 204.205 -81.875 0)
			(layer "F.Fab")
			(hide yes)
			(effects
				(font
					(size 1 1)
					(thickness 0.15)
				)
			)
		)
		(property "License" "Apache-2.0"
			(at 204.205 -81.875 0)
			(layer "F.Fab")
			(hide yes)
			(effects
				(font
					(size 1 1)
					(thickness 0.15)
				)
			)
		)
		(property "MPN" "LG L29K-G2J1-24-Z"
			(at 204.205 -81.875 0)
			(layer "F.Fab")
			(hide yes)
			(effects
				(font
					(size 1 1)
					(thickness 0.15)
				)
			)
		)
		(property "Manufacturer" "OSRAM"
			(at 204.205 -81.875 0)
			(layer "F.Fab")
			(hide yes)
			(effects
				(font
					(size 1 1)
					(thickness 0.15)
				)
			)
		)
		(sheetname "/FPGA banks 34-35 & CFG/")
		(sheetfile "fpga-banks-34-25-cfg.kicad_sch")
		(attr smd)
		(fp_line
			(start 0.22 -0.35)
			(end -0.22 -0.35)
			(stroke
				(width 0.15)
				(type solid)
			)
			(layer "F.SilkS")
		)
		(fp_line
			(start -1.18 -0.319)
			(end -1.18 0.321)
			(stroke
				(width 0.15)
				(type solid)
			)
			(layer "F.SilkS")
		)
		(fp_line
			(start 0.105328 0.001008)
			(end 0.24 0.001)
			(stroke
				(width 0.1)
				(type solid)
			)
			(layer "F.SilkS")
		)
		(fp_line
			(start -0.094672 0.001008)
			(end 0.105328 -0.198992)
			(stroke
				(width 0.1)
				(type solid)
			)
			(layer "F.SilkS")
		)
		(fp_line
			(start -0.094672 0.001008)
			(end -0.24 0.001008)
			(stroke
				(width 0.1)
				(type solid)
			)
			(layer "F.SilkS")
		)
		(fp_line
			(start 0.105328 0.201008)
			(end 0.105328 -0.198992)
			(stroke
				(width 0.1)
				(type solid)
			)
			(layer "F.SilkS")
		)
		(fp_line
			(start 0.105328 0.201008)
			(end -0.094672 0.001008)
			(stroke
				(width 0.1)
				(type solid)
			)
			(layer "F.SilkS")
		)
		(fp_line
			(start -0.094672 0.201008)
			(end -0.094672 -0.198992)
			(stroke
				(width 0.1)
				(type solid)
			)
			(layer "F.SilkS")
		)
		(fp_line
			(start 0.22 0.35)
			(end -0.22 0.35)
			(stroke
				(width 0.15)
				(type solid)
			)
			(layer "F.SilkS")
		)
		(fp_rect
			(start 1.25 0.65)
			(end -1.25 -0.65)
			(stroke
				(width 0.05)
				(type solid)
			)
			(fill no)
			(layer "F.CrtYd")
		)
		(fp_line
			(start 0.201 -0.202)
			(end -0.101 0)
			(stroke
				(width 0.15)
				(type solid)
			)
			(layer "F.Fab")
		)
		(fp_line
			(start -0.199 -0.202)
			(end -0.199 0.1)
			(stroke
				(width 0.15)
				(type solid)
			)
			(layer "F.Fab")
		)
		(fp_line
			(start 0.599 0)
			(end 0.201 0)
			(stroke
				(width 0.15)
				(type solid)
			)
			(layer "F.Fab")
		)
		(fp_line
			(start 0.201 0)
			(end 0.201 -0.202)
			(stroke
				(width 0.15)
				(type solid)
			)
			(layer "F.Fab")
		)
		(fp_line
			(start -0.101 0)
			(end 0.201 0.2)
			(stroke
				(width 0.15)
				(type solid)
			)
			(layer "F.Fab")
		)
		(fp_line
			(start -0.199 0)
			(end -0.597 0)
			(stroke
				(width 0.15)
				(type solid)
			)
			(layer "F.Fab")
		)
		(fp_line
			(start 0.201 0.2)
			(end 0.201 0)
			(stroke
				(width 0.15)
				(type solid)
			)
			(layer "F.Fab")
		)
		(fp_line
			(start -0.199 0.2)
			(end -0.199 0.1)
			(stroke
				(width 0.15)
				(type solid)
			)
			(layer "F.Fab")
		)
		(fp_rect
			(start 0.848 0.4)
			(end -0.85 -0.402)
			(stroke
				(width 0.15)
				(type solid)
			)
			(fill no)
			(layer "F.Fab")
		)
		(pad "1" smd roundrect
			(at -0.7 0 270)
			(size 0.8 1)
			(layers "F.Cu" "F.Mask" "F.Paste")
			(roundrect_rratio 0.2)
			(net 309 "Net-(D13-C)")
			(pinfunction "C")
			(pintype "passive")
		)
		(pad "2" smd roundrect
			(at 0.7 0 270)
			(size 0.8 1)
			(layers "F.Cu" "F.Mask" "F.Paste")
			(roundrect_rratio 0.2)
			(net 311 "Net-(D13-A)")
			(pinfunction "A")
			(pintype "passive")
		)
	)
	(footprint "antmicro-footprints:SOT-23-3"
		(layer "F.Cu")
		(at 121.375 68.13)
		(property "Reference" "Q14"
			(at 0.75 -0.655 0)
			(layer "F.SilkS")
			(effects
				(font
					(size 0.7 0.7)
					(thickness 0.15)
				)
				(justify left bottom)
			)
		)
		(property "Value" "2N7002_SOT-23-3"
			(at -1.9 2.7 0)
			(layer "F.Fab")
			(effects
				(font
					(size 0.7 0.7)
					(thickness 0.15)
				)
				(justify left bottom)
			)
		)
		(property "Datasheet" "https://www.onsemi.com/pub/Collateral/NDS7002A-D.PDF"
			(at 0 0 0)
			(layer "F.Fab")
			(hide yes)
			(effects
				(font
					(size 1.27 1.27)
					(thickness 0.15)
				)
			)
		)
		(property "Description" "Power MOSFET, N Channel, 60 V, 115 mA, 1.2 ohm, SOT-23, Surface Mount"
			(at 0 0 0)
			(layer "F.Fab")
			(hide yes)
			(effects
				(font
					(size 1.27 1.27)
					(thickness 0.15)
				)
			)
		)
		(property "Author" "Antmicro"
			(at 0 0 0)
			(layer "F.Fab")
			(hide yes)
			(effects
				(font
					(size 1 1)
					(thickness 0.15)
				)
			)
		)
		(property "License" "Apache-2.0"
			(at 0 0 0)
			(layer "F.Fab")
			(hide yes)
			(effects
				(font
					(size 1 1)
					(thickness 0.15)
				)
			)
		)
		(property "MPN" "2N7002"
			(at 0 0 0)
			(layer "F.Fab")
			(hide yes)
			(effects
				(font
					(size 1 1)
					(thickness 0.15)
				)
			)
		)
		(property "Manufacturer" "ON Semiconductor"
			(at 0 0 0)
			(layer "F.Fab")
			(hide yes)
			(effects
				(font
					(size 1 1)
					(thickness 0.15)
				)
			)
		)
		(sheetname "/FPGA banks 34-35 & CFG/")
		(sheetfile "fpga-banks-34-25-cfg.kicad_sch")
		(attr smd)
		(fp_line
			(start -1.45 -1.35)
			(end -0.85 -1.35)
			(stroke
				(width 0.15)
				(type solid)
			)
			(layer "F.SilkS")
		)
		(fp_line
			(start -0.85 -1.35)
			(end -0.7 -1.5)
			(stroke
				(width 0.15)
				(type solid)
			)
			(layer "F.SilkS")
		)
		(fp_line
			(start -0.7 1.5)
			(end -0.7 1.35)
			(stroke
				(width 0.15)
				(type solid)
			)
			(layer "F.SilkS")
		)
		(fp_line
			(start 0.7 -1.5)
			(end -0.7 -1.5)
			(stroke
				(width 0.15)
				(type solid)
			)
			(layer "F.SilkS")
		)
		(fp_line
			(start 0.7 -0.4)
			(end 0.7 -1.5)
			(stroke
				(width 0.15)
				(type solid)
			)
			(layer "F.SilkS")
		)
		(fp_line
			(start 0.7 0.4)
			(end 0.7 1.5)
			(stroke
				(width 0.15)
				(type solid)
			)
			(layer "F.SilkS")
		)
		(fp_line
			(start 0.7 1.5)
			(end -0.7 1.5)
			(stroke
				(width 0.15)
				(type solid)
			)
			(layer "F.SilkS")
		)
		(fp_line
			(start -1.75 -0.5)
			(end -1.75 -1.4)
			(stroke
				(width 0.05)
				(type solid)
			)
			(layer "F.CrtYd")
		)
		(fp_line
			(start -1.75 0.5)
			(end -0.85 0.5)
			(stroke
				(width 0.05)
				(type solid)
			)
			(layer "F.CrtYd")
		)
		(fp_line
			(start -1.75 1.4)
			(end -1.75 0.5)
			(stroke
				(width 0.05)
				(type solid)
			)
			(layer "F.CrtYd")
		)
		(fp_line
			(start -0.9 -1.6)
			(end -0.9 -1.4)
			(stroke
				(width 0.05)
				(type solid)
			)
			(layer "F.CrtYd")
		)
		(fp_line
			(start -0.9 -1.6)
			(end 0.825 -1.6)
			(stroke
				(width 0.05)
				(type solid)
			)
			(layer "F.CrtYd")
		)
		(fp_line
			(start -0.9 -1.4)
			(end -1.75 -1.4)
			(stroke
				(width 0.05)
				(type solid)
			)
			(layer "F.CrtYd")
		)
		(fp_line
			(start -0.85 -0.5)
			(end -1.75 -0.5)
			(stroke
				(width 0.05)
				(type solid)
			)
			(layer "F.CrtYd")
		)
		(fp_line
			(start -0.85 0.5)
			(end -0.85 -0.5)
			(stroke
				(width 0.05)
				(type solid)
			)
			(layer "F.CrtYd")
		)
		(fp_line
			(start -0.85 1.4)
			(end -1.75 1.4)
			(stroke
				(width 0.05)
				(type solid)
			)
			(layer "F.CrtYd")
		)
		(fp_line
			(start -0.85 1.65)
			(end -0.85 1.4)
			(stroke
				(width 0.05)
				(type solid)
			)
			(layer "F.CrtYd")
		)
		(fp_line
			(start 0.825 -1.6)
			(end 0.825 -0.45)
			(stroke
				(width 0.05)
				(type solid)
			)
			(layer "F.CrtYd")
		)
		(fp_line
			(start 0.825 -0.45)
			(end 1.75 -0.45)
			(stroke
				(width 0.05)
				(type solid)
			)
			(layer "F.CrtYd")
		)
		(fp_line
			(start 0.85 0.45)
			(end 0.85 1.65)
			(stroke
				(width 0.05)
				(type solid)
			)
			(layer "F.CrtYd")
		)
		(fp_line
			(start 0.85 1.65)
			(end -0.85 1.65)
			(stroke
				(width 0.05)
				(type solid)
			)
			(layer "F.CrtYd")
		)
		(fp_line
			(start 1.75 -0.45)
			(end 1.75 0.45)
			(stroke
				(width 0.05)
				(type solid)
			)
			(layer "F.CrtYd")
		)
		(fp_line
			(start 1.75 0.45)
			(end 0.85 0.45)
			(stroke
				(width 0.05)
				(type solid)
			)
			(layer "F.CrtYd")
		)
		(fp_line
			(start -0.712 -1.325)
			(end -0.712 1.523)
			(stroke
				(width 0.15)
				(type solid)
			)
			(layer "F.Fab")
		)
		(fp_line
			(start -0.712 1.519)
			(end 0.688 1.519)
			(stroke
				(width 0.15)
				(type solid)
			)
			(layer "F.Fab")
		)
		(fp_line
			(start -0.437 -1.526)
			(end -0.712 -1.325)
			(stroke
				(width 0.15)
				(type solid)
			)
			(layer "F.Fab")
		)
		(fp_line
			(start -0.437 -1.526)
			(end 0.688 -1.526)
			(stroke
				(width 0.15)
				(type solid)
			)
			(layer "F.Fab")
		)
		(fp_line
			(start 0.688 1.519)
			(end 0.688 -1.52)
			(stroke
				(width 0.15)
				(type solid)
			)
			(layer "F.Fab")
		)
		(pad "1" smd roundrect
			(at -1.1 -0.951)
			(size 1 0.6)
			(layers "F.Cu" "F.Mask" "F.Paste")
			(roundrect_rratio 0.15)
			(net 316 "USR_LED0")
			(pinfunction "G")
			(pintype "input")
		)
		(pad "2" smd roundrect
			(at -1.1 0.949)
			(size 1 0.6)
			(layers "F.Cu" "F.Mask" "F.Paste")
			(roundrect_rratio 0.15)
			(net 1 "GND")
			(pinfunction "S")
			(pintype "passive")
		)
		(pad "3" smd roundrect
			(at 1.1 -0.0005)
			(size 1 0.6)
			(layers "F.Cu" "F.Mask" "F.Paste")
			(roundrect_rratio 0.15)
			(net 284 "Net-(D11-C)")
			(pinfunction "D")
			(pintype "passive")
		)
	)
	(footprint "antmicro-footprints:SOT-23-3"
		(layer "F.Cu")
		(at 121.375 72.08)
		(property "Reference" "Q15"
			(at 0.75 -0.655 0)
			(layer "F.SilkS")
			(effects
				(font
					(size 0.7 0.7)
					(thickness 0.15)
				)
				(justify left bottom)
			)
		)
		(property "Value" "2N7002_SOT-23-3"
			(at -1.9 2.7 0)
			(layer "F.Fab")
			(effects
				(font
					(size 0.7 0.7)
					(thickness 0.15)
				)
				(justify left bottom)
			)
		)
		(property "Datasheet" "https://www.onsemi.com/pub/Collateral/NDS7002A-D.PDF"
			(at 0 0 0)
			(layer "F.Fab")
			(hide yes)
			(effects
				(font
					(size 1.27 1.27)
					(thickness 0.15)
				)
			)
		)
		(property "Description" "Power MOSFET, N Channel, 60 V, 115 mA, 1.2 ohm, SOT-23, Surface Mount"
			(at 0 0 0)
			(layer "F.Fab")
			(hide yes)
			(effects
				(font
					(size 1.27 1.27)
					(thickness 0.15)
				)
			)
		)
		(property "Author" "Antmicro"
			(at 0 0 0)
			(layer "F.Fab")
			(hide yes)
			(effects
				(font
					(size 1 1)
					(thickness 0.15)
				)
			)
		)
		(property "License" "Apache-2.0"
			(at 0 0 0)
			(layer "F.Fab")
			(hide yes)
			(effects
				(font
					(size 1 1)
					(thickness 0.15)
				)
			)
		)
		(property "MPN" "2N7002"
			(at 0 0 0)
			(layer "F.Fab")
			(hide yes)
			(effects
				(font
					(size 1 1)
					(thickness 0.15)
				)
			)
		)
		(property "Manufacturer" "ON Semiconductor"
			(at 0 0 0)
			(layer "F.Fab")
			(hide yes)
			(effects
				(font
					(size 1 1)
					(thickness 0.15)
				)
			)
		)
		(sheetname "/FPGA banks 34-35 & CFG/")
		(sheetfile "fpga-banks-34-25-cfg.kicad_sch")
		(attr smd)
		(fp_line
			(start -1.45 -1.35)
			(end -0.85 -1.35)
			(stroke
				(width 0.15)
				(type solid)
			)
			(layer "F.SilkS")
		)
		(fp_line
			(start -0.85 -1.35)
			(end -0.7 -1.5)
			(stroke
				(width 0.15)
				(type solid)
			)
			(layer "F.SilkS")
		)
		(fp_line
			(start -0.7 1.5)
			(end -0.7 1.35)
			(stroke
				(width 0.15)
				(type solid)
			)
			(layer "F.SilkS")
		)
		(fp_line
			(start 0.7 -1.5)
			(end -0.7 -1.5)
			(stroke
				(width 0.15)
				(type solid)
			)
			(layer "F.SilkS")
		)
		(fp_line
			(start 0.7 -0.4)
			(end 0.7 -1.5)
			(stroke
				(width 0.15)
				(type solid)
			)
			(layer "F.SilkS")
		)
		(fp_line
			(start 0.7 0.4)
			(end 0.7 1.5)
			(stroke
				(width 0.15)
				(type solid)
			)
			(layer "F.SilkS")
		)
		(fp_line
			(start 0.7 1.5)
			(end -0.7 1.5)
			(stroke
				(width 0.15)
				(type solid)
			)
			(layer "F.SilkS")
		)
		(fp_line
			(start -1.75 -0.5)
			(end -1.75 -1.4)
			(stroke
				(width 0.05)
				(type solid)
			)
			(layer "F.CrtYd")
		)
		(fp_line
			(start -1.75 0.5)
			(end -0.85 0.5)
			(stroke
				(width 0.05)
				(type solid)
			)
			(layer "F.CrtYd")
		)
		(fp_line
			(start -1.75 1.4)
			(end -1.75 0.5)
			(stroke
				(width 0.05)
				(type solid)
			)
			(layer "F.CrtYd")
		)
		(fp_line
			(start -0.9 -1.6)
			(end -0.9 -1.4)
			(stroke
				(width 0.05)
				(type solid)
			)
			(layer "F.CrtYd")
		)
		(fp_line
			(start -0.9 -1.6)
			(end 0.825 -1.6)
			(stroke
				(width 0.05)
				(type solid)
			)
			(layer "F.CrtYd")
		)
		(fp_line
			(start -0.9 -1.4)
			(end -1.75 -1.4)
			(stroke
				(width 0.05)
				(type solid)
			)
			(layer "F.CrtYd")
		)
		(fp_line
			(start -0.85 -0.5)
			(end -1.75 -0.5)
			(stroke
				(width 0.05)
				(type solid)
			)
			(layer "F.CrtYd")
		)
		(fp_line
			(start -0.85 0.5)
			(end -0.85 -0.5)
			(stroke
				(width 0.05)
				(type solid)
			)
			(layer "F.CrtYd")
		)
		(fp_line
			(start -0.85 1.4)
			(end -1.75 1.4)
			(stroke
				(width 0.05)
				(type solid)
			)
			(layer "F.CrtYd")
		)
		(fp_line
			(start -0.85 1.65)
			(end -0.85 1.4)
			(stroke
				(width 0.05)
				(type solid)
			)
			(layer "F.CrtYd")
		)
		(fp_line
			(start 0.825 -1.6)
			(end 0.825 -0.45)
			(stroke
				(width 0.05)
				(type solid)
			)
			(layer "F.CrtYd")
		)
		(fp_line
			(start 0.825 -0.45)
			(end 1.75 -0.45)
			(stroke
				(width 0.05)
				(type solid)
			)
			(layer "F.CrtYd")
		)
		(fp_line
			(start 0.85 0.45)
			(end 0.85 1.65)
			(stroke
				(width 0.05)
				(type solid)
			)
			(layer "F.CrtYd")
		)
		(fp_line
			(start 0.85 1.65)
			(end -0.85 1.65)
			(stroke
				(width 0.05)
				(type solid)
			)
			(layer "F.CrtYd")
		)
		(fp_line
			(start 1.75 -0.45)
			(end 1.75 0.45)
			(stroke
				(width 0.05)
				(type solid)
			)
			(layer "F.CrtYd")
		)
		(fp_line
			(start 1.75 0.45)
			(end 0.85 0.45)
			(stroke
				(width 0.05)
				(type solid)
			)
			(layer "F.CrtYd")
		)
		(fp_line
			(start -0.712 -1.325)
			(end -0.712 1.523)
			(stroke
				(width 0.15)
				(type solid)
			)
			(layer "F.Fab")
		)
		(fp_line
			(start -0.712 1.519)
			(end 0.688 1.519)
			(stroke
				(width 0.15)
				(type solid)
			)
			(layer "F.Fab")
		)
		(fp_line
			(start -0.437 -1.526)
			(end -0.712 -1.325)
			(stroke
				(width 0.15)
				(type solid)
			)
			(layer "F.Fab")
		)
		(fp_line
			(start -0.437 -1.526)
			(end 0.688 -1.526)
			(stroke
				(width 0.15)
				(type solid)
			)
			(layer "F.Fab")
		)
		(fp_line
			(start 0.688 1.519)
			(end 0.688 -1.52)
			(stroke
				(width 0.15)
				(type solid)
			)
			(layer "F.Fab")
		)
		(pad "1" smd roundrect
			(at -1.1 -0.951)
			(size 1 0.6)
			(layers "F.Cu" "F.Mask" "F.Paste")
			(roundrect_rratio 0.15)
			(net 317 "USR_LED1")
			(pinfunction "G")
			(pintype "input")
		)
		(pad "2" smd roundrect
			(at -1.1 0.949)
			(size 1 0.6)
			(layers "F.Cu" "F.Mask" "F.Paste")
			(roundrect_rratio 0.15)
			(net 1 "GND")
			(pinfunction "S")
			(pintype "passive")
		)
		(pad "3" smd roundrect
			(at 1.1 -0.0005)
			(size 1 0.6)
			(layers "F.Cu" "F.Mask" "F.Paste")
			(roundrect_rratio 0.15)
			(net 305 "Net-(D12-C)")
			(pinfunction "D")
			(pintype "passive")
		)
	)
	(footprint "antmicro-footprints:SOT-23-3"
		(layer "F.Cu")
		(at 121.35 76.055)
		(property "Reference" "Q16"
			(at 0.75 -0.655 0)
			(layer "F.SilkS")
			(effects
				(font
					(size 0.7 0.7)
					(thickness 0.15)
				)
				(justify left bottom)
			)
		)
		(property "Value" "2N7002_SOT-23-3"
			(at -1.9 2.7 0)
			(layer "F.Fab")
			(effects
				(font
					(size 0.7 0.7)
					(thickness 0.15)
				)
				(justify left bottom)
			)
		)
		(property "Datasheet" "https://www.onsemi.com/pub/Collateral/NDS7002A-D.PDF"
			(at 0 0 0)
			(layer "F.Fab")
			(hide yes)
			(effects
				(font
					(size 1.27 1.27)
					(thickness 0.15)
				)
			)
		)
		(property "Description" "Power MOSFET, N Channel, 60 V, 115 mA, 1.2 ohm, SOT-23, Surface Mount"
			(at 0 0 0)
			(layer "F.Fab")
			(hide yes)
			(effects
				(font
					(size 1.27 1.27)
					(thickness 0.15)
				)
			)
		)
		(property "Author" "Antmicro"
			(at 0 0 0)
			(layer "F.Fab")
			(hide yes)
			(effects
				(font
					(size 1 1)
					(thickness 0.15)
				)
			)
		)
		(property "License" "Apache-2.0"
			(at 0 0 0)
			(layer "F.Fab")
			(hide yes)
			(effects
				(font
					(size 1 1)
					(thickness 0.15)
				)
			)
		)
		(property "MPN" "2N7002"
			(at 0 0 0)
			(layer "F.Fab")
			(hide yes)
			(effects
				(font
					(size 1 1)
					(thickness 0.15)
				)
			)
		)
		(property "Manufacturer" "ON Semiconductor"
			(at 0 0 0)
			(layer "F.Fab")
			(hide yes)
			(effects
				(font
					(size 1 1)
					(thickness 0.15)
				)
			)
		)
		(sheetname "/FPGA banks 34-35 & CFG/")
		(sheetfile "fpga-banks-34-25-cfg.kicad_sch")
		(attr smd)
		(fp_line
			(start -1.45 -1.35)
			(end -0.85 -1.35)
			(stroke
				(width 0.15)
				(type solid)
			)
			(layer "F.SilkS")
		)
		(fp_line
			(start -0.85 -1.35)
			(end -0.7 -1.5)
			(stroke
				(width 0.15)
				(type solid)
			)
			(layer "F.SilkS")
		)
		(fp_line
			(start -0.7 1.5)
			(end -0.7 1.35)
			(stroke
				(width 0.15)
				(type solid)
			)
			(layer "F.SilkS")
		)
		(fp_line
			(start 0.7 -1.5)
			(end -0.7 -1.5)
			(stroke
				(width 0.15)
				(type solid)
			)
			(layer "F.SilkS")
		)
		(fp_line
			(start 0.7 -0.4)
			(end 0.7 -1.5)
			(stroke
				(width 0.15)
				(type solid)
			)
			(layer "F.SilkS")
		)
		(fp_line
			(start 0.7 0.4)
			(end 0.7 1.5)
			(stroke
				(width 0.15)
				(type solid)
			)
			(layer "F.SilkS")
		)
		(fp_line
			(start 0.7 1.5)
			(end -0.7 1.5)
			(stroke
				(width 0.15)
				(type solid)
			)
			(layer "F.SilkS")
		)
		(fp_line
			(start -1.75 -0.5)
			(end -1.75 -1.4)
			(stroke
				(width 0.05)
				(type solid)
			)
			(layer "F.CrtYd")
		)
		(fp_line
			(start -1.75 0.5)
			(end -0.85 0.5)
			(stroke
				(width 0.05)
				(type solid)
			)
			(layer "F.CrtYd")
		)
		(fp_line
			(start -1.75 1.4)
			(end -1.75 0.5)
			(stroke
				(width 0.05)
				(type solid)
			)
			(layer "F.CrtYd")
		)
		(fp_line
			(start -0.9 -1.6)
			(end -0.9 -1.4)
			(stroke
				(width 0.05)
				(type solid)
			)
			(layer "F.CrtYd")
		)
		(fp_line
			(start -0.9 -1.6)
			(end 0.825 -1.6)
			(stroke
				(width 0.05)
				(type solid)
			)
			(layer "F.CrtYd")
		)
		(fp_line
			(start -0.9 -1.4)
			(end -1.75 -1.4)
			(stroke
				(width 0.05)
				(type solid)
			)
			(layer "F.CrtYd")
		)
		(fp_line
			(start -0.85 -0.5)
			(end -1.75 -0.5)
			(stroke
				(width 0.05)
				(type solid)
			)
			(layer "F.CrtYd")
		)
		(fp_line
			(start -0.85 0.5)
			(end -0.85 -0.5)
			(stroke
				(width 0.05)
				(type solid)
			)
			(layer "F.CrtYd")
		)
		(fp_line
			(start -0.85 1.4)
			(end -1.75 1.4)
			(stroke
				(width 0.05)
				(type solid)
			)
			(layer "F.CrtYd")
		)
		(fp_line
			(start -0.85 1.65)
			(end -0.85 1.4)
			(stroke
				(width 0.05)
				(type solid)
			)
			(layer "F.CrtYd")
		)
		(fp_line
			(start 0.825 -1.6)
			(end 0.825 -0.45)
			(stroke
				(width 0.05)
				(type solid)
			)
			(layer "F.CrtYd")
		)
		(fp_line
			(start 0.825 -0.45)
			(end 1.75 -0.45)
			(stroke
				(width 0.05)
				(type solid)
			)
			(layer "F.CrtYd")
		)
		(fp_line
			(start 0.85 0.45)
			(end 0.85 1.65)
			(stroke
				(width 0.05)
				(type solid)
			)
			(layer "F.CrtYd")
		)
		(fp_line
			(start 0.85 1.65)
			(end -0.85 1.65)
			(stroke
				(width 0.05)
				(type solid)
			)
			(layer "F.CrtYd")
		)
		(fp_line
			(start 1.75 -0.45)
			(end 1.75 0.45)
			(stroke
				(width 0.05)
				(type solid)
			)
			(layer "F.CrtYd")
		)
		(fp_line
			(start 1.75 0.45)
			(end 0.85 0.45)
			(stroke
				(width 0.05)
				(type solid)
			)
			(layer "F.CrtYd")
		)
		(fp_line
			(start -0.712 -1.325)
			(end -0.712 1.523)
			(stroke
				(width 0.15)
				(type solid)
			)
			(layer "F.Fab")
		)
		(fp_line
			(start -0.712 1.519)
			(end 0.688 1.519)
			(stroke
				(width 0.15)
				(type solid)
			)
			(layer "F.Fab")
		)
		(fp_line
			(start -0.437 -1.526)
			(end -0.712 -1.325)
			(stroke
				(width 0.15)
				(type solid)
			)
			(layer "F.Fab")
		)
		(fp_line
			(start -0.437 -1.526)
			(end 0.688 -1.526)
			(stroke
				(width 0.15)
				(type solid)
			)
			(layer "F.Fab")
		)
		(fp_line
			(start 0.688 1.519)
			(end 0.688 -1.52)
			(stroke
				(width 0.15)
				(type solid)
			)
			(layer "F.Fab")
		)
		(pad "1" smd roundrect
			(at -1.1 -0.951)
			(size 1 0.6)
			(layers "F.Cu" "F.Mask" "F.Paste")
			(roundrect_rratio 0.15)
			(net 318 "USR_LED2")
			(pinfunction "G")
			(pintype "input")
		)
		(pad "2" smd roundrect
			(at -1.1 0.949)
			(size 1 0.6)
			(layers "F.Cu" "F.Mask" "F.Paste")
			(roundrect_rratio 0.15)
			(net 1 "GND")
			(pinfunction "S")
			(pintype "passive")
		)
		(pad "3" smd roundrect
			(at 1.1 -0.0005)
			(size 1 0.6)
			(layers "F.Cu" "F.Mask" "F.Paste")
			(roundrect_rratio 0.15)
			(net 309 "Net-(D13-C)")
			(pinfunction "D")
			(pintype "passive")
		)
	)
	(footprint "antmicro-footprints:R_0402_1005Metric"
		(layer "F.Cu")
		(at 138.975 63.705 -90)
		(descr "Resistor SMD 0402")
		(tags "resistor SMD 0402")
		(property "Reference" "R130"
			(at -1.105 -5.725 90)
			(layer "F.SilkS")
			(effects
				(font
					(size 0.7 0.7)
					(thickness 0.15)
				)
				(justify right bottom)
			)
		)
		(property "Value" "R_1k_0402"
			(at 0 1.4 90)
			(layer "F.Fab")
			(effects
				(font
					(size 0.7 0.7)
					(thickness 0.15)
				)
				(justify right bottom)
			)
		)
		(property "Datasheet" "https://www.bourns.com/docs/product-datasheets/cr.pdf"
			(at 0 0 270)
			(layer "F.Fab")
			(hide yes)
			(effects
				(font
					(size 1.27 1.27)
					(thickness 0.15)
				)
			)
		)
		(property "Description" "SMD Chip Resistor, 1 kohm, ± 1%, 63 mW, 0402 [1005 Metric], Thick Film, General Purpose"
			(at 0 0 270)
			(layer "F.Fab")
			(hide yes)
			(effects
				(font
					(size 1.27 1.27)
					(thickness 0.15)
				)
			)
		)
		(property "Author" "Antmicro"
			(at 75.27 202.68 0)
			(layer "F.Fab")
			(hide yes)
			(effects
				(font
					(size 1 1)
					(thickness 0.15)
				)
			)
		)
		(property "License" "Apache-2.0"
			(at 75.27 202.68 0)
			(layer "F.Fab")
			(hide yes)
			(effects
				(font
					(size 1 1)
					(thickness 0.15)
				)
			)
		)
		(property "MPN" "CR0402-FX-1001GLF"
			(at 75.27 202.68 0)
			(layer "F.Fab")
			(hide yes)
			(effects
				(font
					(size 1 1)
					(thickness 0.15)
				)
			)
		)
		(property "Manufacturer" "Bourns"
			(at 75.27 202.68 0)
			(layer "F.Fab")
			(hide yes)
			(effects
				(font
					(size 1 1)
					(thickness 0.15)
				)
			)
		)
		(property "Tolerance" "1%"
			(at 75.27 202.68 0)
			(layer "F.Fab")
			(hide yes)
			(effects
				(font
					(size 1 1)
					(thickness 0.15)
				)
			)
		)
		(property "Val" "1k"
			(at 75.27 202.68 0)
			(layer "F.Fab")
			(hide yes)
			(effects
				(font
					(size 1 1)
					(thickness 0.15)
				)
			)
		)
		(sheetname "/FPGA banks 34-35 & CFG/")
		(sheetfile "fpga-banks-34-25-cfg.kicad_sch")
		(attr smd)
		(fp_rect
			(start -0.925 -0.47)
			(end 0.925 0.47)
			(stroke
				(width 0.05)
				(type default)
			)
			(fill no)
			(layer "F.CrtYd")
		)
		(fp_rect
			(start -0.5 -0.25)
			(end 0.5 0.25)
			(stroke
				(width 0.15)
				(type solid)
			)
			(fill no)
			(layer "F.Fab")
		)
		(pad "1" smd roundrect
			(at -0.48 0 270)
			(size 0.59 0.64)
			(layers "F.Cu" "F.Mask" "F.Paste")
			(roundrect_rratio 0.25)
			(net 286 "Net-(D11-A)")
			(pintype "passive")
		)
		(pad "2" smd roundrect
			(at 0.48 0 270)
			(size 0.59 0.64)
			(layers "F.Cu" "F.Mask" "F.Paste")
			(roundrect_rratio 0.25)
			(net 2 "VCC3V3")
			(pintype "passive")
		)
	)
	(footprint "antmicro-footprints:R_0402_1005Metric"
		(layer "F.Cu")
		(at 141.025 63.705 -90)
		(descr "Resistor SMD 0402")
		(tags "resistor SMD 0402")
		(property "Reference" "R131"
			(at -1.105 -4.775 90)
			(layer "F.SilkS")
			(effects
				(font
					(size 0.7 0.7)
					(thickness 0.15)
				)
				(justify right bottom)
			)
		)
		(property "Value" "R_1k_0402"
			(at 0 1.4 90)
			(layer "F.Fab")
			(effects
				(font
					(size 0.7 0.7)
					(thickness 0.15)
				)
				(justify right bottom)
			)
		)
		(property "Datasheet" "https://www.bourns.com/docs/product-datasheets/cr.pdf"
			(at 0 0 270)
			(layer "F.Fab")
			(hide yes)
			(effects
				(font
					(size 1.27 1.27)
					(thickness 0.15)
				)
			)
		)
		(property "Description" "SMD Chip Resistor, 1 kohm, ± 1%, 63 mW, 0402 [1005 Metric], Thick Film, General Purpose"
			(at 0 0 270)
			(layer "F.Fab")
			(hide yes)
			(effects
				(font
					(size 1.27 1.27)
					(thickness 0.15)
				)
			)
		)
		(property "Author" "Antmicro"
			(at 77.32 204.73 0)
			(layer "F.Fab")
			(hide yes)
			(effects
				(font
					(size 1 1)
					(thickness 0.15)
				)
			)
		)
		(property "License" "Apache-2.0"
			(at 77.32 204.73 0)
			(layer "F.Fab")
			(hide yes)
			(effects
				(font
					(size 1 1)
					(thickness 0.15)
				)
			)
		)
		(property "MPN" "CR0402-FX-1001GLF"
			(at 77.32 204.73 0)
			(layer "F.Fab")
			(hide yes)
			(effects
				(font
					(size 1 1)
					(thickness 0.15)
				)
			)
		)
		(property "Manufacturer" "Bourns"
			(at 77.32 204.73 0)
			(layer "F.Fab")
			(hide yes)
			(effects
				(font
					(size 1 1)
					(thickness 0.15)
				)
			)
		)
		(property "Tolerance" "1%"
			(at 77.32 204.73 0)
			(layer "F.Fab")
			(hide yes)
			(effects
				(font
					(size 1 1)
					(thickness 0.15)
				)
			)
		)
		(property "Val" "1k"
			(at 77.32 204.73 0)
			(layer "F.Fab")
			(hide yes)
			(effects
				(font
					(size 1 1)
					(thickness 0.15)
				)
			)
		)
		(sheetname "/FPGA banks 34-35 & CFG/")
		(sheetfile "fpga-banks-34-25-cfg.kicad_sch")
		(attr smd)
		(fp_rect
			(start -0.925 -0.47)
			(end 0.925 0.47)
			(stroke
				(width 0.05)
				(type default)
			)
			(fill no)
			(layer "F.CrtYd")
		)
		(fp_rect
			(start -0.5 -0.25)
			(end 0.5 0.25)
			(stroke
				(width 0.15)
				(type solid)
			)
			(fill no)
			(layer "F.Fab")
		)
		(pad "1" smd roundrect
			(at -0.48 0 270)
			(size 0.59 0.64)
			(layers "F.Cu" "F.Mask" "F.Paste")
			(roundrect_rratio 0.25)
			(net 307 "Net-(D12-A)")
			(pintype "passive")
		)
		(pad "2" smd roundrect
			(at 0.48 0 270)
			(size 0.59 0.64)
			(layers "F.Cu" "F.Mask" "F.Paste")
			(roundrect_rratio 0.25)
			(net 2 "VCC3V3")
			(pintype "passive")
		)
	)
	(footprint "antmicro-footprints:R_0402_1005Metric"
		(layer "F.Cu")
		(at 143.05 63.705 -90)
		(descr "Resistor SMD 0402")
		(tags "resistor SMD 0402")
		(property "Reference" "R132"
			(at -1.105 -3.85 90)
			(layer "F.SilkS")
			(effects
				(font
					(size 0.7 0.7)
					(thickness 0.15)
				)
				(justify right bottom)
			)
		)
		(property "Value" "R_1k_0402"
			(at 0 1.4 90)
			(layer "F.Fab")
			(effects
				(font
					(size 0.7 0.7)
					(thickness 0.15)
				)
				(justify right bottom)
			)
		)
		(property "Datasheet" "https://www.bourns.com/docs/product-datasheets/cr.pdf"
			(at 0 0 270)
			(layer "F.Fab")
			(hide yes)
			(effects
				(font
					(size 1.27 1.27)
					(thickness 0.15)
				)
			)
		)
		(property "Description" "SMD Chip Resistor, 1 kohm, ± 1%, 63 mW, 0402 [1005 Metric], Thick Film, General Purpose"
			(at 0 0 270)
			(layer "F.Fab")
			(hide yes)
			(effects
				(font
					(size 1.27 1.27)
					(thickness 0.15)
				)
			)
		)
		(property "Author" "Antmicro"
			(at 79.345 206.755 0)
			(layer "F.Fab")
			(hide yes)
			(effects
				(font
					(size 1 1)
					(thickness 0.15)
				)
			)
		)
		(property "License" "Apache-2.0"
			(at 79.345 206.755 0)
			(layer "F.Fab")
			(hide yes)
			(effects
				(font
					(size 1 1)
					(thickness 0.15)
				)
			)
		)
		(property "MPN" "CR0402-FX-1001GLF"
			(at 79.345 206.755 0)
			(layer "F.Fab")
			(hide yes)
			(effects
				(font
					(size 1 1)
					(thickness 0.15)
				)
			)
		)
		(property "Manufacturer" "Bourns"
			(at 79.345 206.755 0)
			(layer "F.Fab")
			(hide yes)
			(effects
				(font
					(size 1 1)
					(thickness 0.15)
				)
			)
		)
		(property "Tolerance" "1%"
			(at 79.345 206.755 0)
			(layer "F.Fab")
			(hide yes)
			(effects
				(font
					(size 1 1)
					(thickness 0.15)
				)
			)
		)
		(property "Val" "1k"
			(at 79.345 206.755 0)
			(layer "F.Fab")
			(hide yes)
			(effects
				(font
					(size 1 1)
					(thickness 0.15)
				)
			)
		)
		(sheetname "/FPGA banks 34-35 & CFG/")
		(sheetfile "fpga-banks-34-25-cfg.kicad_sch")
		(attr smd)
		(fp_rect
			(start -0.925 -0.47)
			(end 0.925 0.47)
			(stroke
				(width 0.05)
				(type default)
			)
			(fill no)
			(layer "F.CrtYd")
		)
		(fp_rect
			(start -0.5 -0.25)
			(end 0.5 0.25)
			(stroke
				(width 0.15)
				(type solid)
			)
			(fill no)
			(layer "F.Fab")
		)
		(pad "1" smd roundrect
			(at -0.48 0 270)
			(size 0.59 0.64)
			(layers "F.Cu" "F.Mask" "F.Paste")
			(roundrect_rratio 0.25)
			(net 311 "Net-(D13-A)")
			(pintype "passive")
		)
		(pad "2" smd roundrect
			(at 0.48 0 270)
			(size 0.59 0.64)
			(layers "F.Cu" "F.Mask" "F.Paste")
			(roundrect_rratio 0.25)
			(net 2 "VCC3V3")
			(pintype "passive")
		)
	)
	(footprint "antmicro-footprints:SOIC-8_5.3x5.3x2mm_P1.27mm"
		(layer "F.Cu")
		(at 66.5 118.605 90)
		(descr "8-Pin SOIC 208-mil")
		(property "Reference" "U2"
			(at -0.0015 -3.2 90)
			(layer "F.SilkS")
			(effects
				(font
					(size 0.7 0.7)
					(thickness 0.15)
				)
				(justify left bottom)
			)
		)
		(property "Value" "W25Q32JW_SOIC-8"
			(at 0 3.8 90)
			(layer "F.Fab")
			(effects
				(font
					(size 0.7 0.7)
					(thickness 0.15)
				)
				(justify left bottom)
			)
		)
		(property "Datasheet" "https://www.mouser.com/datasheet/2/949/w25q32jw_spi_revf_09042018-1489621.pdf"
			(at 0 0 90)
			(layer "F.Fab")
			(hide yes)
			(effects
				(font
					(size 1.27 1.27)
					(thickness 0.15)
				)
			)
		)
		(property "Description" "FLASH - NOR Memory IC 32Mbit SPI - Quad I/O 133 MHz 8-SOIC"
			(at 0 0 90)
			(layer "F.Fab")
			(hide yes)
			(effects
				(font
					(size 1.27 1.27)
					(thickness 0.15)
				)
			)
		)
		(property "Author" "Antmicro"
			(at 185.105 52.105 0)
			(layer "F.Fab")
			(hide yes)
			(effects
				(font
					(size 1 1)
					(thickness 0.15)
				)
			)
		)
		(property "License" "Apache-2.0"
			(at 185.105 52.105 0)
			(layer "F.Fab")
			(hide yes)
			(effects
				(font
					(size 1 1)
					(thickness 0.15)
				)
			)
		)
		(property "MPN" "W25Q32JWSSIQ"
			(at 185.105 52.105 0)
			(layer "F.Fab")
			(hide yes)
			(effects
				(font
					(size 1 1)
					(thickness 0.15)
				)
			)
		)
		(property "Manufacturer" "Winbond"
			(at 185.105 52.105 0)
			(layer "F.Fab")
			(hide yes)
			(effects
				(font
					(size 1 1)
					(thickness 0.15)
				)
			)
		)
		(sheetname "/RoT/")
		(sheetfile "rot.kicad_sch")
		(attr smd)
		(fp_line
			(start -2.8 -2.641)
			(end -4.4 -2.641)
			(stroke
				(width 0.15)
				(type solid)
			)
			(layer "F.SilkS")
		)
		(fp_circle
			(center -4.85 -1.905)
			(end -4.8 -1.855)
			(stroke
				(width 0.15)
				(type solid)
			)
			(fill yes)
			(layer "F.SilkS")
		)
		(fp_rect
			(start 4.675 -3)
			(end -4.675 3)
			(stroke
				(width 0.05)
				(type solid)
			)
			(fill no)
			(layer "F.CrtYd")
		)
		(fp_line
			(start 2.64 -2.641)
			(end 2.64 2.64)
			(stroke
				(width 0.15)
				(type solid)
			)
			(layer "F.Fab")
		)
		(fp_line
			(start -2.641 -2.641)
			(end 2.64 -2.641)
			(stroke
				(width 0.15)
				(type solid)
			)
			(layer "F.Fab")
		)
		(fp_line
			(start -2.641 -1.371)
			(end -1.371 -2.641)
			(stroke
				(width 0.15)
				(type solid)
			)
			(layer "F.Fab")
		)
		(fp_line
			(start 2.64 2.64)
			(end -2.641 2.64)
			(stroke
				(width 0.15)
				(type solid)
			)
			(layer "F.Fab")
		)
		(fp_line
			(start -2.641 2.64)
			(end -2.641 -2.641)
			(stroke
				(width 0.15)
				(type solid)
			)
			(layer "F.Fab")
		)
		(pad "1" smd roundrect
			(at -3.601 -1.905 180)
			(size 0.65 1.65)
			(layers "F.Cu" "F.Mask" "F.Paste")
			(roundrect_rratio 0.25)
			(net 129 "QSPIB2_CS_N")
			(pinfunction "~{CS}")
			(pintype "input")
		)
		(pad "2" smd roundrect
			(at -3.601 -0.635 180)
			(size 0.65 1.65)
			(layers "F.Cu" "F.Mask" "F.Paste")
			(roundrect_rratio 0.25)
			(net 126 "QSPIB2_D1")
			(pinfunction "SO/IO1")
			(pintype "bidirectional")
		)
		(pad "3" smd roundrect
			(at -3.601 0.633 180)
			(size 0.65 1.65)
			(layers "F.Cu" "F.Mask" "F.Paste")
			(roundrect_rratio 0.25)
			(net 127 "QSPIB2_D2")
			(pinfunction "~{WP}/IO2")
			(pintype "bidirectional")
		)
		(pad "4" smd roundrect
			(at -3.601 1.904 180)
			(size 0.65 1.65)
			(layers "F.Cu" "F.Mask" "F.Paste")
			(roundrect_rratio 0.25)
			(net 1 "GND")
			(pinfunction "VSS")
			(pintype "power_in")
		)
		(pad "5" smd roundrect
			(at 3.6 1.904 180)
			(size 0.65 1.65)
			(layers "F.Cu" "F.Mask" "F.Paste")
			(roundrect_rratio 0.25)
			(net 125 "QSPIB2_D0")
			(pinfunction "SI/IO0")
			(pintype "bidirectional")
		)
		(pad "6" smd roundrect
			(at 3.6 0.633 180)
			(size 0.65 1.65)
			(layers "F.Cu" "F.Mask" "F.Paste")
			(roundrect_rratio 0.25)
			(net 119 "QSPIB_CLK")
			(pinfunction "SCLK")
			(pintype "input")
		)
		(pad "7" smd roundrect
			(at 3.6 -0.635 180)
			(size 0.65 1.65)
			(layers "F.Cu" "F.Mask" "F.Paste")
			(roundrect_rratio 0.25)
			(net 128 "QSPIB2_D3")
			(pinfunction "~{HOLD}/IO3")
			(pintype "bidirectional")
		)
		(pad "8" smd roundrect
			(at 3.6 -1.905 180)
			(size 0.65 1.65)
			(layers "F.Cu" "F.Mask" "F.Paste")
			(roundrect_rratio 0.25)
			(net 2 "VCC3V3")
			(pinfunction "VCC")
			(pintype "power_in")
		)
	)
	(footprint "antmicro-footprints:SOIC-8_5.3x5.3x2mm_P1.27mm"
		(layer "F.Cu")
		(at 66.46 128.155 90)
		(descr "8-Pin SOIC 208-mil")
		(property "Reference" "U3"
			(at -0.0015 -3.2 90)
			(layer "F.SilkS")
			(effects
				(font
					(size 0.7 0.7)
					(thickness 0.15)
				)
				(justify left bottom)
			)
		)
		(property "Value" "W25Q32JW_SOIC-8"
			(at 0 3.8 90)
			(layer "F.Fab")
			(effects
				(font
					(size 0.7 0.7)
					(thickness 0.15)
				)
				(justify left bottom)
			)
		)
		(property "Datasheet" "https://www.mouser.com/datasheet/2/949/w25q32jw_spi_revf_09042018-1489621.pdf"
			(at 0 0 90)
			(layer "F.Fab")
			(hide yes)
			(effects
				(font
					(size 1.27 1.27)
					(thickness 0.15)
				)
			)
		)
		(property "Description" "FLASH - NOR Memory IC 32Mbit SPI - Quad I/O 133 MHz 8-SOIC"
			(at 0 0 90)
			(layer "F.Fab")
			(hide yes)
			(effects
				(font
					(size 1.27 1.27)
					(thickness 0.15)
				)
			)
		)
		(property "Author" "Antmicro"
			(at 194.615 61.695 0)
			(layer "F.Fab")
			(hide yes)
			(effects
				(font
					(size 1 1)
					(thickness 0.15)
				)
			)
		)
		(property "License" "Apache-2.0"
			(at 194.615 61.695 0)
			(layer "F.Fab")
			(hide yes)
			(effects
				(font
					(size 1 1)
					(thickness 0.15)
				)
			)
		)
		(property "MPN" "W25Q32JWSSIQ"
			(at 194.615 61.695 0)
			(layer "F.Fab")
			(hide yes)
			(effects
				(font
					(size 1 1)
					(thickness 0.15)
				)
			)
		)
		(property "Manufacturer" "Winbond"
			(at 194.615 61.695 0)
			(layer "F.Fab")
			(hide yes)
			(effects
				(font
					(size 1 1)
					(thickness 0.15)
				)
			)
		)
		(sheetname "/RoT/")
		(sheetfile "rot.kicad_sch")
		(attr smd)
		(fp_line
			(start -2.8 -2.641)
			(end -4.4 -2.641)
			(stroke
				(width 0.15)
				(type solid)
			)
			(layer "F.SilkS")
		)
		(fp_circle
			(center -4.85 -1.905)
			(end -4.8 -1.855)
			(stroke
				(width 0.15)
				(type solid)
			)
			(fill yes)
			(layer "F.SilkS")
		)
		(fp_rect
			(start 4.675 -3)
			(end -4.675 3)
			(stroke
				(width 0.05)
				(type solid)
			)
			(fill no)
			(layer "F.CrtYd")
		)
		(fp_line
			(start 2.64 -2.641)
			(end 2.64 2.64)
			(stroke
				(width 0.15)
				(type solid)
			)
			(layer "F.Fab")
		)
		(fp_line
			(start -2.641 -2.641)
			(end 2.64 -2.641)
			(stroke
				(width 0.15)
				(type solid)
			)
			(layer "F.Fab")
		)
		(fp_line
			(start -2.641 -1.371)
			(end -1.371 -2.641)
			(stroke
				(width 0.15)
				(type solid)
			)
			(layer "F.Fab")
		)
		(fp_line
			(start 2.64 2.64)
			(end -2.641 2.64)
			(stroke
				(width 0.15)
				(type solid)
			)
			(layer "F.Fab")
		)
		(fp_line
			(start -2.641 2.64)
			(end -2.641 -2.641)
			(stroke
				(width 0.15)
				(type solid)
			)
			(layer "F.Fab")
		)
		(pad "1" smd roundrect
			(at -3.601 -1.905 180)
			(size 0.65 1.65)
			(layers "F.Cu" "F.Mask" "F.Paste")
			(roundrect_rratio 0.25)
			(net 124 "QSPIB1_CS_N")
			(pinfunction "~{CS}")
			(pintype "input")
		)
		(pad "2" smd roundrect
			(at -3.601 -0.635 180)
			(size 0.65 1.65)
			(layers "F.Cu" "F.Mask" "F.Paste")
			(roundrect_rratio 0.25)
			(net 121 "QSPIB1_D1")
			(pinfunction "SO/IO1")
			(pintype "bidirectional")
		)
		(pad "3" smd roundrect
			(at -3.601 0.633 180)
			(size 0.65 1.65)
			(layers "F.Cu" "F.Mask" "F.Paste")
			(roundrect_rratio 0.25)
			(net 122 "QSPIB1_D2")
			(pinfunction "~{WP}/IO2")
			(pintype "bidirectional")
		)
		(pad "4" smd roundrect
			(at -3.601 1.904 180)
			(size 0.65 1.65)
			(layers "F.Cu" "F.Mask" "F.Paste")
			(roundrect_rratio 0.25)
			(net 1 "GND")
			(pinfunction "VSS")
			(pintype "power_in")
		)
		(pad "5" smd roundrect
			(at 3.6 1.904 180)
			(size 0.65 1.65)
			(layers "F.Cu" "F.Mask" "F.Paste")
			(roundrect_rratio 0.25)
			(net 120 "QSPIB1_D0")
			(pinfunction "SI/IO0")
			(pintype "bidirectional")
		)
		(pad "6" smd roundrect
			(at 3.6 0.633 180)
			(size 0.65 1.65)
			(layers "F.Cu" "F.Mask" "F.Paste")
			(roundrect_rratio 0.25)
			(net 119 "QSPIB_CLK")
			(pinfunction "SCLK")
			(pintype "input")
		)
		(pad "7" smd roundrect
			(at 3.6 -0.635 180)
			(size 0.65 1.65)
			(layers "F.Cu" "F.Mask" "F.Paste")
			(roundrect_rratio 0.25)
			(net 123 "QSPIB1_D3")
			(pinfunction "~{HOLD}/IO3")
			(pintype "bidirectional")
		)
		(pad "8" smd roundrect
			(at 3.6 -1.905 180)
			(size 0.65 1.65)
			(layers "F.Cu" "F.Mask" "F.Paste")
			(roundrect_rratio 0.25)
			(net 2 "VCC3V3")
			(pinfunction "VCC")
			(pintype "power_in")
		)
	)
	(footprint "antmicro-footprints:C_0402_1005Metric"
		(layer "F.Cu")
		(at 105.275 162.075 180)
		(descr "Capacitor SMD 0402")
		(tags "capacitor SMD 0402")
		(property "Reference" "C42"
			(at -3.025 -0.325 0)
			(layer "F.SilkS")
			(effects
				(font
					(size 0.7 0.7)
					(thickness 0.15)
				)
				(justify right bottom)
			)
		)
		(property "Value" "C_100n_6V3_0402"
			(at 0 1.4 0)
			(layer "F.Fab")
			(effects
				(font
					(size 0.7 0.7)
					(thickness 0.15)
				)
				(justify right bottom)
			)
		)
		(property "Datasheet" "https://www.passivecomponent.com/wp-content/uploads/datasheet/WTC_MLCC_General_Purpose.pdf"
			(at 0 0 180)
			(layer "F.Fab")
			(hide yes)
			(effects
				(font
					(size 1.27 1.27)
					(thickness 0.15)
				)
			)
		)
		(property "Description" "SMT Multilayer Ceramic Capacitor, 0.1 µF, 6.3 V, 0402 [1005 Metric], ± 10%, X5R, Walsin MLCC"
			(at 0 0 180)
			(layer "F.Fab")
			(hide yes)
			(effects
				(font
					(size 1.27 1.27)
					(thickness 0.15)
				)
			)
		)
		(property "Author" "Antmicro"
			(at 210.55 324.15 0)
			(layer "F.Fab")
			(hide yes)
			(effects
				(font
					(size 1 1)
					(thickness 0.15)
				)
			)
		)
		(property "Dielectric" ""
			(at 210.55 324.15 0)
			(layer "F.Fab")
			(hide yes)
			(effects
				(font
					(size 1 1)
					(thickness 0.15)
				)
			)
		)
		(property "License" "Apache-2.0"
			(at 210.55 324.15 0)
			(layer "F.Fab")
			(hide yes)
			(effects
				(font
					(size 1 1)
					(thickness 0.15)
				)
			)
		)
		(property "MPN" "0402X104K6R3CT"
			(at 210.55 324.15 0)
			(layer "F.Fab")
			(hide yes)
			(effects
				(font
					(size 1 1)
					(thickness 0.15)
				)
			)
		)
		(property "Manufacturer" "Walsin"
			(at 210.55 324.15 0)
			(layer "F.Fab")
			(hide yes)
			(effects
				(font
					(size 1 1)
					(thickness 0.15)
				)
			)
		)
		(property "Public" "False"
			(at 210.55 324.15 0)
			(layer "F.Fab")
			(hide yes)
			(effects
				(font
					(size 1 1)
					(thickness 0.15)
				)
			)
		)
		(property "Val" "100n"
			(at 210.55 324.15 0)
			(layer "F.Fab")
			(hide yes)
			(effects
				(font
					(size 1 1)
					(thickness 0.15)
				)
			)
		)
		(property "Voltage" ""
			(at 210.55 324.15 0)
			(layer "F.Fab")
			(hide yes)
			(effects
				(font
					(size 1 1)
					(thickness 0.15)
				)
			)
		)
		(sheetname "/DDR3/")
		(sheetfile "ddr3.kicad_sch")
		(attr smd)
		(fp_rect
			(start -0.925 -0.47)
			(end 0.925 0.47)
			(stroke
				(width 0.05)
				(type default)
			)
			(fill no)
			(layer "F.CrtYd")
		)
		(fp_line
			(start 0.504 0.248)
			(end -0.494 0.248)
			(stroke
				(width 0.15)
				(type solid)
			)
			(layer "F.Fab")
		)
		(fp_line
			(start 0.504 -0.25)
			(end 0.504 0.248)
			(stroke
				(width 0.15)
				(type solid)
			)
			(layer "F.Fab")
		)
		(fp_line
			(start -0.494 0.248)
			(end -0.494 -0.25)
			(stroke
				(width 0.15)
				(type solid)
			)
			(layer "F.Fab")
		)
		(fp_line
			(start -0.494 -0.25)
			(end 0.504 -0.25)
			(stroke
				(width 0.15)
				(type solid)
			)
			(layer "F.Fab")
		)
		(pad "1" smd roundrect
			(at -0.48 0 180)
			(size 0.59 0.64)
			(layers "F.Cu" "F.Mask" "F.Paste")
			(roundrect_rratio 0.25)
			(net 1 "GND")
			(pintype "passive")
		)
		(pad "2" smd roundrect
			(at 0.48 0 180)
			(size 0.59 0.64)
			(layers "F.Cu" "F.Mask" "F.Paste")
			(roundrect_rratio 0.25)
			(net 211 "DDR3_VREF")
			(pintype "passive")
		)
	)
	(footprint "antmicro-footprints:TP_SMD_1mm"
		(layer "F.Cu")
		(at 142.575 163.275)
		(property "Reference" "TP12"
			(at 0.525 0.325 0)
			(layer "F.SilkS")
			(effects
				(font
					(size 0.7 0.7)
					(thickness 0.15)
				)
				(justify left bottom)
			)
		)
		(property "Value" "TP_1mm_SMD"
			(at 0 1.4 0)
			(layer "F.Fab")
			(effects
				(font
					(size 0.7 0.7)
					(thickness 0.15)
				)
				(justify left bottom)
			)
		)
		(property "Description" "Test point 1mm SMD"
			(at 0 0 0)
			(layer "F.Fab")
			(hide yes)
			(effects
				(font
					(size 1.27 1.27)
					(thickness 0.15)
				)
			)
		)
		(property "Author" "Antmicro"
			(at 0 0 0)
			(layer "F.Fab")
			(hide yes)
			(effects
				(font
					(size 1 1)
					(thickness 0.15)
				)
			)
		)
		(property "License" "Apache-2.0"
			(at 0 0 0)
			(layer "F.Fab")
			(hide yes)
			(effects
				(font
					(size 1 1)
					(thickness 0.15)
				)
			)
		)
		(property "MPN" ""
			(at 0 0 0)
			(layer "F.Fab")
			(hide yes)
			(effects
				(font
					(size 1 1)
					(thickness 0.15)
				)
			)
		)
		(property "Manufacturer" ""
			(at 0 0 0)
			(layer "F.Fab")
			(hide yes)
			(effects
				(font
					(size 1 1)
					(thickness 0.15)
				)
			)
		)
		(sheetname "/PCIe-connector/")
		(sheetfile "pcie-conn.kicad_sch")
		(attr exclude_from_pos_files exclude_from_bom)
		(fp_circle
			(center 0 0)
			(end 0.6 0)
			(stroke
				(width 0.05)
				(type default)
			)
			(fill no)
			(layer "F.CrtYd")
		)
		(pad "1" smd circle
			(at 0 0)
			(size 1 1)
			(layers "F.Cu" "F.Mask")
			(net 270 "Net-(J2-~{PEWAKE})")
			(pinfunction "1")
			(pintype "passive")
		)
	)
	(footprint "antmicro-footprints:R_0402_1005Metric"
		(layer "F.Cu")
		(at 73.15 87.867 180)
		(descr "Resistor SMD 0402")
		(tags "resistor SMD 0402")
		(property "Reference" "R190"
			(at -1.05 0.495 0)
			(layer "F.SilkS")
			(effects
				(font
					(size 0.7 0.7)
					(thickness 0.15)
				)
				(justify right bottom)
			)
		)
		(property "Value" "R_1k_0402"
			(at 0 1.4 0)
			(layer "F.Fab")
			(effects
				(font
					(size 0.7 0.7)
					(thickness 0.15)
				)
				(justify right bottom)
			)
		)
		(property "Datasheet" "https://www.bourns.com/docs/product-datasheets/cr.pdf"
			(at 0 0 180)
			(layer "F.Fab")
			(hide yes)
			(effects
				(font
					(size 1.27 1.27)
					(thickness 0.15)
				)
			)
		)
		(property "Description" "SMD Chip Resistor, 1 kohm, ± 1%, 63 mW, 0402 [1005 Metric], Thick Film, General Purpose"
			(at 0 0 180)
			(layer "F.Fab")
			(hide yes)
			(effects
				(font
					(size 1.27 1.27)
					(thickness 0.15)
				)
			)
		)
		(property "Author" "Antmicro"
			(at 146.3 175.734 0)
			(layer "F.Fab")
			(hide yes)
			(effects
				(font
					(size 1 1)
					(thickness 0.15)
				)
			)
		)
		(property "License" "Apache-2.0"
			(at 146.3 175.734 0)
			(layer "F.Fab")
			(hide yes)
			(effects
				(font
					(size 1 1)
					(thickness 0.15)
				)
			)
		)
		(property "MPN" "CR0402-FX-1001GLF"
			(at 146.3 175.734 0)
			(layer "F.Fab")
			(hide yes)
			(effects
				(font
					(size 1 1)
					(thickness 0.15)
				)
			)
		)
		(property "Manufacturer" "Bourns"
			(at 146.3 175.734 0)
			(layer "F.Fab")
			(hide yes)
			(effects
				(font
					(size 1 1)
					(thickness 0.15)
				)
			)
		)
		(property "Tolerance" "1%"
			(at 146.3 175.734 0)
			(layer "F.Fab")
			(hide yes)
			(effects
				(font
					(size 1 1)
					(thickness 0.15)
				)
			)
		)
		(property "Val" "1k"
			(at 146.3 175.734 0)
			(layer "F.Fab")
			(hide yes)
			(effects
				(font
					(size 1 1)
					(thickness 0.15)
				)
			)
		)
		(sheetname "/Power supply/")
		(sheetfile "power-supply.kicad_sch")
		(attr smd)
		(fp_rect
			(start -0.925 -0.47)
			(end 0.925 0.47)
			(stroke
				(width 0.05)
				(type default)
			)
			(fill no)
			(layer "F.CrtYd")
		)
		(fp_rect
			(start -0.5 -0.25)
			(end 0.5 0.25)
			(stroke
				(width 0.15)
				(type solid)
			)
			(fill no)
			(layer "F.Fab")
		)
		(pad "1" smd roundrect
			(at -0.48 0 180)
			(size 0.59 0.64)
			(layers "F.Cu" "F.Mask" "F.Paste")
			(roundrect_rratio 0.25)
			(net 340 "Net-(D14-A)")
			(pintype "passive")
		)
		(pad "2" smd roundrect
			(at 0.48 0 180)
			(size 0.59 0.64)
			(layers "F.Cu" "F.Mask" "F.Paste")
			(roundrect_rratio 0.25)
			(net 2 "VCC3V3")
			(pintype "passive")
		)
	)
	(footprint "antmicro-footprints:LED_0603_1608Metric_G"
		(layer "F.Cu")
		(at 75.719 87.857 180)
		(descr "LED SMD 0603 Green")
		(tags "LED SMD 0603 Green")
		(property "Reference" "D14"
			(at -3.381 -0.443 0)
			(layer "F.SilkS")
			(effects
				(font
					(size 0.7 0.7)
					(thickness 0.15)
				)
				(justify right bottom)
			)
		)
		(property "Value" "LED_G_0603_LG_L29K-G2J1-24-Z"
			(at 0 1.6 0)
			(layer "F.Fab")
			(effects
				(font
					(size 0.7 0.7)
					(thickness 0.15)
				)
				(justify right bottom)
			)
		)
		(property "Datasheet" "https://look.ams-osram.com/m/19ee86b3ae0ee95b/original/LG-L29K.pdf"
			(at 0 0 180)
			(layer "F.Fab")
			(hide yes)
			(effects
				(font
					(size 1.27 1.27)
					(thickness 0.15)
				)
			)
		)
		(property "Description" "LED, Green, SMD, 0603, 20 mA, 1.7 V, 570 nm"
			(at 0 0 180)
			(layer "F.Fab")
			(hide yes)
			(effects
				(font
					(size 1.27 1.27)
					(thickness 0.15)
				)
			)
		)
		(property "Author" "Antmicro"
			(at 151.438 175.714 0)
			(layer "F.Fab")
			(hide yes)
			(effects
				(font
					(size 1 1)
					(thickness 0.15)
				)
			)
		)
		(property "Color" "Green"
			(at 151.438 175.714 0)
			(layer "F.Fab")
			(hide yes)
			(effects
				(font
					(size 1 1)
					(thickness 0.15)
				)
			)
		)
		(property "License" "Apache-2.0"
			(at 151.438 175.714 0)
			(layer "F.Fab")
			(hide yes)
			(effects
				(font
					(size 1 1)
					(thickness 0.15)
				)
			)
		)
		(property "MPN" "LG L29K-G2J1-24-Z"
			(at 151.438 175.714 0)
			(layer "F.Fab")
			(hide yes)
			(effects
				(font
					(size 1 1)
					(thickness 0.15)
				)
			)
		)
		(property "Manufacturer" "OSRAM"
			(at 151.438 175.714 0)
			(layer "F.Fab")
			(hide yes)
			(effects
				(font
					(size 1 1)
					(thickness 0.15)
				)
			)
		)
		(sheetname "/Power supply/")
		(sheetfile "power-supply.kicad_sch")
		(attr smd)
		(fp_line
			(start 0.22 0.35)
			(end -0.22 0.35)
			(stroke
				(width 0.15)
				(type solid)
			)
			(layer "F.SilkS")
		)
		(fp_line
			(start 0.22 -0.35)
			(end -0.22 -0.35)
			(stroke
				(width 0.15)
				(type solid)
			)
			(layer "F.SilkS")
		)
		(fp_line
			(start 0.105328 0.201008)
			(end 0.105328 -0.198992)
			(stroke
				(width 0.1)
				(type solid)
			)
			(layer "F.SilkS")
		)
		(fp_line
			(start 0.105328 0.201008)
			(end -0.094672 0.001008)
			(stroke
				(width 0.1)
				(type solid)
			)
			(layer "F.SilkS")
		)
		(fp_line
			(start 0.105328 0.001008)
			(end 0.24 0.001)
			(stroke
				(width 0.1)
				(type solid)
			)
			(layer "F.SilkS")
		)
		(fp_line
			(start -0.094672 0.201008)
			(end -0.094672 -0.198992)
			(stroke
				(width 0.1)
				(type solid)
			)
			(layer "F.SilkS")
		)
		(fp_line
			(start -0.094672 0.001008)
			(end 0.105328 -0.198992)
			(stroke
				(width 0.1)
				(type solid)
			)
			(layer "F.SilkS")
		)
		(fp_line
			(start -0.094672 0.001008)
			(end -0.24 0.001008)
			(stroke
				(width 0.1)
				(type solid)
			)
			(layer "F.SilkS")
		)
		(fp_line
			(start -1.18 -0.319)
			(end -1.18 0.321)
			(stroke
				(width 0.15)
				(type solid)
			)
			(layer "F.SilkS")
		)
		(fp_rect
			(start 1.25 0.65)
			(end -1.25 -0.65)
			(stroke
				(width 0.05)
				(type solid)
			)
			(fill no)
			(layer "F.CrtYd")
		)
		(fp_line
			(start 0.599 0)
			(end 0.201 0)
			(stroke
				(width 0.15)
				(type solid)
			)
			(layer "F.Fab")
		)
		(fp_line
			(start 0.201 0.2)
			(end 0.201 0)
			(stroke
				(width 0.15)
				(type solid)
			)
			(layer "F.Fab")
		)
		(fp_line
			(start 0.201 0)
			(end 0.201 -0.202)
			(stroke
				(width 0.15)
				(type solid)
			)
			(layer "F.Fab")
		)
		(fp_line
			(start 0.201 -0.202)
			(end -0.101 0)
			(stroke
				(width 0.15)
				(type solid)
			)
			(layer "F.Fab")
		)
		(fp_line
			(start -0.101 0)
			(end 0.201 0.2)
			(stroke
				(width 0.15)
				(type solid)
			)
			(layer "F.Fab")
		)
		(fp_line
			(start -0.199 0.2)
			(end -0.199 0.1)
			(stroke
				(width 0.15)
				(type solid)
			)
			(layer "F.Fab")
		)
		(fp_line
			(start -0.199 0)
			(end -0.597 0)
			(stroke
				(width 0.15)
				(type solid)
			)
			(layer "F.Fab")
		)
		(fp_line
			(start -0.199 -0.202)
			(end -0.199 0.1)
			(stroke
				(width 0.15)
				(type solid)
			)
			(layer "F.Fab")
		)
		(fp_rect
			(start 0.848 0.4)
			(end -0.85 -0.402)
			(stroke
				(width 0.15)
				(type solid)
			)
			(fill no)
			(layer "F.Fab")
		)
		(pad "1" smd roundrect
			(at -0.7 0)
			(size 0.8 1)
			(layers "F.Cu" "F.Mask" "F.Paste")
			(roundrect_rratio 0.2)
			(net 313 "Net-(D14-C)")
			(pinfunction "C")
			(pintype "passive")
		)
		(pad "2" smd roundrect
			(at 0.7 0)
			(size 0.8 1)
			(layers "F.Cu" "F.Mask" "F.Paste")
			(roundrect_rratio 0.2)
			(net 340 "Net-(D14-A)")
			(pinfunction "A")
			(pintype "passive")
		)
	)
	(footprint "antmicro-footprints:C_0402_1005Metric"
		(layer "F.Cu")
		(at 68.739 97.057 90)
		(descr "Capacitor SMD 0402")
		(tags "capacitor SMD 0402")
		(property "Reference" "C64"
			(at -1.143 -0.639 90)
			(layer "F.SilkS")
			(effects
				(font
					(size 0.7 0.7)
					(thickness 0.15)
				)
				(justify left bottom)
			)
		)
		(property "Value" "C_10n_0402"
			(at 0 1.4 90)
			(layer "F.Fab")
			(effects
				(font
					(size 0.7 0.7)
					(thickness 0.15)
				)
				(justify left bottom)
			)
		)
		(property "Datasheet" "https://www.murata.com/products/productdetail?partno=GRM155R71H103KA88%23"
			(at 0 0 90)
			(layer "F.Fab")
			(hide yes)
			(effects
				(font
					(size 1.27 1.27)
					(thickness 0.15)
				)
			)
		)
		(property "Description" "SMD Multilayer Ceramic Capacitor, 10000 pF, 50 V, 0402 [1005 Metric], ± 10%, X7R, GRM Series"
			(at 0 0 90)
			(layer "F.Fab")
			(hide yes)
			(effects
				(font
					(size 1.27 1.27)
					(thickness 0.15)
				)
			)
		)
		(property "Author" "Antmicro"
			(at 165.796 28.318 0)
			(layer "F.Fab")
			(hide yes)
			(effects
				(font
					(size 1 1)
					(thickness 0.15)
				)
			)
		)
		(property "Dielectric" "X7R"
			(at 165.796 28.318 0)
			(layer "F.Fab")
			(hide yes)
			(effects
				(font
					(size 1 1)
					(thickness 0.15)
				)
			)
		)
		(property "License" "Apache-2.0"
			(at 165.796 28.318 0)
			(layer "F.Fab")
			(hide yes)
			(effects
				(font
					(size 1 1)
					(thickness 0.15)
				)
			)
		)
		(property "MPN" "GRM155R71H103KA88D"
			(at 165.796 28.318 0)
			(layer "F.Fab")
			(hide yes)
			(effects
				(font
					(size 1 1)
					(thickness 0.15)
				)
			)
		)
		(property "Manufacturer" "Murata"
			(at 165.796 28.318 0)
			(layer "F.Fab")
			(hide yes)
			(effects
				(font
					(size 1 1)
					(thickness 0.15)
				)
			)
		)
		(property "Val" "10n"
			(at 165.796 28.318 0)
			(layer "F.Fab")
			(hide yes)
			(effects
				(font
					(size 1 1)
					(thickness 0.15)
				)
			)
		)
		(property "Voltage" "50V"
			(at 165.796 28.318 0)
			(layer "F.Fab")
			(hide yes)
			(effects
				(font
					(size 1 1)
					(thickness 0.15)
				)
			)
		)
		(sheetname "/Power supply/")
		(sheetfile "power-supply.kicad_sch")
		(attr smd)
		(fp_rect
			(start -0.925 -0.47)
			(end 0.925 0.47)
			(stroke
				(width 0.05)
				(type default)
			)
			(fill no)
			(layer "F.CrtYd")
		)
		(fp_line
			(start 0.504 -0.25)
			(end 0.504 0.248)
			(stroke
				(width 0.15)
				(type solid)
			)
			(layer "F.Fab")
		)
		(fp_line
			(start -0.494 -0.25)
			(end 0.504 -0.25)
			(stroke
				(width 0.15)
				(type solid)
			)
			(layer "F.Fab")
		)
		(fp_line
			(start 0.504 0.248)
			(end -0.494 0.248)
			(stroke
				(width 0.15)
				(type solid)
			)
			(layer "F.Fab")
		)
		(fp_line
			(start -0.494 0.248)
			(end -0.494 -0.25)
			(stroke
				(width 0.15)
				(type solid)
			)
			(layer "F.Fab")
		)
		(pad "1" smd roundrect
			(at -0.48 0 90)
			(size 0.59 0.64)
			(layers "F.Cu" "F.Mask" "F.Paste")
			(roundrect_rratio 0.25)
			(net 1 "GND")
			(pintype "passive")
		)
		(pad "2" smd roundrect
			(at 0.48 0 90)
			(size 0.59 0.64)
			(layers "F.Cu" "F.Mask" "F.Paste")
			(roundrect_rratio 0.25)
			(net 103 "Net-(U9-TADJ)")
			(pintype "passive")
		)
	)
	(footprint "antmicro-footprints:C_0402_1005Metric"
		(layer "F.Cu")
		(at 107 144.6 -90)
		(descr "Capacitor SMD 0402")
		(tags "capacitor SMD 0402")
		(property "Reference" "C57"
			(at -3 -0.4 90)
			(layer "F.SilkS")
			(effects
				(font
					(size 0.7 0.7)
					(thickness 0.15)
				)
				(justify right bottom)
			)
		)
		(property "Value" "C_100n_6V3_0402"
			(at 0 1.4 90)
			(layer "F.Fab")
			(effects
				(font
					(size 0.7 0.7)
					(thickness 0.15)
				)
				(justify right bottom)
			)
		)
		(property "Datasheet" "https://www.passivecomponent.com/wp-content/uploads/datasheet/WTC_MLCC_General_Purpose.pdf"
			(at 0 0 270)
			(layer "F.Fab")
			(hide yes)
			(effects
				(font
					(size 1.27 1.27)
					(thickness 0.15)
				)
			)
		)
		(property "Description" "SMT Multilayer Ceramic Capacitor, 0.1 µF, 6.3 V, 0402 [1005 Metric], ± 10%, X5R, Walsin MLCC"
			(at 0 0 270)
			(layer "F.Fab")
			(hide yes)
			(effects
				(font
					(size 1.27 1.27)
					(thickness 0.15)
				)
			)
		)
		(property "Author" "Antmicro"
			(at -37.6 251.6 0)
			(layer "F.Fab")
			(hide yes)
			(effects
				(font
					(size 1 1)
					(thickness 0.15)
				)
			)
		)
		(property "Dielectric" ""
			(at -37.6 251.6 0)
			(layer "F.Fab")
			(hide yes)
			(effects
				(font
					(size 1 1)
					(thickness 0.15)
				)
			)
		)
		(property "License" "Apache-2.0"
			(at -37.6 251.6 0)
			(layer "F.Fab")
			(hide yes)
			(effects
				(font
					(size 1 1)
					(thickness 0.15)
				)
			)
		)
		(property "MPN" "0402X104K6R3CT"
			(at -37.6 251.6 0)
			(layer "F.Fab")
			(hide yes)
			(effects
				(font
					(size 1 1)
					(thickness 0.15)
				)
			)
		)
		(property "Manufacturer" "Walsin"
			(at -37.6 251.6 0)
			(layer "F.Fab")
			(hide yes)
			(effects
				(font
					(size 1 1)
					(thickness 0.15)
				)
			)
		)
		(property "Public" "False"
			(at -37.6 251.6 0)
			(layer "F.Fab")
			(hide yes)
			(effects
				(font
					(size 1 1)
					(thickness 0.15)
				)
			)
		)
		(property "Val" "100n"
			(at -37.6 251.6 0)
			(layer "F.Fab")
			(hide yes)
			(effects
				(font
					(size 1 1)
					(thickness 0.15)
				)
			)
		)
		(property "Voltage" ""
			(at -37.6 251.6 0)
			(layer "F.Fab")
			(hide yes)
			(effects
				(font
					(size 1 1)
					(thickness 0.15)
				)
			)
		)
		(sheetname "/DDR3/")
		(sheetfile "ddr3.kicad_sch")
		(attr smd)
		(fp_rect
			(start -0.925 -0.47)
			(end 0.925 0.47)
			(stroke
				(width 0.05)
				(type default)
			)
			(fill no)
			(layer "F.CrtYd")
		)
		(fp_line
			(start -0.494 0.248)
			(end -0.494 -0.25)
			(stroke
				(width 0.15)
				(type solid)
			)
			(layer "F.Fab")
		)
		(fp_line
			(start 0.504 0.248)
			(end -0.494 0.248)
			(stroke
				(width 0.15)
				(type solid)
			)
			(layer "F.Fab")
		)
		(fp_line
			(start -0.494 -0.25)
			(end 0.504 -0.25)
			(stroke
				(width 0.15)
				(type solid)
			)
			(layer "F.Fab")
		)
		(fp_line
			(start 0.504 -0.25)
			(end 0.504 0.248)
			(stroke
				(width 0.15)
				(type solid)
			)
			(layer "F.Fab")
		)
		(pad "1" smd roundrect
			(at -0.48 0 270)
			(size 0.59 0.64)
			(layers "F.Cu" "F.Mask" "F.Paste")
			(roundrect_rratio 0.25)
			(net 1 "GND")
			(pintype "passive")
		)
		(pad "2" smd roundrect
			(at 0.48 0 270)
			(size 0.59 0.64)
			(layers "F.Cu" "F.Mask" "F.Paste")
			(roundrect_rratio 0.25)
			(net 211 "DDR3_VREF")
			(pintype "passive")
		)
	)
	(footprint "antmicro-footprints:PinHeader_1x6_P2.54mm_Drill1.1mm"
		(layer "F.Cu")
		(at 65.126 106.675)
		(descr "WR-PHD 2.54mm Pin Header, 6 Pin")
		(property "Reference" "J7"
			(at -1.626 0.525 90)
			(layer "F.SilkS")
			(effects
				(font
					(size 0.7 0.7)
					(thickness 0.15)
				)
				(justify left bottom)
			)
		)
		(property "Value" "PinHeader_1x6_P2.54mm_Drill1.1mm"
			(at 0 2.45 0)
			(layer "F.Fab")
			(effects
				(font
					(size 0.7 0.7)
					(thickness 0.15)
				)
				(justify left bottom)
			)
		)
		(property "Datasheet" "https://www.we-online.com/components/products/datasheet/61300611121.pdf"
			(at 0 0 0)
			(layer "F.Fab")
			(hide yes)
			(effects
				(font
					(size 1.27 1.27)
					(thickness 0.15)
				)
			)
		)
		(property "Description" "Pin Header, Vertical, Board-to-Board, 2.54 mm, 1 Rows, 6 Contacts, Through Hole Straight, WR-PHD"
			(at 0 0 0)
			(layer "F.Fab")
			(hide yes)
			(effects
				(font
					(size 1.27 1.27)
					(thickness 0.15)
				)
			)
		)
		(property "Author" "Antmicro"
			(at 0 0 0)
			(layer "F.Fab")
			(hide yes)
			(effects
				(font
					(size 1 1)
					(thickness 0.15)
				)
			)
		)
		(property "License" "Apache-2.0"
			(at 0 0 0)
			(layer "F.Fab")
			(hide yes)
			(effects
				(font
					(size 1 1)
					(thickness 0.15)
				)
			)
		)
		(property "MPN" "61300611121"
			(at 0 0 0)
			(layer "F.Fab")
			(hide yes)
			(effects
				(font
					(size 1 1)
					(thickness 0.15)
				)
			)
		)
		(property "Manufacturer" "Würth Elektronik"
			(at 0 0 0)
			(layer "F.Fab")
			(hide yes)
			(effects
				(font
					(size 1 1)
					(thickness 0.15)
				)
			)
		)
		(sheetname "/Interfaces/")
		(sheetfile "interfaces.kicad_sch")
		(attr through_hole)
		(fp_line
			(start -1.272 -1.27)
			(end -1.272 1.269)
			(stroke
				(width 0.15)
				(type solid)
			)
			(layer "F.SilkS")
		)
		(fp_line
			(start -1.272 1.269)
			(end 13.968 1.269)
			(stroke
				(width 0.15)
				(type solid)
			)
			(layer "F.SilkS")
		)
		(fp_line
			(start 13.968 -1.27)
			(end -1.272 -1.27)
			(stroke
				(width 0.15)
				(type solid)
			)
			(layer "F.SilkS")
		)
		(fp_line
			(start 13.968 1.269)
			(end 13.968 -1.27)
			(stroke
				(width 0.15)
				(type solid)
			)
			(layer "F.SilkS")
		)
		(fp_line
			(start -1.5 -1.5)
			(end 14.18 -1.5)
			(stroke
				(width 0.05)
				(type solid)
			)
			(layer "F.CrtYd")
		)
		(fp_line
			(start -1.5 1.48)
			(end -1.5 -1.5)
			(stroke
				(width 0.05)
				(type solid)
			)
			(layer "F.CrtYd")
		)
		(fp_line
			(start 14.18 -1.5)
			(end 14.18 1.48)
			(stroke
				(width 0.05)
				(type solid)
			)
			(layer "F.CrtYd")
		)
		(fp_line
			(start 14.18 1.48)
			(end -1.5 1.48)
			(stroke
				(width 0.05)
				(type solid)
			)
			(layer "F.CrtYd")
		)
		(pad "1" thru_hole circle
			(at 0 0)
			(size 1.9 1.9)
			(drill 1.1)
			(layers "*.Cu" "*.Mask")
			(remove_unused_layers no)
			(net 2 "VCC3V3")
			(pintype "passive")
		)
		(pad "2" thru_hole circle
			(at 2.539 0)
			(size 1.9 1.9)
			(drill 1.1)
			(layers "*.Cu" "*.Mask")
			(remove_unused_layers no)
			(net 57 "SPI0_MOSI")
			(pintype "passive")
		)
		(pad "3" thru_hole circle
			(at 5.078 0)
			(size 1.9 1.9)
			(drill 1.1)
			(layers "*.Cu" "*.Mask")
			(remove_unused_layers no)
			(net 58 "SPI0_MISO")
			(pintype "passive")
		)
		(pad "4" thru_hole circle
			(at 7.618 0)
			(size 1.9 1.9)
			(drill 1.1)
			(layers "*.Cu" "*.Mask")
			(remove_unused_layers no)
			(net 56 "SPI0_CLK")
			(pintype "passive")
		)
		(pad "5" thru_hole circle
			(at 10.159 0)
			(size 1.9 1.9)
			(drill 1.1)
			(layers "*.Cu" "*.Mask")
			(remove_unused_layers no)
			(net 55 "SPI0_CS_N")
			(pintype "passive")
		)
		(pad "6" thru_hole circle
			(at 12.698 0)
			(size 1.9 1.9)
			(drill 1.1)
			(layers "*.Cu" "*.Mask")
			(remove_unused_layers no)
			(net 1 "GND")
			(pintype "passive")
		)
	)
	(footprint "antmicro-footprints:R_0402_1005Metric"
		(layer "F.Cu")
		(at 83.19 123.645 -90)
		(descr "Resistor SMD 0402")
		(tags "resistor SMD 0402")
		(property "Reference" "R144"
			(at 0.855 -0.31 90)
			(layer "F.SilkS")
			(effects
				(font
					(size 0.7 0.7)
					(thickness 0.15)
				)
				(justify right bottom)
			)
		)
		(property "Value" "R_0R_0402"
			(at 0 1.4 90)
			(layer "F.Fab")
			(effects
				(font
					(size 0.7 0.7)
					(thickness 0.15)
				)
				(justify right bottom)
			)
		)
		(property "Datasheet" "https://industrial.panasonic.com/cdbs/www-data/pdf/RDA0000/AOA0000C301.pdf"
			(at 0 0 270)
			(layer "F.Fab")
			(hide yes)
			(effects
				(font
					(size 1.27 1.27)
					(thickness 0.15)
				)
			)
		)
		(property "Description" "SMD Chip Resistor, Jumper, 0 ohm, 100 mW, 0402 [1005 Metric], Thick Film, General Purpose"
			(at 0 0 270)
			(layer "F.Fab")
			(hide yes)
			(effects
				(font
					(size 1.27 1.27)
					(thickness 0.15)
				)
			)
		)
		(property "Author" "Antmicro"
			(at -40.455 206.835 0)
			(layer "F.Fab")
			(hide yes)
			(effects
				(font
					(size 1 1)
					(thickness 0.15)
				)
			)
		)
		(property "Current" "1A"
			(at -40.455 206.835 0)
			(layer "F.Fab")
			(hide yes)
			(effects
				(font
					(size 1 1)
					(thickness 0.15)
				)
			)
		)
		(property "License" "Apache-2.0"
			(at -40.455 206.835 0)
			(layer "F.Fab")
			(hide yes)
			(effects
				(font
					(size 1 1)
					(thickness 0.15)
				)
			)
		)
		(property "MPN" "ERJ2GE0R00X"
			(at -40.455 206.835 0)
			(layer "F.Fab")
			(hide yes)
			(effects
				(font
					(size 1 1)
					(thickness 0.15)
				)
			)
		)
		(property "Manufacturer" "Panasonic"
			(at -40.455 206.835 0)
			(layer "F.Fab")
			(hide yes)
			(effects
				(font
					(size 1 1)
					(thickness 0.15)
				)
			)
		)
		(property "Tolerance" "~"
			(at -40.455 206.835 0)
			(layer "F.Fab")
			(hide yes)
			(effects
				(font
					(size 1 1)
					(thickness 0.15)
				)
			)
		)
		(property "Val" "0R"
			(at -40.455 206.835 0)
			(layer "F.Fab")
			(hide yes)
			(effects
				(font
					(size 1 1)
					(thickness 0.15)
				)
			)
		)
		(sheetname "/Edge connector/")
		(sheetfile "edge-connector.kicad_sch")
		(attr smd)
		(fp_rect
			(start -0.925 -0.47)
			(end 0.925 0.47)
			(stroke
				(width 0.05)
				(type default)
			)
			(fill no)
			(layer "F.CrtYd")
		)
		(fp_rect
			(start -0.5 -0.25)
			(end 0.5 0.25)
			(stroke
				(width 0.15)
				(type solid)
			)
			(fill no)
			(layer "F.Fab")
		)
		(pad "1" smd roundrect
			(at -0.48 0 270)
			(size 0.59 0.64)
			(layers "F.Cu" "F.Mask" "F.Paste")
			(roundrect_rratio 0.25)
			(net 523 "SPI0_MOSI_R")
			(pintype "passive")
		)
		(pad "2" smd roundrect
			(at 0.48 0 270)
			(size 0.59 0.64)
			(layers "F.Cu" "F.Mask" "F.Paste")
			(roundrect_rratio 0.25)
			(net 57 "SPI0_MOSI")
			(pintype "passive")
		)
	)
	(footprint "antmicro-footprints:BGA-170-100_18x14mm_Layout17x10_P1mm"
		(layer "F.Cu")
		(at 138.774 125.014 180)
		(descr "Uses depopulated JEDEC-MO-304B")
		(property "Reference" "U1"
			(at 6.974 9.314 180)
			(layer "F.SilkS")
			(effects
				(font
					(size 0.7 0.7)
					(thickness 0.15)
				)
				(justify left bottom)
			)
		)
		(property "Value" "MTFC16GAPALNA-AIT"
			(at 16.305 13.334 180)
			(layer "F.Fab")
			(effects
				(font
					(size 0.7 0.7)
					(thickness 0.15)
				)
				(justify left bottom)
			)
		)
		(property "Datasheet" "https://www.mouser.com/datasheet/2/671/micron_technology_mict-s-a0006806196-1-1759129.pdf"
			(at 0 0 180)
			(layer "F.Fab")
			(hide yes)
			(effects
				(font
					(size 1.27 1.27)
					(thickness 0.15)
				)
			)
		)
		(property "Description" "Managed NAND Flash Serial e-MMC 3.3V 128G-bit 128G/32G/16G x 1/4-bit/8-bit Automotive AEC-Q100 100-Pin TBGA Tray"
			(at 0 0 180)
			(layer "F.Fab")
			(hide yes)
			(effects
				(font
					(size 1.27 1.27)
					(thickness 0.15)
				)
			)
		)
		(property "Author" "Antmicro"
			(at 277.548 250.028 0)
			(layer "F.Fab")
			(hide yes)
			(effects
				(font
					(size 1 1)
					(thickness 0.15)
				)
			)
		)
		(property "License" "Apache-2.0"
			(at 277.548 250.028 0)
			(layer "F.Fab")
			(hide yes)
			(effects
				(font
					(size 1 1)
					(thickness 0.15)
				)
			)
		)
		(property "MPN" "MTFC16GAPALNA-AIT"
			(at 277.548 250.028 0)
			(layer "F.Fab")
			(hide yes)
			(effects
				(font
					(size 1 1)
					(thickness 0.15)
				)
			)
		)
		(property "Manufacturer" "Micron Technology"
			(at 277.548 250.028 0)
			(layer "F.Fab")
			(hide yes)
			(effects
				(font
					(size 1 1)
					(thickness 0.15)
				)
			)
		)
		(sheetname "/Interfaces/")
		(sheetfile "interfaces.kicad_sch")
		(attr smd)
		(fp_line
			(start 6.998 8.999)
			(end 6.998 -9)
			(stroke
				(width 0.15)
				(type solid)
			)
			(layer "F.SilkS")
		)
		(fp_line
			(start 6.998 8.999)
			(end -7 8.999)
			(stroke
				(width 0.15)
				(type solid)
			)
			(layer "F.SilkS")
		)
		(fp_line
			(start 6.998 -9)
			(end -7 -9)
			(stroke
				(width 0.15)
				(type solid)
			)
			(layer "F.SilkS")
		)
		(fp_line
			(start -7 8.999)
			(end -7 -9)
			(stroke
				(width 0.15)
				(type solid)
			)
			(layer "F.SilkS")
		)
		(fp_circle
			(center -7.2 -9.2)
			(end -7.15 -9.2)
			(stroke
				(width 0.15)
				(type solid)
			)
			(fill yes)
			(layer "F.SilkS")
		)
		(fp_rect
			(start -7.3 -9.3)
			(end 7.3 9.3)
			(stroke
				(width 0.05)
				(type solid)
			)
			(fill no)
			(layer "F.CrtYd")
		)
		(fp_line
			(start 6.998 8.999)
			(end 6.998 -9)
			(stroke
				(width 0.15)
				(type solid)
			)
			(layer "F.Fab")
		)
		(fp_line
			(start 6.998 8.999)
			(end -7 8.999)
			(stroke
				(width 0.15)
				(type solid)
			)
			(layer "F.Fab")
		)
		(fp_line
			(start 6.998 -9)
			(end -7 -9)
			(stroke
				(width 0.15)
				(type solid)
			)
			(layer "F.Fab")
		)
		(fp_line
			(start -7 8.999)
			(end -7 -9)
			(stroke
				(width 0.15)
				(type solid)
			)
			(layer "F.Fab")
		)
		(pad "A1" smd circle
			(at -4.5 -8 180)
			(size 0.37 0.37)
			(layers "F.Cu" "F.Mask" "F.Paste")
			(net 417 "unconnected-(U1-NC-PadA1)")
			(pinfunction "NC")
			(pintype "no_connect")
		)
		(pad "A2" smd circle
			(at -3.5 -8 180)
			(size 0.37 0.37)
			(layers "F.Cu" "F.Mask" "F.Paste")
			(net 418 "unconnected-(U1-NC-PadA2)")
			(pinfunction "NC")
			(pintype "no_connect")
		)
		(pad "A9" smd circle
			(at 3.499 -8 180)
			(size 0.37 0.37)
			(layers "F.Cu" "F.Mask" "F.Paste")
			(net 419 "unconnected-(U1-NC-PadA9)")
			(pinfunction "NC")
			(pintype "no_connect")
		)
		(pad "A10" smd circle
			(at 4.499 -8 180)
			(size 0.37 0.37)
			(layers "F.Cu" "F.Mask" "F.Paste")
			(net 426 "unconnected-(U1-NC-PadA10)")
			(pinfunction "NC")
			(pintype "no_connect")
		)
		(pad "B1" smd circle
			(at -4.5 -7 180)
			(size 0.37 0.37)
			(layers "F.Cu" "F.Mask" "F.Paste")
			(net 436 "unconnected-(U1-NC-PadB1)")
			(pinfunction "NC")
			(pintype "no_connect")
		)
		(pad "B10" smd circle
			(at 4.499 -7 180)
			(size 0.37 0.37)
			(layers "F.Cu" "F.Mask" "F.Paste")
			(net 437 "unconnected-(U1-NC-PadB10)")
			(pinfunction "NC")
			(pintype "no_connect")
		)
		(pad "D2" smd circle
			(at -3.5 -5 180)
			(size 0.37 0.37)
			(layers "F.Cu" "F.Mask" "F.Paste")
			(net 438 "unconnected-(U1-VSF1-PadD2)")
			(pinfunction "VSF1")
			(pintype "no_connect")
		)
		(pad "D3" smd circle
			(at -2.5 -5 180)
			(size 0.37 0.37)
			(layers "F.Cu" "F.Mask" "F.Paste")
			(net 439 "unconnected-(U1-VSF2-PadD3)")
			(pinfunction "VSF2")
			(pintype "no_connect")
		)
		(pad "D4" smd circle
			(at -1.5 -5 180)
			(size 0.37 0.37)
			(layers "F.Cu" "F.Mask" "F.Paste")
			(net 440 "unconnected-(U1-VSF3-PadD4)")
			(pinfunction "VSF3")
			(pintype "no_connect")
		)
		(pad "D5" smd circle
			(at -0.5 -5 180)
			(size 0.37 0.37)
			(layers "F.Cu" "F.Mask" "F.Paste")
			(net 441 "unconnected-(U1-VSF4-PadD5)")
			(pinfunction "VSF4")
			(pintype "no_connect")
		)
		(pad "D6" smd circle
			(at 0.499 -5 180)
			(size 0.37 0.37)
			(layers "F.Cu" "F.Mask" "F.Paste")
			(net 443 "unconnected-(U1-VSF5-PadD6)")
			(pinfunction "VSF5")
			(pintype "no_connect")
		)
		(pad "D7" smd circle
			(at 1.499 -5 180)
			(size 0.37 0.37)
			(layers "F.Cu" "F.Mask" "F.Paste")
			(net 456 "unconnected-(U1-VSF6-PadD7)")
			(pinfunction "VSF6")
			(pintype "no_connect")
		)
		(pad "D8" smd circle
			(at 2.499 -5 180)
			(size 0.37 0.37)
			(layers "F.Cu" "F.Mask" "F.Paste")
			(net 470 "unconnected-(U1-VSF7-PadD8)")
			(pinfunction "VSF7")
			(pintype "no_connect")
		)
		(pad "D9" smd circle
			(at 3.499 -5 180)
			(size 0.37 0.37)
			(layers "F.Cu" "F.Mask" "F.Paste")
			(net 471 "unconnected-(U1-VSF8-PadD9)")
			(pinfunction "VSF8")
			(pintype "no_connect")
		)
		(pad "E2" smd circle
			(at -3.5 -4 180)
			(size 0.37 0.37)
			(layers "F.Cu" "F.Mask" "F.Paste")
			(net 472 "unconnected-(U1-RFU-PadE2)")
			(pinfunction "RFU")
			(pintype "no_connect")
		)
		(pad "E3" smd circle
			(at -2.5 -4 180)
			(size 0.37 0.37)
			(layers "F.Cu" "F.Mask" "F.Paste")
			(net 473 "unconnected-(U1-RFU-PadE3)")
			(pinfunction "RFU")
			(pintype "no_connect")
		)
		(pad "E4" smd circle
			(at -1.5 -4 180)
			(size 0.37 0.37)
			(layers "F.Cu" "F.Mask" "F.Paste")
			(net 200 "Net-(U1-VDDIM)")
			(pinfunction "VDDIM")
			(pintype "power_in")
		)
		(pad "E5" smd circle
			(at -0.5 -4 180)
			(size 0.37 0.37)
			(layers "F.Cu" "F.Mask" "F.Paste")
			(net 480 "unconnected-(U1-RFU-PadE5)")
			(pinfunction "RFU")
			(pintype "no_connect")
		)
		(pad "E6" smd circle
			(at 0.499 -4 180)
			(size 0.37 0.37)
			(layers "F.Cu" "F.Mask" "F.Paste")
			(net 481 "unconnected-(U1-RFU-PadE6)")
			(pinfunction "RFU")
			(pintype "no_connect")
		)
		(pad "E7" smd circle
			(at 1.499 -4 180)
			(size 0.37 0.37)
			(layers "F.Cu" "F.Mask" "F.Paste")
			(net 482 "unconnected-(U1-RFU-PadE7)")
			(pinfunction "RFU")
			(pintype "no_connect")
		)
		(pad "E8" smd circle
			(at 2.499 -4 180)
			(size 0.37 0.37)
			(layers "F.Cu" "F.Mask" "F.Paste")
			(net 483 "unconnected-(U1-RFU-PadE8)")
			(pinfunction "RFU")
			(pintype "no_connect")
		)
		(pad "E9" smd circle
			(at 3.499 -4 180)
			(size 0.37 0.37)
			(layers "F.Cu" "F.Mask" "F.Paste")
			(net 484 "unconnected-(U1-RFU-PadE9)")
			(pinfunction "RFU")
			(pintype "no_connect")
		)
		(pad "F2" smd circle
			(at -3.5 -3 180)
			(size 0.37 0.37)
			(layers "F.Cu" "F.Mask" "F.Paste")
			(net 2 "VCC3V3")
			(pinfunction "VCC")
			(pintype "power_in")
		)
		(pad "F3" smd circle
			(at -2.5 -3 180)
			(size 0.37 0.37)
			(layers "F.Cu" "F.Mask" "F.Paste")
			(net 2 "VCC3V3")
			(pinfunction "VCC")
			(pintype "passive")
		)
		(pad "F4" smd circle
			(at -1.5 -3 180)
			(size 0.37 0.37)
			(layers "F.Cu" "F.Mask" "F.Paste")
			(net 2 "VCC3V3")
			(pinfunction "VCC")
			(pintype "passive")
		)
		(pad "F5" smd circle
			(at -0.5 -3 180)
			(size 0.37 0.37)
			(layers "F.Cu" "F.Mask" "F.Paste")
			(net 2 "VCC3V3")
			(pinfunction "VCC")
			(pintype "passive")
		)
		(pad "F6" smd circle
			(at 0.499 -3 180)
			(size 0.37 0.37)
			(layers "F.Cu" "F.Mask" "F.Paste")
			(net 2 "VCC3V3")
			(pinfunction "VCC")
			(pintype "passive")
		)
		(pad "F7" smd circle
			(at 1.499 -3 180)
			(size 0.37 0.37)
			(layers "F.Cu" "F.Mask" "F.Paste")
			(net 2 "VCC3V3")
			(pinfunction "VCC")
			(pintype "passive")
		)
		(pad "F8" smd circle
			(at 2.499 -3 180)
			(size 0.37 0.37)
			(layers "F.Cu" "F.Mask" "F.Paste")
			(net 2 "VCC3V3")
			(pinfunction "VCC")
			(pintype "passive")
		)
		(pad "F9" smd circle
			(at 3.499 -3 180)
			(size 0.37 0.37)
			(layers "F.Cu" "F.Mask" "F.Paste")
			(net 2 "VCC3V3")
			(pinfunction "VCC")
			(pintype "passive")
		)
		(pad "G2" smd circle
			(at -3.5 -2 180)
			(size 0.37 0.37)
			(layers "F.Cu" "F.Mask" "F.Paste")
			(net 1 "GND")
			(pinfunction "VSS")
			(pintype "power_in")
		)
		(pad "G3" smd circle
			(at -2.5 -2 180)
			(size 0.37 0.37)
			(layers "F.Cu" "F.Mask" "F.Paste")
			(net 1 "GND")
			(pinfunction "VSS")
			(pintype "passive")
		)
		(pad "G4" smd circle
			(at -1.5 -2 180)
			(size 0.37 0.37)
			(layers "F.Cu" "F.Mask" "F.Paste")
			(net 1 "GND")
			(pinfunction "VSS")
			(pintype "passive")
		)
		(pad "G5" smd circle
			(at -0.5 -2 180)
			(size 0.37 0.37)
			(layers "F.Cu" "F.Mask" "F.Paste")
			(net 1 "GND")
			(pinfunction "VSS")
			(pintype "passive")
		)
		(pad "G6" smd circle
			(at 0.499 -2 180)
			(size 0.37 0.37)
			(layers "F.Cu" "F.Mask" "F.Paste")
			(net 1 "GND")
			(pinfunction "VSS")
			(pintype "passive")
		)
		(pad "G7" smd circle
			(at 1.499 -2 180)
			(size 0.37 0.37)
			(layers "F.Cu" "F.Mask" "F.Paste")
			(net 1 "GND")
			(pinfunction "VSS")
			(pintype "passive")
		)
		(pad "G8" smd circle
			(at 2.499 -2 180)
			(size 0.37 0.37)
			(layers "F.Cu" "F.Mask" "F.Paste")
			(net 1 "GND")
			(pinfunction "VSS")
			(pintype "passive")
		)
		(pad "G9" smd circle
			(at 3.499 -2 180)
			(size 0.37 0.37)
			(layers "F.Cu" "F.Mask" "F.Paste")
			(net 1 "GND")
			(pinfunction "VSS")
			(pintype "passive")
		)
		(pad "H2" smd circle
			(at -3.5 -1 180)
			(size 0.37 0.37)
			(layers "F.Cu" "F.Mask" "F.Paste")
			(net 1 "GND")
			(pinfunction "VSSQ")
			(pintype "power_in")
		)
		(pad "H3" smd circle
			(at -2.5 -1 180)
			(size 0.37 0.37)
			(layers "F.Cu" "F.Mask" "F.Paste")
			(net 2 "VCC3V3")
			(pinfunction "VCCQ")
			(pintype "power_in")
		)
		(pad "H4" smd circle
			(at -1.5 -1 180)
			(size 0.37 0.37)
			(layers "F.Cu" "F.Mask" "F.Paste")
			(net 485 "unconnected-(U1-RFU-PadH4)")
			(pinfunction "RFU")
			(pintype "no_connect")
		)
		(pad "H5" smd circle
			(at -0.5 -1 180)
			(size 0.37 0.37)
			(layers "F.Cu" "F.Mask" "F.Paste")
			(net 486 "unconnected-(U1-RFU-PadH5)")
			(pinfunction "RFU")
			(pintype "no_connect")
		)
		(pad "H6" smd circle
			(at 0.499 -1 180)
			(size 0.37 0.37)
			(layers "F.Cu" "F.Mask" "F.Paste")
			(net 487 "unconnected-(U1-RFU-PadH6)")
			(pinfunction "RFU")
			(pintype "no_connect")
		)
		(pad "H7" smd circle
			(at 1.499 -1 180)
			(size 0.37 0.37)
			(layers "F.Cu" "F.Mask" "F.Paste")
			(net 488 "unconnected-(U1-RFU-PadH7)")
			(pinfunction "RFU")
			(pintype "no_connect")
		)
		(pad "H8" smd circle
			(at 2.499 -1 180)
			(size 0.37 0.37)
			(layers "F.Cu" "F.Mask" "F.Paste")
			(net 2 "VCC3V3")
			(pinfunction "VCCQ")
			(pintype "passive")
		)
		(pad "H9" smd circle
			(at 3.499 -1 180)
			(size 0.37 0.37)
			(layers "F.Cu" "F.Mask" "F.Paste")
			(net 1 "GND")
			(pinfunction "VSSQ")
			(pintype "passive")
		)
		(pad "J2" smd circle
			(at -3.5 0 180)
			(size 0.37 0.37)
			(layers "F.Cu" "F.Mask" "F.Paste")
			(net 491 "unconnected-(U1-RFU-PadJ2)")
			(pinfunction "RFU")
			(pintype "no_connect")
		)
		(pad "J3" smd circle
			(at -2.5 0 180)
			(size 0.37 0.37)
			(layers "F.Cu" "F.Mask" "F.Paste")
			(net 492 "unconnected-(U1-RFU-PadJ3)")
			(pinfunction "RFU")
			(pintype "no_connect")
		)
		(pad "J4" smd circle
			(at -1.5 0 180)
			(size 0.37 0.37)
			(layers "F.Cu" "F.Mask" "F.Paste")
			(net 493 "unconnected-(U1-RFU-PadJ4)")
			(pinfunction "RFU")
			(pintype "no_connect")
		)
		(pad "J5" smd circle
			(at -0.5 0 180)
			(size 0.37 0.37)
			(layers "F.Cu" "F.Mask" "F.Paste")
			(net 1 "GND")
			(pinfunction "VSS")
			(pintype "passive")
		)
		(pad "J6" smd circle
			(at 0.499 0 180)
			(size 0.37 0.37)
			(layers "F.Cu" "F.Mask" "F.Paste")
			(net 494 "unconnected-(U1-RFU-PadJ6)")
			(pinfunction "RFU")
			(pintype "no_connect")
		)
		(pad "J7" smd circle
			(at 1.499 0 180)
			(size 0.37 0.37)
			(layers "F.Cu" "F.Mask" "F.Paste")
			(net 495 "unconnected-(U1-RFU-PadJ7)")
			(pinfunction "RFU")
			(pintype "no_connect")
		)
		(pad "J8" smd circle
			(at 2.499 0 180)
			(size 0.37 0.37)
			(layers "F.Cu" "F.Mask" "F.Paste")
			(net 496 "unconnected-(U1-RFU-PadJ8)")
			(pinfunction "RFU")
			(pintype "no_connect")
		)
		(pad "J9" smd circle
			(at 3.499 0 180)
			(size 0.37 0.37)
			(layers "F.Cu" "F.Mask" "F.Paste")
			(net 497 "unconnected-(U1-RFU-PadJ9)")
			(pinfunction "RFU")
			(pintype "no_connect")
		)
		(pad "K2" smd circle
			(at -3.5 0.999 180)
			(size 0.37 0.37)
			(layers "F.Cu" "F.Mask" "F.Paste")
			(net 321 "MMC_DAT0")
			(pinfunction "DAT0")
			(pintype "bidirectional")
		)
		(pad "K3" smd circle
			(at -2.5 0.999 180)
			(size 0.37 0.37)
			(layers "F.Cu" "F.Mask" "F.Paste")
			(net 323 "MMC_DAT2")
			(pinfunction "DAT2")
			(pintype "bidirectional")
		)
		(pad "K4" smd circle
			(at -1.5 0.999 180)
			(size 0.37 0.37)
			(layers "F.Cu" "F.Mask" "F.Paste")
			(net 498 "unconnected-(U1-RFU-PadK4)")
			(pinfunction "RFU")
			(pintype "no_connect")
		)
		(pad "K5" smd circle
			(at -0.5 0.999 180)
			(size 0.37 0.37)
			(layers "F.Cu" "F.Mask" "F.Paste")
			(net 402 "Net-(U1-DS)")
			(pinfunction "DS")
			(pintype "output")
		)
		(pad "K6" smd circle
			(at 0.499 0.999 180)
			(size 0.37 0.37)
			(layers "F.Cu" "F.Mask" "F.Paste")
			(net 499 "unconnected-(U1-RFU-PadK6)")
			(pinfunction "RFU")
			(pintype "no_connect")
		)
		(pad "K7" smd circle
			(at 1.499 0.999 180)
			(size 0.37 0.37)
			(layers "F.Cu" "F.Mask" "F.Paste")
			(net 500 "unconnected-(U1-RFU-PadK7)")
			(pinfunction "RFU")
			(pintype "no_connect")
		)
		(pad "K8" smd circle
			(at 2.499 0.999 180)
			(size 0.37 0.37)
			(layers "F.Cu" "F.Mask" "F.Paste")
			(net 326 "MMC_DAT5")
			(pinfunction "DAT5")
			(pintype "bidirectional")
		)
		(pad "K9" smd circle
			(at 3.499 0.999 180)
			(size 0.37 0.37)
			(layers "F.Cu" "F.Mask" "F.Paste")
			(net 328 "MMC_DAT7")
			(pinfunction "DAT7")
			(pintype "bidirectional")
		)
		(pad "L2" smd circle
			(at -3.5 1.999 180)
			(size 0.37 0.37)
			(layers "F.Cu" "F.Mask" "F.Paste")
			(net 2 "VCC3V3")
			(pinfunction "VCCQ")
			(pintype "passive")
		)
		(pad "L3" smd circle
			(at -2.5 1.999 180)
			(size 0.37 0.37)
			(layers "F.Cu" "F.Mask" "F.Paste")
			(net 1 "GND")
			(pinfunction "VSSQ")
			(pintype "passive")
		)
		(pad "L4" smd circle
			(at -1.5 1.999 180)
			(size 0.37 0.37)
			(layers "F.Cu" "F.Mask" "F.Paste")
			(net 2 "VCC3V3")
			(pinfunction "VCCQ")
			(pintype "passive")
		)
		(pad "L5" smd circle
			(at -0.5 1.999 180)
			(size 0.37 0.37)
			(layers "F.Cu" "F.Mask" "F.Paste")
			(net 501 "unconnected-(U1-RFU-PadL5)")
			(pinfunction "RFU")
			(pintype "no_connect")
		)
		(pad "L6" smd circle
			(at 0.499 1.999 180)
			(size 0.37 0.37)
			(layers "F.Cu" "F.Mask" "F.Paste")
			(net 502 "unconnected-(U1-RFU-PadL6)")
			(pinfunction "RFU")
			(pintype "no_connect")
		)
		(pad "L7" smd circle
			(at 1.499 1.999 180)
			(size 0.37 0.37)
			(layers "F.Cu" "F.Mask" "F.Paste")
			(net 2 "VCC3V3")
			(pinfunction "VCCQ")
			(pintype "passive")
		)
		(pad "L8" smd circle
			(at 2.499 1.999 180)
			(size 0.37 0.37)
			(layers "F.Cu" "F.Mask" "F.Paste")
			(net 1 "GND")
			(pinfunction "VSSQ")
			(pintype "passive")
		)
		(pad "L9" smd circle
			(at 3.499 1.999 180)
			(size 0.37 0.37)
			(layers "F.Cu" "F.Mask" "F.Paste")
			(net 2 "VCC3V3")
			(pinfunction "VCCQ")
			(pintype "passive")
		)
		(pad "M2" smd circle
			(at -3.5 2.999 180)
			(size 0.37 0.37)
			(layers "F.Cu" "F.Mask" "F.Paste")
			(net 504 "unconnected-(U1-RFU-PadM2)")
			(pinfunction "RFU")
			(pintype "no_connect")
		)
		(pad "M3" smd circle
			(at -2.5 2.999 180)
			(size 0.37 0.37)
			(layers "F.Cu" "F.Mask" "F.Paste")
			(net 505 "unconnected-(U1-RFU-PadM3)")
			(pinfunction "RFU")
			(pintype "no_connect")
		)
		(pad "M4" smd circle
			(at -1.5 2.999 180)
			(size 0.37 0.37)
			(layers "F.Cu" "F.Mask" "F.Paste")
			(net 1 "GND")
			(pinfunction "VSSQ")
			(pintype "passive")
		)
		(pad "M5" smd circle
			(at -0.5 2.999 180)
			(size 0.37 0.37)
			(layers "F.Cu" "F.Mask" "F.Paste")
			(net 331 "MMC_RSTN")
			(pinfunction "RST_N")
			(pintype "input")
		)
		(pad "M6" smd circle
			(at 0.499 2.999 180)
			(size 0.37 0.37)
			(layers "F.Cu" "F.Mask" "F.Paste")
			(net 506 "unconnected-(U1-RFU-PadM6)")
			(pinfunction "RFU")
			(pintype "no_connect")
		)
		(pad "M7" smd circle
			(at 1.499 2.999 180)
			(size 0.37 0.37)
			(layers "F.Cu" "F.Mask" "F.Paste")
			(net 1 "GND")
			(pinfunction "VSSQ")
			(pintype "passive")
		)
		(pad "M8" smd circle
			(at 2.499 2.999 180)
			(size 0.37 0.37)
			(layers "F.Cu" "F.Mask" "F.Paste")
			(net 507 "unconnected-(U1-RFU-PadM8)")
			(pinfunction "RFU")
			(pintype "no_connect")
		)
		(pad "M9" smd circle
			(at 3.499 2.999 180)
			(size 0.37 0.37)
			(layers "F.Cu" "F.Mask" "F.Paste")
			(net 508 "unconnected-(U1-RFU-PadM9)")
			(pinfunction "RFU")
			(pintype "no_connect")
		)
		(pad "N2" smd circle
			(at -3.5 3.999 180)
			(size 0.37 0.37)
			(layers "F.Cu" "F.Mask" "F.Paste")
			(net 322 "MMC_DAT1")
			(pinfunction "DAT1")
			(pintype "bidirectional")
		)
		(pad "N3" smd circle
			(at -2.5 3.999 180)
			(size 0.37 0.37)
			(layers "F.Cu" "F.Mask" "F.Paste")
			(net 324 "MMC_DAT3")
			(pinfunction "DAT3")
			(pintype "bidirectional")
		)
		(pad "N4" smd circle
			(at -1.5 3.999 180)
			(size 0.37 0.37)
			(layers "F.Cu" "F.Mask" "F.Paste")
			(net 509 "unconnected-(U1-RFU-PadN4)")
			(pinfunction "RFU")
			(pintype "no_connect")
		)
		(pad "N5" smd circle
			(at -0.5 3.999 180)
			(size 0.37 0.37)
			(layers "F.Cu" "F.Mask" "F.Paste")
			(net 510 "unconnected-(U1-RFU-PadN5)")
			(pinfunction "RFU")
			(pintype "no_connect")
		)
		(pad "N6" smd circle
			(at 0.499 3.999 180)
			(size 0.37 0.37)
			(layers "F.Cu" "F.Mask" "F.Paste")
			(net 511 "unconnected-(U1-RFU-PadN6)")
			(pinfunction "RFU")
			(pintype "no_connect")
		)
		(pad "N7" smd circle
			(at 1.499 3.999 180)
			(size 0.37 0.37)
			(layers "F.Cu" "F.Mask" "F.Paste")
			(net 512 "unconnected-(U1-RFU-PadN7)")
			(pinfunction "RFU")
			(pintype "no_connect")
		)
		(pad "N8" smd circle
			(at 2.499 3.999 180)
			(size 0.37 0.37)
			(layers "F.Cu" "F.Mask" "F.Paste")
			(net 325 "MMC_DAT4")
			(pinfunction "DAT4")
			(pintype "bidirectional")
		)
		(pad "N9" smd circle
			(at 3.499 3.999 180)
			(size 0.37 0.37)
			(layers "F.Cu" "F.Mask" "F.Paste")
			(net 327 "MMC_DAT6")
			(pinfunction "DAT6")
			(pintype "bidirectional")
		)
		(pad "P2" smd circle
			(at -3.5 4.999 180)
			(size 0.37 0.37)
			(layers "F.Cu" "F.Mask" "F.Paste")
			(net 1 "GND")
			(pinfunction "VSSQ")
			(pintype "passive")
		)
		(pad "P3" smd circle
			(at -2.5 4.999 180)
			(size 0.37 0.37)
			(layers "F.Cu" "F.Mask" "F.Paste")
			(net 2 "VCC3V3")
			(pinfunction "VCCQ")
			(pintype "passive")
		)
		(pad "P4" smd circle
			(at -1.5 4.999 180)
			(size 0.37 0.37)
			(layers "F.Cu" "F.Mask" "F.Paste")
			(net 513 "unconnected-(U1-RFU-PadP4)")
			(pinfunction "RFU")
			(pintype "no_connect")
		)
		(pad "P5" smd circle
			(at -0.5 4.999 180)
			(size 0.37 0.37)
			(layers "F.Cu" "F.Mask" "F.Paste")
			(net 329 "MMC_CMD")
			(pinfunction "CMD")
			(pintype "bidirectional")
		)
		(pad "P6" smd circle
			(at 0.499 4.999 180)
			(size 0.37 0.37)
			(layers "F.Cu" "F.Mask" "F.Paste")
			(net 306 "Net-(U1-CLK)")
			(pinfunction "CLK")
			(pintype "input")
		)
		(pad "P7" smd circle
			(at 1.499 4.999 180)
			(size 0.37 0.37)
			(layers "F.Cu" "F.Mask" "F.Paste")
			(net 514 "unconnected-(U1-RFU-PadP7)")
			(pinfunction "RFU")
			(pintype "no_connect")
		)
		(pad "P8" smd circle
			(at 2.499 4.999 180)
			(size 0.37 0.37)
			(layers "F.Cu" "F.Mask" "F.Paste")
			(net 2 "VCC3V3")
			(pinfunction "VCCQ")
			(pintype "passive")
		)
		(pad "P9" smd circle
			(at 3.499 4.999 180)
			(size 0.37 0.37)
			(layers "F.Cu" "F.Mask" "F.Paste")
			(net 1 "GND")
			(pinfunction "VSSQ")
			(pintype "passive")
		)
		(pad "T1" smd circle
			(at -4.5 6.998 180)
			(size 0.37 0.37)
			(layers "F.Cu" "F.Mask" "F.Paste")
			(net 515 "unconnected-(U1-NC-PadT1)")
			(pinfunction "NC")
			(pintype "no_connect")
		)
		(pad "T10" smd circle
			(at 4.499 6.998 180)
			(size 0.37 0.37)
			(layers "F.Cu" "F.Mask" "F.Paste")
			(net 516 "unconnected-(U1-NC-PadT10)")
			(pinfunction "NC")
			(pintype "no_connect")
		)
		(pad "U1" smd circle
			(at -4.5 7.998 180)
			(size 0.37 0.37)
			(layers "F.Cu" "F.Mask" "F.Paste")
			(net 517 "unconnected-(U1-NC-PadU1)")
			(pinfunction "NC")
			(pintype "no_connect")
		)
		(pad "U2" smd circle
			(at -3.5 7.998 180)
			(size 0.37 0.37)
			(layers "F.Cu" "F.Mask" "F.Paste")
			(net 518 "unconnected-(U1-NC-PadU2)")
			(pinfunction "NC")
			(pintype "no_connect")
		)
		(pad "U9" smd circle
			(at 3.499 7.998 180)
			(size 0.37 0.37)
			(layers "F.Cu" "F.Mask" "F.Paste")
			(net 519 "unconnected-(U1-NC-PadU9)")
			(pinfunction "NC")
			(pintype "no_connect")
		)
		(pad "U10" smd circle
			(at 4.499 7.998 180)
			(size 0.37 0.37)
			(layers "F.Cu" "F.Mask" "F.Paste")
			(net 520 "unconnected-(U1-NC-PadU10)")
			(pinfunction "NC")
			(pintype "no_connect")
		)
	)
	(footprint "antmicro-footprints:R_0402_1005Metric"
		(layer "F.Cu")
		(at 76.74 162.06 -90)
		(descr "Resistor SMD 0402")
		(tags "resistor SMD 0402")
		(property "Reference" "R47"
			(at -2.16 -8.36 90)
			(layer "F.SilkS")
			(effects
				(font
					(size 0.7 0.7)
					(thickness 0.15)
				)
				(justify right bottom)
			)
		)
		(property "Value" "R_357k_0402"
			(at 0 1.4 90)
			(layer "F.Fab")
			(effects
				(font
					(size 0.7 0.7)
					(thickness 0.15)
				)
				(justify right bottom)
			)
		)
		(property "Datasheet" "https://www.bourns.com/docs/product-datasheets/cr.pdf"
			(at 0 0 270)
			(layer "F.Fab")
			(hide yes)
			(effects
				(font
					(size 1.27 1.27)
					(thickness 0.15)
				)
			)
		)
		(property "Description" "SMD Chip Resistor"
			(at 0 0 270)
			(layer "F.Fab")
			(hide yes)
			(effects
				(font
					(size 1.27 1.27)
					(thickness 0.15)
				)
			)
		)
		(property "Author" "Antmicro"
			(at -85.32 238.8 0)
			(layer "F.Fab")
			(hide yes)
			(effects
				(font
					(size 1 1)
					(thickness 0.15)
				)
			)
		)
		(property "License" "Apache-2.0"
			(at -85.32 238.8 0)
			(layer "F.Fab")
			(hide yes)
			(effects
				(font
					(size 1 1)
					(thickness 0.15)
				)
			)
		)
		(property "MPN" "CR0402-FX-3573GLF"
			(at -85.32 238.8 0)
			(layer "F.Fab")
			(hide yes)
			(effects
				(font
					(size 1 1)
					(thickness 0.15)
				)
			)
		)
		(property "Manufacturer" "Bourns"
			(at -85.32 238.8 0)
			(layer "F.Fab")
			(hide yes)
			(effects
				(font
					(size 1 1)
					(thickness 0.15)
				)
			)
		)
		(property "Tolerance" "1%"
			(at -85.32 238.8 0)
			(layer "F.Fab")
			(hide yes)
			(effects
				(font
					(size 1 1)
					(thickness 0.15)
				)
			)
		)
		(property "Val" "357k"
			(at -85.32 238.8 0)
			(layer "F.Fab")
			(hide yes)
			(effects
				(font
					(size 1 1)
					(thickness 0.15)
				)
			)
		)
		(sheetname "/Interfaces/")
		(sheetfile "interfaces.kicad_sch")
		(attr smd)
		(fp_rect
			(start -0.925 -0.47)
			(end 0.925 0.47)
			(stroke
				(width 0.05)
				(type default)
			)
			(fill no)
			(layer "F.CrtYd")
		)
		(fp_rect
			(start -0.5 -0.25)
			(end 0.5 0.25)
			(stroke
				(width 0.15)
				(type solid)
			)
			(fill no)
			(layer "F.Fab")
		)
		(pad "1" smd roundrect
			(at -0.48 0 270)
			(size 0.59 0.64)
			(layers "F.Cu" "F.Mask" "F.Paste")
			(roundrect_rratio 0.25)
			(net 2 "VCC3V3")
			(pintype "passive")
		)
		(pad "2" smd roundrect
			(at 0.48 0 270)
			(size 0.59 0.64)
			(layers "F.Cu" "F.Mask" "F.Paste")
			(roundrect_rratio 0.25)
			(net 170 "I3C[1]_SDA_3V3")
			(pintype "passive")
		)
	)
	(footprint "antmicro-footprints:R_0402_1005Metric"
		(layer "F.Cu")
		(at 105.275 160.275)
		(descr "Resistor SMD 0402")
		(tags "resistor SMD 0402")
		(property "Reference" "R113"
			(at 0.725 0.425 0)
			(layer "F.SilkS")
			(effects
				(font
					(size 0.7 0.7)
					(thickness 0.15)
				)
				(justify left bottom)
			)
		)
		(property "Value" "R_10k_0402"
			(at 0 1.4 0)
			(layer "F.Fab")
			(effects
				(font
					(size 0.7 0.7)
					(thickness 0.15)
				)
				(justify left bottom)
			)
		)
		(property "Datasheet" "https://www.bourns.com/docs/product-datasheets/cr.pdf"
			(at 0 0 0)
			(layer "F.Fab")
			(hide yes)
			(effects
				(font
					(size 1.27 1.27)
					(thickness 0.15)
				)
			)
		)
		(property "Description" "SMD Chip Resistor, 10 kohm, ± 1%, 62.5 mW, 0402 [1005 Metric], Thick Film, General Purpose"
			(at 0 0 0)
			(layer "F.Fab")
			(hide yes)
			(effects
				(font
					(size 1.27 1.27)
					(thickness 0.15)
				)
			)
		)
		(property "Author" "Antmicro"
			(at 0 0 0)
			(layer "F.Fab")
			(hide yes)
			(effects
				(font
					(size 1 1)
					(thickness 0.15)
				)
			)
		)
		(property "License" "Apache-2.0"
			(at 0 0 0)
			(layer "F.Fab")
			(hide yes)
			(effects
				(font
					(size 1 1)
					(thickness 0.15)
				)
			)
		)
		(property "MPN" "CR0402-FX-1002GLF"
			(at 0 0 0)
			(layer "F.Fab")
			(hide yes)
			(effects
				(font
					(size 1 1)
					(thickness 0.15)
				)
			)
		)
		(property "Manufacturer" "Bourns"
			(at 0 0 0)
			(layer "F.Fab")
			(hide yes)
			(effects
				(font
					(size 1 1)
					(thickness 0.15)
				)
			)
		)
		(property "Tolerance" "1%"
			(at 0 0 0)
			(layer "F.Fab")
			(hide yes)
			(effects
				(font
					(size 1 1)
					(thickness 0.15)
				)
			)
		)
		(property "Val" "10k"
			(at 0 0 0)
			(layer "F.Fab")
			(hide yes)
			(effects
				(font
					(size 1 1)
					(thickness 0.15)
				)
			)
		)
		(sheetname "/DDR3/")
		(sheetfile "ddr3.kicad_sch")
		(attr smd)
		(fp_rect
			(start -0.925 -0.47)
			(end 0.925 0.47)
			(stroke
				(width 0.05)
				(type default)
			)
			(fill no)
			(layer "F.CrtYd")
		)
		(fp_rect
			(start -0.5 -0.25)
			(end 0.5 0.25)
			(stroke
				(width 0.15)
				(type solid)
			)
			(fill no)
			(layer "F.Fab")
		)
		(pad "1" smd roundrect
			(at -0.48 0)
			(size 0.59 0.64)
			(layers "F.Cu" "F.Mask" "F.Paste")
			(roundrect_rratio 0.25)
			(net 341 "Net-(U8-EN)")
			(pintype "passive")
		)
		(pad "2" smd roundrect
			(at 0.48 0)
			(size 0.59 0.64)
			(layers "F.Cu" "F.Mask" "F.Paste")
			(roundrect_rratio 0.25)
			(net 2 "VCC3V3")
			(pintype "passive")
		)
	)
	(footprint "antmicro-footprints:C_0402_1005Metric"
		(layer "F.Cu")
		(at 124.005 168.181 -90)
		(descr "Capacitor SMD 0402")
		(tags "capacitor SMD 0402")
		(property "Reference" "C29"
			(at 0.819 -0.404 90)
			(layer "F.SilkS")
			(effects
				(font
					(size 0.7 0.7)
					(thickness 0.15)
				)
				(justify right bottom)
			)
		)
		(property "Value" "C_100n_6V3_0402"
			(at 0 1.4 90)
			(layer "F.Fab")
			(effects
				(font
					(size 0.7 0.7)
					(thickness 0.15)
				)
				(justify right bottom)
			)
		)
		(property "Datasheet" "https://www.passivecomponent.com/wp-content/uploads/datasheet/WTC_MLCC_General_Purpose.pdf"
			(at 0 0 270)
			(layer "F.Fab")
			(hide yes)
			(effects
				(font
					(size 1.27 1.27)
					(thickness 0.15)
				)
			)
		)
		(property "Description" "SMT Multilayer Ceramic Capacitor, 0.1 µF, 6.3 V, 0402 [1005 Metric], ± 10%, X5R, Walsin MLCC"
			(at 0 0 270)
			(layer "F.Fab")
			(hide yes)
			(effects
				(font
					(size 1.27 1.27)
					(thickness 0.15)
				)
			)
		)
		(property "Author" "Antmicro"
			(at -44.176 292.186 0)
			(layer "F.Fab")
			(hide yes)
			(effects
				(font
					(size 1 1)
					(thickness 0.15)
				)
			)
		)
		(property "Dielectric" ""
			(at -44.176 292.186 0)
			(layer "F.Fab")
			(hide yes)
			(effects
				(font
					(size 1 1)
					(thickness 0.15)
				)
			)
		)
		(property "License" "Apache-2.0"
			(at -44.176 292.186 0)
			(layer "F.Fab")
			(hide yes)
			(effects
				(font
					(size 1 1)
					(thickness 0.15)
				)
			)
		)
		(property "MPN" "0402X104K6R3CT"
			(at -44.176 292.186 0)
			(layer "F.Fab")
			(hide yes)
			(effects
				(font
					(size 1 1)
					(thickness 0.15)
				)
			)
		)
		(property "Manufacturer" "Walsin"
			(at -44.176 292.186 0)
			(layer "F.Fab")
			(hide yes)
			(effects
				(font
					(size 1 1)
					(thickness 0.15)
				)
			)
		)
		(property "Public" "False"
			(at -44.176 292.186 0)
			(layer "F.Fab")
			(hide yes)
			(effects
				(font
					(size 1 1)
					(thickness 0.15)
				)
			)
		)
		(property "Val" "100n"
			(at -44.176 292.186 0)
			(layer "F.Fab")
			(hide yes)
			(effects
				(font
					(size 1 1)
					(thickness 0.15)
				)
			)
		)
		(property "Voltage" ""
			(at -44.176 292.186 0)
			(layer "F.Fab")
			(hide yes)
			(effects
				(font
					(size 1 1)
					(thickness 0.15)
				)
			)
		)
		(sheetname "/PCIe-connector/")
		(sheetfile "pcie-conn.kicad_sch")
		(attr smd)
		(fp_rect
			(start -0.925 -0.47)
			(end 0.925 0.47)
			(stroke
				(width 0.05)
				(type default)
			)
			(fill no)
			(layer "F.CrtYd")
		)
		(fp_line
			(start -0.494 0.248)
			(end -0.494 -0.25)
			(stroke
				(width 0.15)
				(type solid)
			)
			(layer "F.Fab")
		)
		(fp_line
			(start 0.504 0.248)
			(end -0.494 0.248)
			(stroke
				(width 0.15)
				(type solid)
			)
			(layer "F.Fab")
		)
		(fp_line
			(start -0.494 -0.25)
			(end 0.504 -0.25)
			(stroke
				(width 0.15)
				(type solid)
			)
			(layer "F.Fab")
		)
		(fp_line
			(start 0.504 -0.25)
			(end 0.504 0.248)
			(stroke
				(width 0.15)
				(type solid)
			)
			(layer "F.Fab")
		)
		(pad "1" smd roundrect
			(at -0.48 0 270)
			(size 0.59 0.64)
			(layers "F.Cu" "F.Mask" "F.Paste")
			(roundrect_rratio 0.25)
			(net 371 "/PCIe-connector/PCIE_HPM_TX0_C_N")
			(pintype "passive")
		)
		(pad "2" smd roundrect
			(at 0.48 0 270)
			(size 0.59 0.64)
			(layers "F.Cu" "F.Mask" "F.Paste")
			(roundrect_rratio 0.25)
			(net 353 "PCIE_HPM_TX[0]_N")
			(pintype "passive")
		)
	)
	(footprint "antmicro-footprints:C_0402_1005Metric"
		(layer "F.Cu")
		(at 122.995 168.181 -90)
		(descr "Capacitor SMD 0402")
		(tags "capacitor SMD 0402")
		(property "Reference" "C27"
			(at 0.819 -0.404 90)
			(layer "F.SilkS")
			(effects
				(font
					(size 0.7 0.7)
					(thickness 0.15)
				)
				(justify right bottom)
			)
		)
		(property "Value" "C_100n_6V3_0402"
			(at 0 1.4 90)
			(layer "F.Fab")
			(effects
				(font
					(size 0.7 0.7)
					(thickness 0.15)
				)
				(justify right bottom)
			)
		)
		(property "Datasheet" "https://www.passivecomponent.com/wp-content/uploads/datasheet/WTC_MLCC_General_Purpose.pdf"
			(at 0 0 270)
			(layer "F.Fab")
			(hide yes)
			(effects
				(font
					(size 1.27 1.27)
					(thickness 0.15)
				)
			)
		)
		(property "Description" "SMT Multilayer Ceramic Capacitor, 0.1 µF, 6.3 V, 0402 [1005 Metric], ± 10%, X5R, Walsin MLCC"
			(at 0 0 270)
			(layer "F.Fab")
			(hide yes)
			(effects
				(font
					(size 1.27 1.27)
					(thickness 0.15)
				)
			)
		)
		(property "Author" "Antmicro"
			(at -45.186 291.176 0)
			(layer "F.Fab")
			(hide yes)
			(effects
				(font
					(size 1 1)
					(thickness 0.15)
				)
			)
		)
		(property "Dielectric" ""
			(at -45.186 291.176 0)
			(layer "F.Fab")
			(hide yes)
			(effects
				(font
					(size 1 1)
					(thickness 0.15)
				)
			)
		)
		(property "License" "Apache-2.0"
			(at -45.186 291.176 0)
			(layer "F.Fab")
			(hide yes)
			(effects
				(font
					(size 1 1)
					(thickness 0.15)
				)
			)
		)
		(property "MPN" "0402X104K6R3CT"
			(at -45.186 291.176 0)
			(layer "F.Fab")
			(hide yes)
			(effects
				(font
					(size 1 1)
					(thickness 0.15)
				)
			)
		)
		(property "Manufacturer" "Walsin"
			(at -45.186 291.176 0)
			(layer "F.Fab")
			(hide yes)
			(effects
				(font
					(size 1 1)
					(thickness 0.15)
				)
			)
		)
		(property "Public" "False"
			(at -45.186 291.176 0)
			(layer "F.Fab")
			(hide yes)
			(effects
				(font
					(size 1 1)
					(thickness 0.15)
				)
			)
		)
		(property "Val" "100n"
			(at -45.186 291.176 0)
			(layer "F.Fab")
			(hide yes)
			(effects
				(font
					(size 1 1)
					(thickness 0.15)
				)
			)
		)
		(property "Voltage" ""
			(at -45.186 291.176 0)
			(layer "F.Fab")
			(hide yes)
			(effects
				(font
					(size 1 1)
					(thickness 0.15)
				)
			)
		)
		(sheetname "/PCIe-connector/")
		(sheetfile "pcie-conn.kicad_sch")
		(attr smd)
		(fp_rect
			(start -0.925 -0.47)
			(end 0.925 0.47)
			(stroke
				(width 0.05)
				(type default)
			)
			(fill no)
			(layer "F.CrtYd")
		)
		(fp_line
			(start -0.494 0.248)
			(end -0.494 -0.25)
			(stroke
				(width 0.15)
				(type solid)
			)
			(layer "F.Fab")
		)
		(fp_line
			(start 0.504 0.248)
			(end -0.494 0.248)
			(stroke
				(width 0.15)
				(type solid)
			)
			(layer "F.Fab")
		)
		(fp_line
			(start -0.494 -0.25)
			(end 0.504 -0.25)
			(stroke
				(width 0.15)
				(type solid)
			)
			(layer "F.Fab")
		)
		(fp_line
			(start 0.504 -0.25)
			(end 0.504 0.248)
			(stroke
				(width 0.15)
				(type solid)
			)
			(layer "F.Fab")
		)
		(pad "1" smd roundrect
			(at -0.48 0 270)
			(size 0.59 0.64)
			(layers "F.Cu" "F.Mask" "F.Paste")
			(roundrect_rratio 0.25)
			(net 369 "/PCIe-connector/PCIE_HPM_TX0_C_P")
			(pintype "passive")
		)
		(pad "2" smd roundrect
			(at 0.48 0 270)
			(size 0.59 0.64)
			(layers "F.Cu" "F.Mask" "F.Paste")
			(roundrect_rratio 0.25)
			(net 351 "PCIE_HPM_TX[0]_P")
			(pintype "passive")
		)
	)
	(footprint "antmicro-footprints:C_0402_1005Metric"
		(layer "F.Cu")
		(at 85.8 78.025 180)
		(descr "Capacitor SMD 0402")
		(tags "capacitor SMD 0402")
		(property "Reference" "C89"
			(at -5.705 -0.675 0)
			(layer "F.SilkS")
			(effects
				(font
					(size 0.7 0.7)
					(thickness 0.15)
				)
				(justify right bottom)
			)
		)
		(property "Value" "C_10u_0402"
			(at 0 1.4 0)
			(layer "F.Fab")
			(effects
				(font
					(size 0.7 0.7)
					(thickness 0.15)
				)
				(justify right bottom)
			)
		)
		(property "Datasheet" "https://www.yageo.com/en/Chart/Download/pdf/CC0402MRX5R5BB106"
			(at 0 0 180)
			(layer "F.Fab")
			(hide yes)
			(effects
				(font
					(size 1.27 1.27)
					(thickness 0.15)
				)
			)
		)
		(property "Description" "SMD Multilayer Ceramic Capacitor, 10 µF, 6.3 V, 0402 [1005 Metric], ± 20%, X5R, CC Series"
			(at 0 0 180)
			(layer "F.Fab")
			(hide yes)
			(effects
				(font
					(size 1.27 1.27)
					(thickness 0.15)
				)
			)
		)
		(property "Author" "Antmicro"
			(at 171.6 156.05 0)
			(layer "F.Fab")
			(hide yes)
			(effects
				(font
					(size 1 1)
					(thickness 0.15)
				)
			)
		)
		(property "Dielectric" ""
			(at 171.6 156.05 0)
			(layer "F.Fab")
			(hide yes)
			(effects
				(font
					(size 1 1)
					(thickness 0.15)
				)
			)
		)
		(property "License" "Apache-2.0"
			(at 171.6 156.05 0)
			(layer "F.Fab")
			(hide yes)
			(effects
				(font
					(size 1 1)
					(thickness 0.15)
				)
			)
		)
		(property "MPN" "CC0402MRX5R5BB106"
			(at 171.6 156.05 0)
			(layer "F.Fab")
			(hide yes)
			(effects
				(font
					(size 1 1)
					(thickness 0.15)
				)
			)
		)
		(property "Manufacturer" "YAGEO"
			(at 171.6 156.05 0)
			(layer "F.Fab")
			(hide yes)
			(effects
				(font
					(size 1 1)
					(thickness 0.15)
				)
			)
		)
		(property "Val" "10u"
			(at 171.6 156.05 0)
			(layer "F.Fab")
			(hide yes)
			(effects
				(font
					(size 1 1)
					(thickness 0.15)
				)
			)
		)
		(property "Voltage" ""
			(at 171.6 156.05 0)
			(layer "F.Fab")
			(hide yes)
			(effects
				(font
					(size 1 1)
					(thickness 0.15)
				)
			)
		)
		(sheetname "/Power supply/")
		(sheetfile "power-supply.kicad_sch")
		(attr smd)
		(fp_rect
			(start -0.925 -0.47)
			(end 0.925 0.47)
			(stroke
				(width 0.05)
				(type default)
			)
			(fill no)
			(layer "F.CrtYd")
		)
		(fp_line
			(start 0.504 0.248)
			(end -0.494 0.248)
			(stroke
				(width 0.15)
				(type solid)
			)
			(layer "F.Fab")
		)
		(fp_line
			(start 0.504 -0.25)
			(end 0.504 0.248)
			(stroke
				(width 0.15)
				(type solid)
			)
			(layer "F.Fab")
		)
		(fp_line
			(start -0.494 0.248)
			(end -0.494 -0.25)
			(stroke
				(width 0.15)
				(type solid)
			)
			(layer "F.Fab")
		)
		(fp_line
			(start -0.494 -0.25)
			(end 0.504 -0.25)
			(stroke
				(width 0.15)
				(type solid)
			)
			(layer "F.Fab")
		)
		(pad "1" smd roundrect
			(at -0.48 0 180)
			(size 0.59 0.64)
			(layers "F.Cu" "F.Mask" "F.Paste")
			(roundrect_rratio 0.25)
			(net 1 "GND")
			(pintype "passive")
		)
		(pad "2" smd roundrect
			(at 0.48 0 180)
			(size 0.59 0.64)
			(layers "F.Cu" "F.Mask" "F.Paste")
			(roundrect_rratio 0.25)
			(net 276 "Net-(C81-Pad2)")
			(pintype "passive")
		)
	)
	(footprint "antmicro-footprints:C_0402_1005Metric"
		(layer "F.Cu")
		(at 85.905 86.835 180)
		(descr "Capacitor SMD 0402")
		(tags "capacitor SMD 0402")
		(property "Reference" "C86"
			(at -2.995 -0.315 0)
			(layer "F.SilkS")
			(effects
				(font
					(size 0.7 0.7)
					(thickness 0.15)
				)
				(justify right bottom)
			)
		)
		(property "Value" "C_10u_0402"
			(at 0 1.4 0)
			(layer "F.Fab")
			(effects
				(font
					(size 0.7 0.7)
					(thickness 0.15)
				)
				(justify right bottom)
			)
		)
		(property "Datasheet" "https://www.yageo.com/en/Chart/Download/pdf/CC0402MRX5R5BB106"
			(at 0 0 180)
			(layer "F.Fab")
			(hide yes)
			(effects
				(font
					(size 1.27 1.27)
					(thickness 0.15)
				)
			)
		)
		(property "Description" "SMD Multilayer Ceramic Capacitor, 10 µF, 6.3 V, 0402 [1005 Metric], ± 20%, X5R, CC Series"
			(at 0 0 180)
			(layer "F.Fab")
			(hide yes)
			(effects
				(font
					(size 1.27 1.27)
					(thickness 0.15)
				)
			)
		)
		(property "Author" "Antmicro"
			(at 171.81 173.67 0)
			(layer "F.Fab")
			(hide yes)
			(effects
				(font
					(size 1 1)
					(thickness 0.15)
				)
			)
		)
		(property "Dielectric" ""
			(at 171.81 173.67 0)
			(layer "F.Fab")
			(hide yes)
			(effects
				(font
					(size 1 1)
					(thickness 0.15)
				)
			)
		)
		(property "License" "Apache-2.0"
			(at 171.81 173.67 0)
			(layer "F.Fab")
			(hide yes)
			(effects
				(font
					(size 1 1)
					(thickness 0.15)
				)
			)
		)
		(property "MPN" "CC0402MRX5R5BB106"
			(at 171.81 173.67 0)
			(layer "F.Fab")
			(hide yes)
			(effects
				(font
					(size 1 1)
					(thickness 0.15)
				)
			)
		)
		(property "Manufacturer" "YAGEO"
			(at 171.81 173.67 0)
			(layer "F.Fab")
			(hide yes)
			(effects
				(font
					(size 1 1)
					(thickness 0.15)
				)
			)
		)
		(property "Val" "10u"
			(at 171.81 173.67 0)
			(layer "F.Fab")
			(hide yes)
			(effects
				(font
					(size 1 1)
					(thickness 0.15)
				)
			)
		)
		(property "Voltage" ""
			(at 171.81 173.67 0)
			(layer "F.Fab")
			(hide yes)
			(effects
				(font
					(size 1 1)
					(thickness 0.15)
				)
			)
		)
		(sheetname "/Power supply/")
		(sheetfile "power-supply.kicad_sch")
		(attr smd)
		(fp_rect
			(start -0.925 -0.47)
			(end 0.925 0.47)
			(stroke
				(width 0.05)
				(type default)
			)
			(fill no)
			(layer "F.CrtYd")
		)
		(fp_line
			(start 0.504 0.248)
			(end -0.494 0.248)
			(stroke
				(width 0.15)
				(type solid)
			)
			(layer "F.Fab")
		)
		(fp_line
			(start 0.504 -0.25)
			(end 0.504 0.248)
			(stroke
				(width 0.15)
				(type solid)
			)
			(layer "F.Fab")
		)
		(fp_line
			(start -0.494 0.248)
			(end -0.494 -0.25)
			(stroke
				(width 0.15)
				(type solid)
			)
			(layer "F.Fab")
		)
		(fp_line
			(start -0.494 -0.25)
			(end 0.504 -0.25)
			(stroke
				(width 0.15)
				(type solid)
			)
			(layer "F.Fab")
		)
		(pad "1" smd roundrect
			(at -0.48 0 180)
			(size 0.59 0.64)
			(layers "F.Cu" "F.Mask" "F.Paste")
			(roundrect_rratio 0.25)
			(net 1 "GND")
			(pintype "passive")
		)
		(pad "2" smd roundrect
			(at 0.48 0 180)
			(size 0.59 0.64)
			(layers "F.Cu" "F.Mask" "F.Paste")
			(roundrect_rratio 0.25)
			(net 277 "Net-(C82-Pad2)")
			(pintype "passive")
		)
	)
	(footprint "antmicro-footprints:QFN-8_2x1.5mm"
		(layer "F.Cu")
		(at 86.995 104.125 180)
		(property "Reference" "U10"
			(at 0.885 -2.245 180)
			(layer "F.SilkS")
			(effects
				(font
					(size 0.7 0.7)
					(thickness 0.15)
				)
				(justify left bottom)
			)
		)
		(property "Value" "TPS62823DLCT"
			(at 0 2.2 180)
			(layer "F.Fab")
			(effects
				(font
					(size 0.7 0.7)
					(thickness 0.15)
				)
				(justify left bottom)
			)
		)
		(property "Datasheet" "https://www.ti.com/lit/ds/symlink/tps62823.pdf?ts=1685970309606&ref_url=https%253A%252F%252Fwww.ti.com%252Fproduct%252FTPS62823%252Fpart-details%252FTPS62823DLCT"
			(at 0 0 180)
			(layer "F.Fab")
			(hide yes)
			(effects
				(font
					(size 1.27 1.27)
					(thickness 0.15)
				)
			)
		)
		(property "Description" "DC/DC converter"
			(at 0 0 180)
			(layer "F.Fab")
			(hide yes)
			(effects
				(font
					(size 1.27 1.27)
					(thickness 0.15)
				)
			)
		)
		(property "Author" "Antmicro"
			(at 173.99 208.25 0)
			(layer "F.Fab")
			(hide yes)
			(effects
				(font
					(size 1 1)
					(thickness 0.15)
				)
			)
		)
		(property "License" "Apache-2.0"
			(at 173.99 208.25 0)
			(layer "F.Fab")
			(hide yes)
			(effects
				(font
					(size 1 1)
					(thickness 0.15)
				)
			)
		)
		(property "MPN" "TPS62823DLCT"
			(at 173.99 208.25 0)
			(layer "F.Fab")
			(hide yes)
			(effects
				(font
					(size 1 1)
					(thickness 0.15)
				)
			)
		)
		(property "Manufacturer" "Texas Instruments"
			(at 173.99 208.25 0)
			(layer "F.Fab")
			(hide yes)
			(effects
				(font
					(size 1 1)
					(thickness 0.15)
				)
			)
		)
		(sheetname "/Power supply/")
		(sheetfile "power-supply.kicad_sch")
		(attr smd)
		(fp_line
			(start -0.25 -1.05)
			(end 0.9 -1.05)
			(stroke
				(width 0.15)
				(type solid)
			)
			(layer "F.SilkS")
		)
		(fp_line
			(start -0.9 1.05)
			(end 0.9 1.05)
			(stroke
				(width 0.15)
				(type solid)
			)
			(layer "F.SilkS")
		)
		(fp_circle
			(center -0.9 -1.05)
			(end -0.849 -1.05)
			(stroke
				(width 0.15)
				(type solid)
			)
			(fill yes)
			(layer "F.SilkS")
		)
		(fp_rect
			(start -1.1 -1.25)
			(end 1.1 1.25)
			(stroke
				(width 0.05)
				(type solid)
			)
			(fill no)
			(layer "F.CrtYd")
		)
		(fp_line
			(start 0.998 0.998)
			(end -1 0.998)
			(stroke
				(width 0.15)
				(type solid)
			)
			(layer "F.Fab")
		)
		(fp_line
			(start 0.998 -1)
			(end 0.998 0.998)
			(stroke
				(width 0.15)
				(type solid)
			)
			(layer "F.Fab")
		)
		(fp_line
			(start -0.5 -1)
			(end 0.998 -1)
			(stroke
				(width 0.15)
				(type solid)
			)
			(layer "F.Fab")
		)
		(fp_line
			(start -1 0.998)
			(end -1 -0.5)
			(stroke
				(width 0.15)
				(type solid)
			)
			(layer "F.Fab")
		)
		(fp_line
			(start -1 -0.5)
			(end -0.5 -1)
			(stroke
				(width 0.15)
				(type solid)
			)
			(layer "F.Fab")
		)
		(pad "1" smd rect
			(at -0.677 -0.75 180)
			(size 0.55 0.25)
			(layers "F.Cu" "F.Mask" "F.Paste")
			(net 314 "Net-(U10-EN)")
			(pinfunction "EN")
			(pintype "input")
		)
		(pad "2" smd rect
			(at -0.677 -0.25 180)
			(size 0.55 0.25)
			(layers "F.Cu" "F.Mask" "F.Paste")
			(net 113 "Net-(U10-FB)")
			(pinfunction "FB")
			(pintype "bidirectional")
		)
		(pad "3" smd rect
			(at -0.677 0.248 180)
			(size 0.55 0.25)
			(layers "F.Cu" "F.Mask" "F.Paste")
			(net 1 "GND")
			(pinfunction "AGND")
			(pintype "power_in")
		)
		(pad "4" smd rect
			(at -0.677 0.748 180)
			(size 0.55 0.25)
			(layers "F.Cu" "F.Mask" "F.Paste")
			(net 528 "unconnected-(U10-NC-Pad4)")
			(pinfunction "NC")
			(pintype "no_connect")
		)
		(pad "5" smd rect
			(at 0.675 0.748 180)
			(size 0.55 0.25)
			(layers "F.Cu" "F.Mask" "F.Paste")
			(net 1 "GND")
			(pinfunction "PGND")
			(pintype "power_in")
		)
		(pad "6" smd rect
			(at 0.675 0.248 180)
			(size 0.55 0.25)
			(layers "F.Cu" "F.Mask" "F.Paste")
			(net 285 "Net-(U10-SW)")
			(pinfunction "SW")
			(pintype "bidirectional")
		)
		(pad "7" smd rect
			(at 0.675 -0.25 180)
			(size 0.55 0.25)
			(layers "F.Cu" "F.Mask" "F.Paste")
			(net 4 "VCC5V0")
			(pinfunction "VIN")
			(pintype "power_in")
		)
		(pad "8" smd rect
			(at 0.675 -0.75 180)
			(size 0.55 0.25)
			(layers "F.Cu" "F.Mask" "F.Paste")
			(net 529 "unconnected-(U10-PG-Pad8)")
			(pinfunction "PG")
			(pintype "output+no_connect")
		)
	)
	(footprint "antmicro-footprints:L_Vishay-IHLP-1212AE"
		(layer "F.Cu")
		(at 82.55 79.825 90)
		(property "Reference" "L4"
			(at -2.735 -2.02 180)
			(layer "F.SilkS")
			(effects
				(font
					(size 0.7 0.7)
					(thickness 0.15)
				)
				(justify left bottom)
			)
		)
		(property "Value" "L_470n_6.7A_Vishay-IHLP-1212AE-11"
			(at 1.278 3.401 90)
			(layer "F.Fab")
			(effects
				(font
					(size 0.7 0.7)
					(thickness 0.15)
				)
				(justify left bottom)
			)
		)
		(property "Datasheet" "https://www.vishay.com/docs/34300/ihlp-1212ae-11.pdf"
			(at 0 0 90)
			(layer "F.Fab")
			(hide yes)
			(effects
				(font
					(size 1.27 1.27)
					(thickness 0.15)
				)
			)
		)
		(property "Description" "Power Inductor (SMT), 470 nH, 6.7 A, Shielded, 6.7 A"
			(at 0 0 90)
			(layer "F.Fab")
			(hide yes)
			(effects
				(font
					(size 1.27 1.27)
					(thickness 0.15)
				)
			)
		)
		(property "Author" "Antmicro"
			(at 162.375 -2.725 0)
			(layer "F.Fab")
			(hide yes)
			(effects
				(font
					(size 1 1)
					(thickness 0.15)
				)
			)
		)
		(property "IMax" "6.7 A"
			(at 162.375 -2.725 0)
			(layer "F.Fab")
			(hide yes)
			(effects
				(font
					(size 1 1)
					(thickness 0.15)
				)
			)
		)
		(property "ISat" "6.7 A"
			(at 162.375 -2.725 0)
			(layer "F.Fab")
			(hide yes)
			(effects
				(font
					(size 1 1)
					(thickness 0.15)
				)
			)
		)
		(property "License" "Apache-2.0"
			(at 162.375 -2.725 0)
			(layer "F.Fab")
			(hide yes)
			(effects
				(font
					(size 1 1)
					(thickness 0.15)
				)
			)
		)
		(property "MPN" "IHLP1212AEERR47M11"
			(at 162.375 -2.725 0)
			(layer "F.Fab")
			(hide yes)
			(effects
				(font
					(size 1 1)
					(thickness 0.15)
				)
			)
		)
		(property "Manufacturer" "Vishay"
			(at 162.375 -2.725 0)
			(layer "F.Fab")
			(hide yes)
			(effects
				(font
					(size 1 1)
					(thickness 0.15)
				)
			)
		)
		(property "Size" "3.0x3.0"
			(at 162.375 -2.725 0)
			(layer "F.Fab")
			(hide yes)
			(effects
				(font
					(size 1 1)
					(thickness 0.15)
				)
			)
		)
		(property "Val" "470n/6.7A"
			(at 162.375 -2.725 0)
			(layer "F.Fab")
			(hide yes)
			(effects
				(font
					(size 1 1)
					(thickness 0.15)
				)
			)
		)
		(sheetname "/Power supply/")
		(sheetfile "power-supply.kicad_sch")
		(attr smd)
		(fp_line
			(start 1.653 -1.6)
			(end 1.653 -0.9)
			(stroke
				(width 0.15)
				(type solid)
			)
			(layer "F.SilkS")
		)
		(fp_line
			(start -1.647 -1.6)
			(end 1.653 -1.6)
			(stroke
				(width 0.15)
				(type solid)
			)
			(layer "F.SilkS")
		)
		(fp_line
			(start -1.647 -0.9)
			(end -1.647 -1.6)
			(stroke
				(width 0.15)
				(type solid)
			)
			(layer "F.SilkS")
		)
		(fp_line
			(start 1.653 0.9)
			(end 1.653 1.601)
			(stroke
				(width 0.15)
				(type solid)
			)
			(layer "F.SilkS")
		)
		(fp_line
			(start -1.647 1.6)
			(end -1.647 0.9)
			(stroke
				(width 0.15)
				(type solid)
			)
			(layer "F.SilkS")
		)
		(fp_line
			(start 1.653 1.601)
			(end -1.647 1.6)
			(stroke
				(width 0.15)
				(type solid)
			)
			(layer "F.SilkS")
		)
		(fp_rect
			(start -2.35 -1.85)
			(end 2.35 1.85)
			(stroke
				(width 0.05)
				(type solid)
			)
			(fill no)
			(layer "F.CrtYd")
		)
		(fp_rect
			(start -1.803 -1.601)
			(end 1.803 1.601)
			(stroke
				(width 0.15)
				(type solid)
			)
			(fill no)
			(layer "F.Fab")
		)
		(pad "1" smd roundrect
			(at -1.35 0 90)
			(size 1.5 1.2)
			(layers "F.Cu" "F.Mask" "F.Paste")
			(roundrect_rratio 0.1)
			(net 289 "Net-(U12-SW)")
			(pintype "passive")
		)
		(pad "2" smd roundrect
			(at 1.35 0 90)
			(size 1.5 1.2)
			(layers "F.Cu" "F.Mask" "F.Paste")
			(roundrect_rratio 0.1)
			(net 276 "Net-(C81-Pad2)")
			(pintype "passive")
		)
	)
	(footprint "antmicro-footprints:L_Vishay-IHLP-1212AE"
		(layer "F.Cu")
		(at 82.65 101.8 90)
		(property "Reference" "L2"
			(at -2.067 -0.6545 90)
			(layer "F.SilkS")
			(effects
				(font
					(size 0.7 0.7)
					(thickness 0.15)
				)
				(justify left bottom)
			)
		)
		(property "Value" "L_470n_6.7A_Vishay-IHLP-1212AE-11"
			(at 1.278 3.401 90)
			(layer "F.Fab")
			(effects
				(font
					(size 0.7 0.7)
					(thickness 0.15)
				)
				(justify left bottom)
			)
		)
		(property "Datasheet" "https://www.vishay.com/docs/34300/ihlp-1212ae-11.pdf"
			(at 0 0 90)
			(layer "F.Fab")
			(hide yes)
			(effects
				(font
					(size 1.27 1.27)
					(thickness 0.15)
				)
			)
		)
		(property "Description" "Power Inductor (SMT), 470 nH, 6.7 A, Shielded, 6.7 A"
			(at 0 0 90)
			(layer "F.Fab")
			(hide yes)
			(effects
				(font
					(size 1.27 1.27)
					(thickness 0.15)
				)
			)
		)
		(property "Author" "Antmicro"
			(at 184.45 19.15 0)
			(layer "F.Fab")
			(hide yes)
			(effects
				(font
					(size 1 1)
					(thickness 0.15)
				)
			)
		)
		(property "IMax" "6.7 A"
			(at 184.45 19.15 0)
			(layer "F.Fab")
			(hide yes)
			(effects
				(font
					(size 1 1)
					(thickness 0.15)
				)
			)
		)
		(property "ISat" "6.7 A"
			(at 184.45 19.15 0)
			(layer "F.Fab")
			(hide yes)
			(effects
				(font
					(size 1 1)
					(thickness 0.15)
				)
			)
		)
		(property "License" "Apache-2.0"
			(at 184.45 19.15 0)
			(layer "F.Fab")
			(hide yes)
			(effects
				(font
					(size 1 1)
					(thickness 0.15)
				)
			)
		)
		(property "MPN" "IHLP1212AEERR47M11"
			(at 184.45 19.15 0)
			(layer "F.Fab")
			(hide yes)
			(effects
				(font
					(size 1 1)
					(thickness 0.15)
				)
			)
		)
		(property "Manufacturer" "Vishay"
			(at 184.45 19.15 0)
			(layer "F.Fab")
			(hide yes)
			(effects
				(font
					(size 1 1)
					(thickness 0.15)
				)
			)
		)
		(property "Size" "3.0x3.0"
			(at 184.45 19.15 0)
			(layer "F.Fab")
			(hide yes)
			(effects
				(font
					(size 1 1)
					(thickness 0.15)
				)
			)
		)
		(property "Val" "470n/6.7A"
			(at 184.45 19.15 0)
			(layer "F.Fab")
			(hide yes)
			(effects
				(font
					(size 1 1)
					(thickness 0.15)
				)
			)
		)
		(sheetname "/Power supply/")
		(sheetfile "power-supply.kicad_sch")
		(attr smd)
		(fp_line
			(start 1.653 -1.6)
			(end 1.653 -0.9)
			(stroke
				(width 0.15)
				(type solid)
			)
			(layer "F.SilkS")
		)
		(fp_line
			(start -1.647 -1.6)
			(end 1.653 -1.6)
			(stroke
				(width 0.15)
				(type solid)
			)
			(layer "F.SilkS")
		)
		(fp_line
			(start -1.647 -0.9)
			(end -1.647 -1.6)
			(stroke
				(width 0.15)
				(type solid)
			)
			(layer "F.SilkS")
		)
		(fp_line
			(start 1.653 0.9)
			(end 1.653 1.601)
			(stroke
				(width 0.15)
				(type solid)
			)
			(layer "F.SilkS")
		)
		(fp_line
			(start -1.647 1.6)
			(end -1.647 0.9)
			(stroke
				(width 0.15)
				(type solid)
			)
			(layer "F.SilkS")
		)
		(fp_line
			(start 1.653 1.601)
			(end -1.647 1.6)
			(stroke
				(width 0.15)
				(type solid)
			)
			(layer "F.SilkS")
		)
		(fp_rect
			(start -2.35 -1.85)
			(end 2.35 1.85)
			(stroke
				(width 0.05)
				(type solid)
			)
			(fill no)
			(layer "F.CrtYd")
		)
		(fp_rect
			(start -1.803 -1.601)
			(end 1.803 1.601)
			(stroke
				(width 0.15)
				(type solid)
			)
			(fill no)
			(layer "F.Fab")
		)
		(pad "1" smd roundrect
			(at -1.35 0 90)
			(size 1.5 1.2)
			(layers "F.Cu" "F.Mask" "F.Paste")
			(roundrect_rratio 0.1)
			(net 285 "Net-(U10-SW)")
			(pintype "passive")
		)
		(pad "2" smd roundrect
			(at 1.35 0 90)
			(size 1.5 1.2)
			(layers "F.Cu" "F.Mask" "F.Paste")
			(roundrect_rratio 0.1)
			(net 274 "Net-(C79-Pad2)")
			(pintype "passive")
		)
	)
	(footprint "antmicro-footprints:L_Vishay-IHLP-1212AE"
		(layer "F.Cu")
		(at 82.5545 94.6 90)
		(property "Reference" "L3"
			(at -2.067 -0.6545 90)
			(layer "F.SilkS")
			(effects
				(font
					(size 0.7 0.7)
					(thickness 0.15)
				)
				(justify left bottom)
			)
		)
		(property "Value" "L_470n_6.7A_Vishay-IHLP-1212AE-11"
			(at 1.278 3.401 90)
			(layer "F.Fab")
			(effects
				(font
					(size 0.7 0.7)
					(thickness 0.15)
				)
				(justify left bottom)
			)
		)
		(property "Datasheet" "https://www.vishay.com/docs/34300/ihlp-1212ae-11.pdf"
			(at 0 0 90)
			(layer "F.Fab")
			(hide yes)
			(effects
				(font
					(size 1.27 1.27)
					(thickness 0.15)
				)
			)
		)
		(property "Description" "Power Inductor (SMT), 470 nH, 6.7 A, Shielded, 6.7 A"
			(at 0 0 90)
			(layer "F.Fab")
			(hide yes)
			(effects
				(font
					(size 1.27 1.27)
					(thickness 0.15)
				)
			)
		)
		(property "Author" "Antmicro"
			(at 177.1545 12.0455 0)
			(layer "F.Fab")
			(hide yes)
			(effects
				(font
					(size 1 1)
					(thickness 0.15)
				)
			)
		)
		(property "IMax" "6.7 A"
			(at 177.1545 12.0455 0)
			(layer "F.Fab")
			(hide yes)
			(effects
				(font
					(size 1 1)
					(thickness 0.15)
				)
			)
		)
		(property "ISat" "6.7 A"
			(at 177.1545 12.0455 0)
			(layer "F.Fab")
			(hide yes)
			(effects
				(font
					(size 1 1)
					(thickness 0.15)
				)
			)
		)
		(property "License" "Apache-2.0"
			(at 177.1545 12.0455 0)
			(layer "F.Fab")
			(hide yes)
			(effects
				(font
					(size 1 1)
					(thickness 0.15)
				)
			)
		)
		(property "MPN" "IHLP1212AEERR47M11"
			(at 177.1545 12.0455 0)
			(layer "F.Fab")
			(hide yes)
			(effects
				(font
					(size 1 1)
					(thickness 0.15)
				)
			)
		)
		(property "Manufacturer" "Vishay"
			(at 177.1545 12.0455 0)
			(layer "F.Fab")
			(hide yes)
			(effects
				(font
					(size 1 1)
					(thickness 0.15)
				)
			)
		)
		(property "Size" "3.0x3.0"
			(at 177.1545 12.0455 0)
			(layer "F.Fab")
			(hide yes)
			(effects
				(font
					(size 1 1)
					(thickness 0.15)
				)
			)
		)
		(property "Val" "470n/6.7A"
			(at 177.1545 12.0455 0)
			(layer "F.Fab")
			(hide yes)
			(effects
				(font
					(size 1 1)
					(thickness 0.15)
				)
			)
		)
		(sheetname "/Power supply/")
		(sheetfile "power-supply.kicad_sch")
		(attr smd)
		(fp_line
			(start 1.653 -1.6)
			(end 1.653 -0.9)
			(stroke
				(width 0.15)
				(type solid)
			)
			(layer "F.SilkS")
		)
		(fp_line
			(start -1.647 -1.6)
			(end 1.653 -1.6)
			(stroke
				(width 0.15)
				(type solid)
			)
			(layer "F.SilkS")
		)
		(fp_line
			(start -1.647 -0.9)
			(end -1.647 -1.6)
			(stroke
				(width 0.15)
				(type solid)
			)
			(layer "F.SilkS")
		)
		(fp_line
			(start 1.653 0.9)
			(end 1.653 1.601)
			(stroke
				(width 0.15)
				(type solid)
			)
			(layer "F.SilkS")
		)
		(fp_line
			(start -1.647 1.6)
			(end -1.647 0.9)
			(stroke
				(width 0.15)
				(type solid)
			)
			(layer "F.SilkS")
		)
		(fp_line
			(start 1.653 1.601)
			(end -1.647 1.6)
			(stroke
				(width 0.15)
				(type solid)
			)
			(layer "F.SilkS")
		)
		(fp_rect
			(start -2.35 -1.85)
			(end 2.35 1.85)
			(stroke
				(width 0.05)
				(type solid)
			)
			(fill no)
			(layer "F.CrtYd")
		)
		(fp_rect
			(start -1.803 -1.601)
			(end 1.803 1.601)
			(stroke
				(width 0.15)
				(type solid)
			)
			(fill no)
			(layer "F.Fab")
		)
		(pad "1" smd roundrect
			(at -1.35 0 90)
			(size 1.5 1.2)
			(layers "F.Cu" "F.Mask" "F.Paste")
			(roundrect_rratio 0.1)
			(net 288 "Net-(U11-SW)")
			(pintype "passive")
		)
		(pad "2" smd roundrect
			(at 1.35 0 90)
			(size 1.5 1.2)
			(layers "F.Cu" "F.Mask" "F.Paste")
			(roundrect_rratio 0.1)
			(net 275 "Net-(C80-Pad2)")
			(pintype "passive")
		)
	)
	(footprint "antmicro-footprints:L_Vishay-IHLP-1212AE"
		(layer "F.Cu")
		(at 82.65 87.2 90)
		(property "Reference" "L5"
			(at -2.067 -0.6545 90)
			(layer "F.SilkS")
			(effects
				(font
					(size 0.7 0.7)
					(thickness 0.15)
				)
				(justify left bottom)
			)
		)
		(property "Value" "L_470n_6.7A_Vishay-IHLP-1212AE-11"
			(at 1.278 3.401 90)
			(layer "F.Fab")
			(effects
				(font
					(size 0.7 0.7)
					(thickness 0.15)
				)
				(justify left bottom)
			)
		)
		(property "Datasheet" "https://www.vishay.com/docs/34300/ihlp-1212ae-11.pdf"
			(at 0 0 90)
			(layer "F.Fab")
			(hide yes)
			(effects
				(font
					(size 1.27 1.27)
					(thickness 0.15)
				)
			)
		)
		(property "Description" "Power Inductor (SMT), 470 nH, 6.7 A, Shielded, 6.7 A"
			(at 0 0 90)
			(layer "F.Fab")
			(hide yes)
			(effects
				(font
					(size 1.27 1.27)
					(thickness 0.15)
				)
			)
		)
		(property "Author" "Antmicro"
			(at 169.85 4.55 0)
			(layer "F.Fab")
			(hide yes)
			(effects
				(font
					(size 1 1)
					(thickness 0.15)
				)
			)
		)
		(property "IMax" "6.7 A"
			(at 169.85 4.55 0)
			(layer "F.Fab")
			(hide yes)
			(effects
				(font
					(size 1 1)
					(thickness 0.15)
				)
			)
		)
		(property "ISat" "6.7 A"
			(at 169.85 4.55 0)
			(layer "F.Fab")
			(hide yes)
			(effects
				(font
					(size 1 1)
					(thickness 0.15)
				)
			)
		)
		(property "License" "Apache-2.0"
			(at 169.85 4.55 0)
			(layer "F.Fab")
			(hide yes)
			(effects
				(font
					(size 1 1)
					(thickness 0.15)
				)
			)
		)
		(property "MPN" "IHLP1212AEERR47M11"
			(at 169.85 4.55 0)
			(layer "F.Fab")
			(hide yes)
			(effects
				(font
					(size 1 1)
					(thickness 0.15)
				)
			)
		)
		(property "Manufacturer" "Vishay"
			(at 169.85 4.55 0)
			(layer "F.Fab")
			(hide yes)
			(effects
				(font
					(size 1 1)
					(thickness 0.15)
				)
			)
		)
		(property "Size" "3.0x3.0"
			(at 169.85 4.55 0)
			(layer "F.Fab")
			(hide yes)
			(effects
				(font
					(size 1 1)
					(thickness 0.15)
				)
			)
		)
		(property "Val" "470n/6.7A"
			(at 169.85 4.55 0)
			(layer "F.Fab")
			(hide yes)
			(effects
				(font
					(size 1 1)
					(thickness 0.15)
				)
			)
		)
		(sheetname "/Power supply/")
		(sheetfile "power-supply.kicad_sch")
		(attr smd)
		(fp_line
			(start 1.653 -1.6)
			(end 1.653 -0.9)
			(stroke
				(width 0.15)
				(type solid)
			)
			(layer "F.SilkS")
		)
		(fp_line
			(start -1.647 -1.6)
			(end 1.653 -1.6)
			(stroke
				(width 0.15)
				(type solid)
			)
			(layer "F.SilkS")
		)
		(fp_line
			(start -1.647 -0.9)
			(end -1.647 -1.6)
			(stroke
				(width 0.15)
				(type solid)
			)
			(layer "F.SilkS")
		)
		(fp_line
			(start 1.653 0.9)
			(end 1.653 1.601)
			(stroke
				(width 0.15)
				(type solid)
			)
			(layer "F.SilkS")
		)
		(fp_line
			(start -1.647 1.6)
			(end -1.647 0.9)
			(stroke
				(width 0.15)
				(type solid)
			)
			(layer "F.SilkS")
		)
		(fp_line
			(start 1.653 1.601)
			(end -1.647 1.6)
			(stroke
				(width 0.15)
				(type solid)
			)
			(layer "F.SilkS")
		)
		(fp_rect
			(start -2.35 -1.85)
			(end 2.35 1.85)
			(stroke
				(width 0.05)
				(type solid)
			)
			(fill no)
			(layer "F.CrtYd")
		)
		(fp_rect
			(start -1.803 -1.601)
			(end 1.803 1.601)
			(stroke
				(width 0.15)
				(type solid)
			)
			(fill no)
			(layer "F.Fab")
		)
		(pad "1" smd roundrect
			(at -1.35 0 90)
			(size 1.5 1.2)
			(layers "F.Cu" "F.Mask" "F.Paste")
			(roundrect_rratio 0.1)
			(net 290 "Net-(U13-SW)")
			(pintype "passive")
		)
		(pad "2" smd roundrect
			(at 1.35 0 90)
			(size 1.5 1.2)
			(layers "F.Cu" "F.Mask" "F.Paste")
			(roundrect_rratio 0.1)
			(net 277 "Net-(C82-Pad2)")
			(pintype "passive")
		)
	)
	(footprint "antmicro-footprints:R_0603_1608Metric"
		(layer "F.Cu")
		(at 80.15 100.175 -90)
		(descr "Resistor SMD 0603")
		(tags "resistor SMD 0603")
		(property "Reference" "R139"
			(at 1.025 -0.325 90)
			(layer "F.SilkS")
			(effects
				(font
					(size 0.7 0.7)
					(thickness 0.15)
				)
				(justify right bottom)
			)
		)
		(property "Value" "R_0R_0603"
			(at 0 1.6 90)
			(layer "F.Fab")
			(effects
				(font
					(size 0.7 0.7)
					(thickness 0.15)
				)
				(justify right bottom)
			)
		)
		(property "Datasheet" "https://www.bourns.com/docs/product-datasheets/cr.pdf?sfvrsn=574d41f6_14"
			(at 0 0 270)
			(layer "F.Fab")
			(hide yes)
			(effects
				(font
					(size 1.27 1.27)
					(thickness 0.15)
				)
			)
		)
		(property "Description" "Zero Ohm Resistor, Jumper, 0603 [1608 Metric], Thick Film, 100 mW, 1 A, Surface Mount Device, CR"
			(at 0 0 270)
			(layer "F.Fab")
			(hide yes)
			(effects
				(font
					(size 1.27 1.27)
					(thickness 0.15)
				)
			)
		)
		(property "Author" "Antmicro"
			(at -20.025 180.325 0)
			(layer "F.Fab")
			(hide yes)
			(effects
				(font
					(size 1 1)
					(thickness 0.15)
				)
			)
		)
		(property "Current" "1A"
			(at -20.025 180.325 0)
			(layer "F.Fab")
			(hide yes)
			(effects
				(font
					(size 1 1)
					(thickness 0.15)
				)
			)
		)
		(property "License" "Apache-2.0"
			(at -20.025 180.325 0)
			(layer "F.Fab")
			(hide yes)
			(effects
				(font
					(size 1 1)
					(thickness 0.15)
				)
			)
		)
		(property "MPN" "CR0603-J/-000ELF"
			(at -20.025 180.325 0)
			(layer "F.Fab")
			(hide yes)
			(effects
				(font
					(size 1 1)
					(thickness 0.15)
				)
			)
		)
		(property "Manufacturer" "Bourns"
			(at -20.025 180.325 0)
			(layer "F.Fab")
			(hide yes)
			(effects
				(font
					(size 1 1)
					(thickness 0.15)
				)
			)
		)
		(property "Tolerance" "~"
			(at -20.025 180.325 0)
			(layer "F.Fab")
			(hide yes)
			(effects
				(font
					(size 1 1)
					(thickness 0.15)
				)
			)
		)
		(property "Val" "0R"
			(at -20.025 180.325 0)
			(layer "F.Fab")
			(hide yes)
			(effects
				(font
					(size 1 1)
					(thickness 0.15)
				)
			)
		)
		(sheetname "/Power supply/")
		(sheetfile "power-supply.kicad_sch")
		(attr smd)
		(fp_line
			(start -0.15 0.4)
			(end 0.15 0.4)
			(stroke
				(width 0.15)
				(type solid)
			)
			(layer "F.SilkS")
		)
		(fp_line
			(start -0.15 -0.4)
			(end 0.15 -0.4)
			(stroke
				(width 0.15)
				(type solid)
			)
			(layer "F.SilkS")
		)
		(fp_rect
			(start -1.25 -0.65)
			(end 1.25 0.65)
			(stroke
				(width 0.05)
				(type solid)
			)
			(fill no)
			(layer "F.CrtYd")
		)
		(fp_rect
			(start -0.8 -0.4)
			(end 0.8 0.4)
			(stroke
				(width 0.15)
				(type solid)
			)
			(fill no)
			(layer "F.Fab")
		)
		(pad "1" smd roundrect
			(at -0.7 0 270)
			(size 0.8 1)
			(layers "F.Cu" "F.Mask" "F.Paste")
			(roundrect_rratio 0.2)
			(net 2 "VCC3V3")
			(pintype "passive")
		)
		(pad "2" smd roundrect
			(at 0.7 0 270)
			(size 0.8 1)
			(layers "F.Cu" "F.Mask" "F.Paste")
			(roundrect_rratio 0.2)
			(net 274 "Net-(C79-Pad2)")
			(pintype "passive")
		)
	)
	(footprint "antmicro-footprints:R_0603_1608Metric"
		(layer "F.Cu")
		(at 79.925 79.4 90)
		(descr "Resistor SMD 0603")
		(tags "resistor SMD 0603")
		(property "Reference" "R141"
			(at -3.9 0.175 90)
			(layer "F.SilkS")
			(effects
				(font
					(size 0.7 0.7)
					(thickness 0.15)
				)
				(justify left bottom)
			)
		)
		(property "Value" "R_0R_0603"
			(at 0 1.6 90)
			(layer "F.Fab")
			(effects
				(font
					(size 0.7 0.7)
					(thickness 0.15)
				)
				(justify left bottom)
			)
		)
		(property "Datasheet" "https://www.bourns.com/docs/product-datasheets/cr.pdf?sfvrsn=574d41f6_14"
			(at 0 0 90)
			(layer "F.Fab")
			(hide yes)
			(effects
				(font
					(size 1.27 1.27)
					(thickness 0.15)
				)
			)
		)
		(property "Description" "Zero Ohm Resistor, Jumper, 0603 [1608 Metric], Thick Film, 100 mW, 1 A, Surface Mount Device, CR"
			(at 0 0 90)
			(layer "F.Fab")
			(hide yes)
			(effects
				(font
					(size 1.27 1.27)
					(thickness 0.15)
				)
			)
		)
		(property "Author" "Antmicro"
			(at 159.325 -0.525 0)
			(layer "F.Fab")
			(hide yes)
			(effects
				(font
					(size 1 1)
					(thickness 0.15)
				)
			)
		)
		(property "Current" "1A"
			(at 159.325 -0.525 0)
			(layer "F.Fab")
			(hide yes)
			(effects
				(font
					(size 1 1)
					(thickness 0.15)
				)
			)
		)
		(property "License" "Apache-2.0"
			(at 159.325 -0.525 0)
			(layer "F.Fab")
			(hide yes)
			(effects
				(font
					(size 1 1)
					(thickness 0.15)
				)
			)
		)
		(property "MPN" "CR0603-J/-000ELF"
			(at 159.325 -0.525 0)
			(layer "F.Fab")
			(hide yes)
			(effects
				(font
					(size 1 1)
					(thickness 0.15)
				)
			)
		)
		(property "Manufacturer" "Bourns"
			(at 159.325 -0.525 0)
			(layer "F.Fab")
			(hide yes)
			(effects
				(font
					(size 1 1)
					(thickness 0.15)
				)
			)
		)
		(property "Tolerance" "~"
			(at 159.325 -0.525 0)
			(layer "F.Fab")
			(hide yes)
			(effects
				(font
					(size 1 1)
					(thickness 0.15)
				)
			)
		)
		(property "Val" "0R"
			(at 159.325 -0.525 0)
			(layer "F.Fab")
			(hide yes)
			(effects
				(font
					(size 1 1)
					(thickness 0.15)
				)
			)
		)
		(sheetname "/Power supply/")
		(sheetfile "power-supply.kicad_sch")
		(attr smd)
		(fp_line
			(start -0.15 -0.4)
			(end 0.15 -0.4)
			(stroke
				(width 0.15)
				(type solid)
			)
			(layer "F.SilkS")
		)
		(fp_line
			(start -0.15 0.4)
			(end 0.15 0.4)
			(stroke
				(width 0.15)
				(type solid)
			)
			(layer "F.SilkS")
		)
		(fp_rect
			(start -1.25 -0.65)
			(end 1.25 0.65)
			(stroke
				(width 0.05)
				(type solid)
			)
			(fill no)
			(layer "F.CrtYd")
		)
		(fp_rect
			(start -0.8 -0.4)
			(end 0.8 0.4)
			(stroke
				(width 0.15)
				(type solid)
			)
			(fill no)
			(layer "F.Fab")
		)
		(pad "1" smd roundrect
			(at -0.7 0 90)
			(size 0.8 1)
			(layers "F.Cu" "F.Mask" "F.Paste")
			(roundrect_rratio 0.2)
			(net 6 "VCC1V0")
			(pintype "passive")
		)
		(pad "2" smd roundrect
			(at 0.7 0 90)
			(size 0.8 1)
			(layers "F.Cu" "F.Mask" "F.Paste")
			(roundrect_rratio 0.2)
			(net 276 "Net-(C81-Pad2)")
			(pintype "passive")
		)
	)
	(footprint "antmicro-footprints:R_0603_1608Metric"
		(layer "F.Cu")
		(at 79.775 85.375 -90)
		(descr "Resistor SMD 0603")
		(tags "resistor SMD 0603")
		(property "Reference" "R142"
			(at 1.025 -0.325 90)
			(layer "F.SilkS")
			(effects
				(font
					(size 0.7 0.7)
					(thickness 0.15)
				)
				(justify right bottom)
			)
		)
		(property "Value" "R_0R_0603"
			(at 0 1.6 90)
			(layer "F.Fab")
			(effects
				(font
					(size 0.7 0.7)
					(thickness 0.15)
				)
				(justify right bottom)
			)
		)
		(property "Datasheet" "https://www.bourns.com/docs/product-datasheets/cr.pdf?sfvrsn=574d41f6_14"
			(at 0 0 270)
			(layer "F.Fab")
			(hide yes)
			(effects
				(font
					(size 1.27 1.27)
					(thickness 0.15)
				)
			)
		)
		(property "Description" "Zero Ohm Resistor, Jumper, 0603 [1608 Metric], Thick Film, 100 mW, 1 A, Surface Mount Device, CR"
			(at 0 0 270)
			(layer "F.Fab")
			(hide yes)
			(effects
				(font
					(size 1.27 1.27)
					(thickness 0.15)
				)
			)
		)
		(property "Author" "Antmicro"
			(at -5.6 165.15 0)
			(layer "F.Fab")
			(hide yes)
			(effects
				(font
					(size 1 1)
					(thickness 0.15)
				)
			)
		)
		(property "Current" "1A"
			(at -5.6 165.15 0)
			(layer "F.Fab")
			(hide yes)
			(effects
				(font
					(size 1 1)
					(thickness 0.15)
				)
			)
		)
		(property "License" "Apache-2.0"
			(at -5.6 165.15 0)
			(layer "F.Fab")
			(hide yes)
			(effects
				(font
					(size 1 1)
					(thickness 0.15)
				)
			)
		)
		(property "MPN" "CR0603-J/-000ELF"
			(at -5.6 165.15 0)
			(layer "F.Fab")
			(hide yes)
			(effects
				(font
					(size 1 1)
					(thickness 0.15)
				)
			)
		)
		(property "Manufacturer" "Bourns"
			(at -5.6 165.15 0)
			(layer "F.Fab")
			(hide yes)
			(effects
				(font
					(size 1 1)
					(thickness 0.15)
				)
			)
		)
		(property "Tolerance" "~"
			(at -5.6 165.15 0)
			(layer "F.Fab")
			(hide yes)
			(effects
				(font
					(size 1 1)
					(thickness 0.15)
				)
			)
		)
		(property "Val" "0R"
			(at -5.6 165.15 0)
			(layer "F.Fab")
			(hide yes)
			(effects
				(font
					(size 1 1)
					(thickness 0.15)
				)
			)
		)
		(sheetname "/Power supply/")
		(sheetfile "power-supply.kicad_sch")
		(attr smd)
		(fp_line
			(start -0.15 0.4)
			(end 0.15 0.4)
			(stroke
				(width 0.15)
				(type solid)
			)
			(layer "F.SilkS")
		)
		(fp_line
			(start -0.15 -0.4)
			(end 0.15 -0.4)
			(stroke
				(width 0.15)
				(type solid)
			)
			(layer "F.SilkS")
		)
		(fp_rect
			(start -1.25 -0.65)
			(end 1.25 0.65)
			(stroke
				(width 0.05)
				(type solid)
			)
			(fill no)
			(layer "F.CrtYd")
		)
		(fp_rect
			(start -0.8 -0.4)
			(end 0.8 0.4)
			(stroke
				(width 0.15)
				(type solid)
			)
			(fill no)
			(layer "F.Fab")
		)
		(pad "1" smd roundrect
			(at -0.7 0 270)
			(size 0.8 1)
			(layers "F.Cu" "F.Mask" "F.Paste")
			(roundrect_rratio 0.2)
			(net 3 "VCC1V35")
			(pintype "passive")
		)
		(pad "2" smd roundrect
			(at 0.7 0 270)
			(size 0.8 1)
			(layers "F.Cu" "F.Mask" "F.Paste")
			(roundrect_rratio 0.2)
			(net 277 "Net-(C82-Pad2)")
			(pintype "passive")
		)
	)
	(footprint "antmicro-footprints:R_0603_1608Metric"
		(layer "F.Cu")
		(at 79.675 92.575 -90)
		(descr "Resistor SMD 0603")
		(tags "resistor SMD 0603")
		(property "Reference" "R140"
			(at 1.025 -0.325 90)
			(layer "F.SilkS")
			(effects
				(font
					(size 0.7 0.7)
					(thickness 0.15)
				)
				(justify right bottom)
			)
		)
		(property "Value" "R_0R_0603"
			(at 0 1.6 90)
			(layer "F.Fab")
			(effects
				(font
					(size 0.7 0.7)
					(thickness 0.15)
				)
				(justify right bottom)
			)
		)
		(property "Datasheet" "https://www.bourns.com/docs/product-datasheets/cr.pdf?sfvrsn=574d41f6_14"
			(at 0 0 270)
			(layer "F.Fab")
			(hide yes)
			(effects
				(font
					(size 1.27 1.27)
					(thickness 0.15)
				)
			)
		)
		(property "Description" "Zero Ohm Resistor, Jumper, 0603 [1608 Metric], Thick Film, 100 mW, 1 A, Surface Mount Device, CR"
			(at 0 0 270)
			(layer "F.Fab")
			(hide yes)
			(effects
				(font
					(size 1.27 1.27)
					(thickness 0.15)
				)
			)
		)
		(property "Author" "Antmicro"
			(at -12.9 172.25 0)
			(layer "F.Fab")
			(hide yes)
			(effects
				(font
					(size 1 1)
					(thickness 0.15)
				)
			)
		)
		(property "Current" "1A"
			(at -12.9 172.25 0)
			(layer "F.Fab")
			(hide yes)
			(effects
				(font
					(size 1 1)
					(thickness 0.15)
				)
			)
		)
		(property "License" "Apache-2.0"
			(at -12.9 172.25 0)
			(layer "F.Fab")
			(hide yes)
			(effects
				(font
					(size 1 1)
					(thickness 0.15)
				)
			)
		)
		(property "MPN" "CR0603-J/-000ELF"
			(at -12.9 172.25 0)
			(layer "F.Fab")
			(hide yes)
			(effects
				(font
					(size 1 1)
					(thickness 0.15)
				)
			)
		)
		(property "Manufacturer" "Bourns"
			(at -12.9 172.25 0)
			(layer "F.Fab")
			(hide yes)
			(effects
				(font
					(size 1 1)
					(thickness 0.15)
				)
			)
		)
		(property "Tolerance" "~"
			(at -12.9 172.25 0)
			(layer "F.Fab")
			(hide yes)
			(effects
				(font
					(size 1 1)
					(thickness 0.15)
				)
			)
		)
		(property "Val" "0R"
			(at -12.9 172.25 0)
			(layer "F.Fab")
			(hide yes)
			(effects
				(font
					(size 1 1)
					(thickness 0.15)
				)
			)
		)
		(sheetname "/Power supply/")
		(sheetfile "power-supply.kicad_sch")
		(attr smd)
		(fp_line
			(start -0.15 0.4)
			(end 0.15 0.4)
			(stroke
				(width 0.15)
				(type solid)
			)
			(layer "F.SilkS")
		)
		(fp_line
			(start -0.15 -0.4)
			(end 0.15 -0.4)
			(stroke
				(width 0.15)
				(type solid)
			)
			(layer "F.SilkS")
		)
		(fp_rect
			(start -1.25 -0.65)
			(end 1.25 0.65)
			(stroke
				(width 0.05)
				(type solid)
			)
			(fill no)
			(layer "F.CrtYd")
		)
		(fp_rect
			(start -0.8 -0.4)
			(end 0.8 0.4)
			(stroke
				(width 0.15)
				(type solid)
			)
			(fill no)
			(layer "F.Fab")
		)
		(pad "1" smd roundrect
			(at -0.7 0 270)
			(size 0.8 1)
			(layers "F.Cu" "F.Mask" "F.Paste")
			(roundrect_rratio 0.2)
			(net 5 "VCC1V8")
			(pintype "passive")
		)
		(pad "2" smd roundrect
			(at 0.7 0 270)
			(size 0.8 1)
			(layers "F.Cu" "F.Mask" "F.Paste")
			(roundrect_rratio 0.2)
			(net 275 "Net-(C80-Pad2)")
			(pintype "passive")
		)
	)
	(footprint "antmicro-footprints:C_1210_3225Metric"
		(layer "F.Cu")
		(at 76.399 84.5)
		(descr "Capacitor SMD 1210")
		(tags "capacitor SMD 1210")
		(property "Reference" "C151"
			(at -2.299 1.4 90)
			(layer "F.SilkS")
			(effects
				(font
					(size 0.7 0.7)
					(thickness 0.15)
				)
				(justify left bottom)
			)
		)
		(property "Value" "C_100u_1210"
			(at 0 2.749 0)
			(layer "F.Fab")
			(effects
				(font
					(size 0.7 0.7)
					(thickness 0.15)
				)
				(justify left bottom)
			)
		)
		(property "Datasheet" "https://product.samsungsem.com/mlcc/CL32A107MQVNNN.do"
			(at 0 0 0)
			(layer "F.Fab")
			(hide yes)
			(effects
				(font
					(size 1.27 1.27)
					(thickness 0.15)
				)
			)
		)
		(property "Description" "SMD Multilayer Ceramic Capacitor, 100 µF, 6.3 V, 1210 [3225 Metric], ± 20%, X5R, CL"
			(at 0 0 0)
			(layer "F.Fab")
			(hide yes)
			(effects
				(font
					(size 1.27 1.27)
					(thickness 0.15)
				)
			)
		)
		(property "Author" "Antmicro"
			(at 0 0 0)
			(layer "F.Fab")
			(hide yes)
			(effects
				(font
					(size 1 1)
					(thickness 0.15)
				)
			)
		)
		(property "Dielectric" ""
			(at 0 0 0)
			(layer "F.Fab")
			(hide yes)
			(effects
				(font
					(size 1 1)
					(thickness 0.15)
				)
			)
		)
		(property "License" "Apache-2.0"
			(at 0 0 0)
			(layer "F.Fab")
			(hide yes)
			(effects
				(font
					(size 1 1)
					(thickness 0.15)
				)
			)
		)
		(property "MPN" "CL32A107MQVNNNE"
			(at 0 0 0)
			(layer "F.Fab")
			(hide yes)
			(effects
				(font
					(size 1 1)
					(thickness 0.15)
				)
			)
		)
		(property "Manufacturer" "Samsung Electro-Mechanics"
			(at 0 0 0)
			(layer "F.Fab")
			(hide yes)
			(effects
				(font
					(size 1 1)
					(thickness 0.15)
				)
			)
		)
		(property "Public" "False"
			(at 0 0 0)
			(layer "F.Fab")
			(hide yes)
			(effects
				(font
					(size 1 1)
					(thickness 0.15)
				)
			)
		)
		(property "Val" "100u"
			(at 0 0 0)
			(layer "F.Fab")
			(hide yes)
			(effects
				(font
					(size 1 1)
					(thickness 0.15)
				)
			)
		)
		(property "Voltage" ""
			(at 0 0 0)
			(layer "F.Fab")
			(hide yes)
			(effects
				(font
					(size 1 1)
					(thickness 0.15)
				)
			)
		)
		(property "DNP" ""
			(at 0 0 0)
			(unlocked yes)
			(layer "F.Fab")
			(hide yes)
			(effects
				(font
					(size 1 1)
					(thickness 0.15)
				)
			)
		)
		(sheetname "/FPGA power supply/")
		(sheetfile "fpga-power-supply.kicad_sch")
		(attr smd)
		(fp_line
			(start -0.3 -1.39)
			(end 0.3 -1.39)
			(stroke
				(width 0.15)
				(type solid)
			)
			(layer "F.SilkS")
		)
		(fp_line
			(start -0.3 1.39)
			(end 0.3 1.39)
			(stroke
				(width 0.15)
				(type solid)
			)
			(layer "F.SilkS")
		)
		(fp_rect
			(start -2.1 -1.75)
			(end 2.1 1.75)
			(stroke
				(width 0.05)
				(type solid)
			)
			(fill no)
			(layer "F.CrtYd")
		)
		(fp_rect
			(start -1.6 -1.25)
			(end 1.6 1.25)
			(stroke
				(width 0.15)
				(type solid)
			)
			(fill no)
			(layer "F.Fab")
		)
		(pad "1" smd rect
			(at -1.145 0)
			(size 1.52 3.05)
			(layers "F.Cu" "F.Mask" "F.Paste")
			(net 1 "GND")
			(pintype "passive")
		)
		(pad "2" smd rect
			(at 1.145 0)
			(size 1.52 3.05)
			(layers "F.Cu" "F.Mask" "F.Paste")
			(net 6 "VCC1V0")
			(pintype "passive")
		)
	)
	(footprint "antmicro-footprints:LED_0603_1608Metric_G"
		(layer "F.Cu")
		(at 75.719 91.899 180)
		(descr "LED SMD 0603 Green")
		(tags "LED SMD 0603 Green")
		(property "Reference" "D4"
			(at -2.781 -0.401 0)
			(layer "F.SilkS")
			(effects
				(font
					(size 0.7 0.7)
					(thickness 0.15)
				)
				(justify right bottom)
			)
		)
		(property "Value" "LED_G_0603_LG_L29K-G2J1-24-Z"
			(at 0 1.6 0)
			(layer "F.Fab")
			(effects
				(font
					(size 0.7 0.7)
					(thickness 0.15)
				)
				(justify right bottom)
			)
		)
		(property "Datasheet" "https://look.ams-osram.com/m/19ee86b3ae0ee95b/original/LG-L29K.pdf"
			(at 0 0 180)
			(layer "F.Fab")
			(hide yes)
			(effects
				(font
					(size 1.27 1.27)
					(thickness 0.15)
				)
			)
		)
		(property "Description" "LED, Green, SMD, 0603, 20 mA, 1.7 V, 570 nm"
			(at 0 0 180)
			(layer "F.Fab")
			(hide yes)
			(effects
				(font
					(size 1.27 1.27)
					(thickness 0.15)
				)
			)
		)
		(property "Author" "Antmicro"
			(at 151.438 183.798 0)
			(layer "F.Fab")
			(hide yes)
			(effects
				(font
					(size 1 1)
					(thickness 0.15)
				)
			)
		)
		(property "Color" "Green"
			(at 151.438 183.798 0)
			(layer "F.Fab")
			(hide yes)
			(effects
				(font
					(size 1 1)
					(thickness 0.15)
				)
			)
		)
		(property "License" "Apache-2.0"
			(at 151.438 183.798 0)
			(layer "F.Fab")
			(hide yes)
			(effects
				(font
					(size 1 1)
					(thickness 0.15)
				)
			)
		)
		(property "MPN" "LG L29K-G2J1-24-Z"
			(at 151.438 183.798 0)
			(layer "F.Fab")
			(hide yes)
			(effects
				(font
					(size 1 1)
					(thickness 0.15)
				)
			)
		)
		(property "Manufacturer" "OSRAM"
			(at 151.438 183.798 0)
			(layer "F.Fab")
			(hide yes)
			(effects
				(font
					(size 1 1)
					(thickness 0.15)
				)
			)
		)
		(sheetname "/Power supply/")
		(sheetfile "power-supply.kicad_sch")
		(attr smd)
		(fp_line
			(start 0.22 0.35)
			(end -0.22 0.35)
			(stroke
				(width 0.15)
				(type solid)
			)
			(layer "F.SilkS")
		)
		(fp_line
			(start 0.22 -0.35)
			(end -0.22 -0.35)
			(stroke
				(width 0.15)
				(type solid)
			)
			(layer "F.SilkS")
		)
		(fp_line
			(start 0.105328 0.201008)
			(end 0.105328 -0.198992)
			(stroke
				(width 0.1)
				(type solid)
			)
			(layer "F.SilkS")
		)
		(fp_line
			(start 0.105328 0.201008)
			(end -0.094672 0.001008)
			(stroke
				(width 0.1)
				(type solid)
			)
			(layer "F.SilkS")
		)
		(fp_line
			(start 0.105328 0.001008)
			(end 0.24 0.001)
			(stroke
				(width 0.1)
				(type solid)
			)
			(layer "F.SilkS")
		)
		(fp_line
			(start -0.094672 0.201008)
			(end -0.094672 -0.198992)
			(stroke
				(width 0.1)
				(type solid)
			)
			(layer "F.SilkS")
		)
		(fp_line
			(start -0.094672 0.001008)
			(end 0.105328 -0.198992)
			(stroke
				(width 0.1)
				(type solid)
			)
			(layer "F.SilkS")
		)
		(fp_line
			(start -0.094672 0.001008)
			(end -0.24 0.001008)
			(stroke
				(width 0.1)
				(type solid)
			)
			(layer "F.SilkS")
		)
		(fp_line
			(start -1.18 -0.319)
			(end -1.18 0.321)
			(stroke
				(width 0.15)
				(type solid)
			)
			(layer "F.SilkS")
		)
		(fp_rect
			(start 1.25 0.65)
			(end -1.25 -0.65)
			(stroke
				(width 0.05)
				(type solid)
			)
			(fill no)
			(layer "F.CrtYd")
		)
		(fp_line
			(start 0.599 0)
			(end 0.201 0)
			(stroke
				(width 0.15)
				(type solid)
			)
			(layer "F.Fab")
		)
		(fp_line
			(start 0.201 0.2)
			(end 0.201 0)
			(stroke
				(width 0.15)
				(type solid)
			)
			(layer "F.Fab")
		)
		(fp_line
			(start 0.201 0)
			(end 0.201 -0.202)
			(stroke
				(width 0.15)
				(type solid)
			)
			(layer "F.Fab")
		)
		(fp_line
			(start 0.201 -0.202)
			(end -0.101 0)
			(stroke
				(width 0.15)
				(type solid)
			)
			(layer "F.Fab")
		)
		(fp_line
			(start -0.101 0)
			(end 0.201 0.2)
			(stroke
				(width 0.15)
				(type solid)
			)
			(layer "F.Fab")
		)
		(fp_line
			(start -0.199 0.2)
			(end -0.199 0.1)
			(stroke
				(width 0.15)
				(type solid)
			)
			(layer "F.Fab")
		)
		(fp_line
			(start -0.199 0)
			(end -0.597 0)
			(stroke
				(width 0.15)
				(type solid)
			)
			(layer "F.Fab")
		)
		(fp_line
			(start -0.199 -0.202)
			(end -0.199 0.1)
			(stroke
				(width 0.15)
				(type solid)
			)
			(layer "F.Fab")
		)
		(fp_rect
			(start 0.848 0.4)
			(end -0.85 -0.402)
			(stroke
				(width 0.15)
				(type solid)
			)
			(fill no)
			(layer "F.Fab")
		)
		(pad "1" smd roundrect
			(at -0.7 0)
			(size 0.8 1)
			(layers "F.Cu" "F.Mask" "F.Paste")
			(roundrect_rratio 0.2)
			(net 207 "Net-(D4-C)")
			(pinfunction "C")
			(pintype "passive")
		)
		(pad "2" smd roundrect
			(at 0.7 0)
			(size 0.8 1)
			(layers "F.Cu" "F.Mask" "F.Paste")
			(roundrect_rratio 0.2)
			(net 208 "Net-(D4-A)")
			(pinfunction "A")
			(pintype "passive")
		)
	)
	(footprint "antmicro-footprints:LED_0603_1608Metric_G"
		(layer "F.Cu")
		(at 75.719 89.867 180)
		(descr "LED SMD 0603 Green")
		(tags "LED SMD 0603 Green")
		(property "Reference" "D5"
			(at -2.781 -0.433 0)
			(layer "F.SilkS")
			(effects
				(font
					(size 0.7 0.7)
					(thickness 0.15)
				)
				(justify right bottom)
			)
		)
		(property "Value" "LED_G_0603_LG_L29K-G2J1-24-Z"
			(at 0 1.6 0)
			(layer "F.Fab")
			(effects
				(font
					(size 0.7 0.7)
					(thickness 0.15)
				)
				(justify right bottom)
			)
		)
		(property "Datasheet" "https://look.ams-osram.com/m/19ee86b3ae0ee95b/original/LG-L29K.pdf"
			(at 0 0 180)
			(layer "F.Fab")
			(hide yes)
			(effects
				(font
					(size 1.27 1.27)
					(thickness 0.15)
				)
			)
		)
		(property "Description" "LED, Green, SMD, 0603, 20 mA, 1.7 V, 570 nm"
			(at 0 0 180)
			(layer "F.Fab")
			(hide yes)
			(effects
				(font
					(size 1.27 1.27)
					(thickness 0.15)
				)
			)
		)
		(property "Author" "Antmicro"
			(at 151.438 179.734 0)
			(layer "F.Fab")
			(hide yes)
			(effects
				(font
					(size 1 1)
					(thickness 0.15)
				)
			)
		)
		(property "Color" "Green"
			(at 151.438 179.734 0)
			(layer "F.Fab")
			(hide yes)
			(effects
				(font
					(size 1 1)
					(thickness 0.15)
				)
			)
		)
		(property "License" "Apache-2.0"
			(at 151.438 179.734 0)
			(layer "F.Fab")
			(hide yes)
			(effects
				(font
					(size 1 1)
					(thickness 0.15)
				)
			)
		)
		(property "MPN" "LG L29K-G2J1-24-Z"
			(at 151.438 179.734 0)
			(layer "F.Fab")
			(hide yes)
			(effects
				(font
					(size 1 1)
					(thickness 0.15)
				)
			)
		)
		(property "Manufacturer" "OSRAM"
			(at 151.438 179.734 0)
			(layer "F.Fab")
			(hide yes)
			(effects
				(font
					(size 1 1)
					(thickness 0.15)
				)
			)
		)
		(sheetname "/Power supply/")
		(sheetfile "power-supply.kicad_sch")
		(attr smd)
		(fp_line
			(start 0.22 0.35)
			(end -0.22 0.35)
			(stroke
				(width 0.15)
				(type solid)
			)
			(layer "F.SilkS")
		)
		(fp_line
			(start 0.22 -0.35)
			(end -0.22 -0.35)
			(stroke
				(width 0.15)
				(type solid)
			)
			(layer "F.SilkS")
		)
		(fp_line
			(start 0.105328 0.201008)
			(end 0.105328 -0.198992)
			(stroke
				(width 0.1)
				(type solid)
			)
			(layer "F.SilkS")
		)
		(fp_line
			(start 0.105328 0.201008)
			(end -0.094672 0.001008)
			(stroke
				(width 0.1)
				(type solid)
			)
			(layer "F.SilkS")
		)
		(fp_line
			(start 0.105328 0.001008)
			(end 0.24 0.001)
			(stroke
				(width 0.1)
				(type solid)
			)
			(layer "F.SilkS")
		)
		(fp_line
			(start -0.094672 0.201008)
			(end -0.094672 -0.198992)
			(stroke
				(width 0.1)
				(type solid)
			)
			(layer "F.SilkS")
		)
		(fp_line
			(start -0.094672 0.001008)
			(end 0.105328 -0.198992)
			(stroke
				(width 0.1)
				(type solid)
			)
			(layer "F.SilkS")
		)
		(fp_line
			(start -0.094672 0.001008)
			(end -0.24 0.001008)
			(stroke
				(width 0.1)
				(type solid)
			)
			(layer "F.SilkS")
		)
		(fp_line
			(start -1.18 -0.319)
			(end -1.18 0.321)
			(stroke
				(width 0.15)
				(type solid)
			)
			(layer "F.SilkS")
		)
		(fp_rect
			(start 1.25 0.65)
			(end -1.25 -0.65)
			(stroke
				(width 0.05)
				(type solid)
			)
			(fill no)
			(layer "F.CrtYd")
		)
		(fp_line
			(start 0.599 0)
			(end 0.201 0)
			(stroke
				(width 0.15)
				(type solid)
			)
			(layer "F.Fab")
		)
		(fp_line
			(start 0.201 0.2)
			(end 0.201 0)
			(stroke
				(width 0.15)
				(type solid)
			)
			(layer "F.Fab")
		)
		(fp_line
			(start 0.201 0)
			(end 0.201 -0.202)
			(stroke
				(width 0.15)
				(type solid)
			)
			(layer "F.Fab")
		)
		(fp_line
			(start 0.201 -0.202)
			(end -0.101 0)
			(stroke
				(width 0.15)
				(type solid)
			)
			(layer "F.Fab")
		)
		(fp_line
			(start -0.101 0)
			(end 0.201 0.2)
			(stroke
				(width 0.15)
				(type solid)
			)
			(layer "F.Fab")
		)
		(fp_line
			(start -0.199 0.2)
			(end -0.199 0.1)
			(stroke
				(width 0.15)
				(type solid)
			)
			(layer "F.Fab")
		)
		(fp_line
			(start -0.199 0)
			(end -0.597 0)
			(stroke
				(width 0.15)
				(type solid)
			)
			(layer "F.Fab")
		)
		(fp_line
			(start -0.199 -0.202)
			(end -0.199 0.1)
			(stroke
				(width 0.15)
				(type solid)
			)
			(layer "F.Fab")
		)
		(fp_rect
			(start 0.848 0.4)
			(end -0.85 -0.402)
			(stroke
				(width 0.15)
				(type solid)
			)
			(fill no)
			(layer "F.Fab")
		)
		(pad "1" smd roundrect
			(at -0.7 0)
			(size 0.8 1)
			(layers "F.Cu" "F.Mask" "F.Paste")
			(roundrect_rratio 0.2)
			(net 214 "Net-(D5-C)")
			(pinfunction "C")
			(pintype "passive")
		)
		(pad "2" smd roundrect
			(at 0.7 0)
			(size 0.8 1)
			(layers "F.Cu" "F.Mask" "F.Paste")
			(roundrect_rratio 0.2)
			(net 215 "Net-(D5-A)")
			(pinfunction "A")
			(pintype "passive")
		)
	)
	(footprint "antmicro-footprints:LED_0603_1608Metric_G"
		(layer "F.Cu")
		(at 75.719 95.963 180)
		(descr "LED SMD 0603 Green")
		(tags "LED SMD 0603 Green")
		(property "Reference" "D6"
			(at -2.781 -0.437 0)
			(layer "F.SilkS")
			(effects
				(font
					(size 0.7 0.7)
					(thickness 0.15)
				)
				(justify right bottom)
			)
		)
		(property "Value" "LED_G_0603_LG_L29K-G2J1-24-Z"
			(at 0 1.6 0)
			(layer "F.Fab")
			(effects
				(font
					(size 0.7 0.7)
					(thickness 0.15)
				)
				(justify right bottom)
			)
		)
		(property "Datasheet" "https://look.ams-osram.com/m/19ee86b3ae0ee95b/original/LG-L29K.pdf"
			(at 0 0 180)
			(layer "F.Fab")
			(hide yes)
			(effects
				(font
					(size 1.27 1.27)
					(thickness 0.15)
				)
			)
		)
		(property "Description" "LED, Green, SMD, 0603, 20 mA, 1.7 V, 570 nm"
			(at 0 0 180)
			(layer "F.Fab")
			(hide yes)
			(effects
				(font
					(size 1.27 1.27)
					(thickness 0.15)
				)
			)
		)
		(property "Author" "Antmicro"
			(at 151.438 191.926 0)
			(layer "F.Fab")
			(hide yes)
			(effects
				(font
					(size 1 1)
					(thickness 0.15)
				)
			)
		)
		(property "Color" "Green"
			(at 151.438 191.926 0)
			(layer "F.Fab")
			(hide yes)
			(effects
				(font
					(size 1 1)
					(thickness 0.15)
				)
			)
		)
		(property "License" "Apache-2.0"
			(at 151.438 191.926 0)
			(layer "F.Fab")
			(hide yes)
			(effects
				(font
					(size 1 1)
					(thickness 0.15)
				)
			)
		)
		(property "MPN" "LG L29K-G2J1-24-Z"
			(at 151.438 191.926 0)
			(layer "F.Fab")
			(hide yes)
			(effects
				(font
					(size 1 1)
					(thickness 0.15)
				)
			)
		)
		(property "Manufacturer" "OSRAM"
			(at 151.438 191.926 0)
			(layer "F.Fab")
			(hide yes)
			(effects
				(font
					(size 1 1)
					(thickness 0.15)
				)
			)
		)
		(sheetname "/Power supply/")
		(sheetfile "power-supply.kicad_sch")
		(attr smd)
		(fp_line
			(start 0.22 0.35)
			(end -0.22 0.35)
			(stroke
				(width 0.15)
				(type solid)
			)
			(layer "F.SilkS")
		)
		(fp_line
			(start 0.22 -0.35)
			(end -0.22 -0.35)
			(stroke
				(width 0.15)
				(type solid)
			)
			(layer "F.SilkS")
		)
		(fp_line
			(start 0.105328 0.201008)
			(end 0.105328 -0.198992)
			(stroke
				(width 0.1)
				(type solid)
			)
			(layer "F.SilkS")
		)
		(fp_line
			(start 0.105328 0.201008)
			(end -0.094672 0.001008)
			(stroke
				(width 0.1)
				(type solid)
			)
			(layer "F.SilkS")
		)
		(fp_line
			(start 0.105328 0.001008)
			(end 0.24 0.001)
			(stroke
				(width 0.1)
				(type solid)
			)
			(layer "F.SilkS")
		)
		(fp_line
			(start -0.094672 0.201008)
			(end -0.094672 -0.198992)
			(stroke
				(width 0.1)
				(type solid)
			)
			(layer "F.SilkS")
		)
		(fp_line
			(start -0.094672 0.001008)
			(end 0.105328 -0.198992)
			(stroke
				(width 0.1)
				(type solid)
			)
			(layer "F.SilkS")
		)
		(fp_line
			(start -0.094672 0.001008)
			(end -0.24 0.001008)
			(stroke
				(width 0.1)
				(type solid)
			)
			(layer "F.SilkS")
		)
		(fp_line
			(start -1.18 -0.319)
			(end -1.18 0.321)
			(stroke
				(width 0.15)
				(type solid)
			)
			(layer "F.SilkS")
		)
		(fp_rect
			(start 1.25 0.65)
			(end -1.25 -0.65)
			(stroke
				(width 0.05)
				(type solid)
			)
			(fill no)
			(layer "F.CrtYd")
		)
		(fp_line
			(start 0.599 0)
			(end 0.201 0)
			(stroke
				(width 0.15)
				(type solid)
			)
			(layer "F.Fab")
		)
		(fp_line
			(start 0.201 0.2)
			(end 0.201 0)
			(stroke
				(width 0.15)
				(type solid)
			)
			(layer "F.Fab")
		)
		(fp_line
			(start 0.201 0)
			(end 0.201 -0.202)
			(stroke
				(width 0.15)
				(type solid)
			)
			(layer "F.Fab")
		)
		(fp_line
			(start 0.201 -0.202)
			(end -0.101 0)
			(stroke
				(width 0.15)
				(type solid)
			)
			(layer "F.Fab")
		)
		(fp_line
			(start -0.101 0)
			(end 0.201 0.2)
			(stroke
				(width 0.15)
				(type solid)
			)
			(layer "F.Fab")
		)
		(fp_line
			(start -0.199 0.2)
			(end -0.199 0.1)
			(stroke
				(width 0.15)
				(type solid)
			)
			(layer "F.Fab")
		)
		(fp_line
			(start -0.199 0)
			(end -0.597 0)
			(stroke
				(width 0.15)
				(type solid)
			)
			(layer "F.Fab")
		)
		(fp_line
			(start -0.199 -0.202)
			(end -0.199 0.1)
			(stroke
				(width 0.15)
				(type solid)
			)
			(layer "F.Fab")
		)
		(fp_rect
			(start 0.848 0.4)
			(end -0.85 -0.402)
			(stroke
				(width 0.15)
				(type solid)
			)
			(fill no)
			(layer "F.Fab")
		)
		(pad "1" smd roundrect
			(at -0.7 0)
			(size 0.8 1)
			(layers "F.Cu" "F.Mask" "F.Paste")
			(roundrect_rratio 0.2)
			(net 216 "Net-(D6-C)")
			(pinfunction "C")
			(pintype "passive")
		)
		(pad "2" smd roundrect
			(at 0.7 0)
			(size 0.8 1)
			(layers "F.Cu" "F.Mask" "F.Paste")
			(roundrect_rratio 0.2)
			(net 217 "Net-(D6-A)")
			(pinfunction "A")
			(pintype "passive")
		)
	)
	(footprint "antmicro-footprints:LED_0603_1608Metric_G"
		(layer "F.Cu")
		(at 75.719 93.931 180)
		(descr "LED SMD 0603 Green")
		(tags "LED SMD 0603 Green")
		(property "Reference" "D7"
			(at -2.781 -0.469 0)
			(layer "F.SilkS")
			(effects
				(font
					(size 0.7 0.7)
					(thickness 0.15)
				)
				(justify right bottom)
			)
		)
		(property "Value" "LED_G_0603_LG_L29K-G2J1-24-Z"
			(at 0 1.6 0)
			(layer "F.Fab")
			(effects
				(font
					(size 0.7 0.7)
					(thickness 0.15)
				)
				(justify right bottom)
			)
		)
		(property "Datasheet" "https://look.ams-osram.com/m/19ee86b3ae0ee95b/original/LG-L29K.pdf"
			(at 0 0 180)
			(layer "F.Fab")
			(hide yes)
			(effects
				(font
					(size 1.27 1.27)
					(thickness 0.15)
				)
			)
		)
		(property "Description" "LED, Green, SMD, 0603, 20 mA, 1.7 V, 570 nm"
			(at 0 0 180)
			(layer "F.Fab")
			(hide yes)
			(effects
				(font
					(size 1.27 1.27)
					(thickness 0.15)
				)
			)
		)
		(property "Author" "Antmicro"
			(at 151.438 187.862 0)
			(layer "F.Fab")
			(hide yes)
			(effects
				(font
					(size 1 1)
					(thickness 0.15)
				)
			)
		)
		(property "Color" "Green"
			(at 151.438 187.862 0)
			(layer "F.Fab")
			(hide yes)
			(effects
				(font
					(size 1 1)
					(thickness 0.15)
				)
			)
		)
		(property "License" "Apache-2.0"
			(at 151.438 187.862 0)
			(layer "F.Fab")
			(hide yes)
			(effects
				(font
					(size 1 1)
					(thickness 0.15)
				)
			)
		)
		(property "MPN" "LG L29K-G2J1-24-Z"
			(at 151.438 187.862 0)
			(layer "F.Fab")
			(hide yes)
			(effects
				(font
					(size 1 1)
					(thickness 0.15)
				)
			)
		)
		(property "Manufacturer" "OSRAM"
			(at 151.438 187.862 0)
			(layer "F.Fab")
			(hide yes)
			(effects
				(font
					(size 1 1)
					(thickness 0.15)
				)
			)
		)
		(sheetname "/Power supply/")
		(sheetfile "power-supply.kicad_sch")
		(attr smd)
		(fp_line
			(start 0.22 0.35)
			(end -0.22 0.35)
			(stroke
				(width 0.15)
				(type solid)
			)
			(layer "F.SilkS")
		)
		(fp_line
			(start 0.22 -0.35)
			(end -0.22 -0.35)
			(stroke
				(width 0.15)
				(type solid)
			)
			(layer "F.SilkS")
		)
		(fp_line
			(start 0.105328 0.201008)
			(end 0.105328 -0.198992)
			(stroke
				(width 0.1)
				(type solid)
			)
			(layer "F.SilkS")
		)
		(fp_line
			(start 0.105328 0.201008)
			(end -0.094672 0.001008)
			(stroke
				(width 0.1)
				(type solid)
			)
			(layer "F.SilkS")
		)
		(fp_line
			(start 0.105328 0.001008)
			(end 0.24 0.001)
			(stroke
				(width 0.1)
				(type solid)
			)
			(layer "F.SilkS")
		)
		(fp_line
			(start -0.094672 0.201008)
			(end -0.094672 -0.198992)
			(stroke
				(width 0.1)
				(type solid)
			)
			(layer "F.SilkS")
		)
		(fp_line
			(start -0.094672 0.001008)
			(end 0.105328 -0.198992)
			(stroke
				(width 0.1)
				(type solid)
			)
			(layer "F.SilkS")
		)
		(fp_line
			(start -0.094672 0.001008)
			(end -0.24 0.001008)
			(stroke
				(width 0.1)
				(type solid)
			)
			(layer "F.SilkS")
		)
		(fp_line
			(start -1.18 -0.319)
			(end -1.18 0.321)
			(stroke
				(width 0.15)
				(type solid)
			)
			(layer "F.SilkS")
		)
		(fp_rect
			(start 1.25 0.65)
			(end -1.25 -0.65)
			(stroke
				(width 0.05)
				(type solid)
			)
			(fill no)
			(layer "F.CrtYd")
		)
		(fp_line
			(start 0.599 0)
			(end 0.201 0)
			(stroke
				(width 0.15)
				(type solid)
			)
			(layer "F.Fab")
		)
		(fp_line
			(start 0.201 0.2)
			(end 0.201 0)
			(stroke
				(width 0.15)
				(type solid)
			)
			(layer "F.Fab")
		)
		(fp_line
			(start 0.201 0)
			(end 0.201 -0.202)
			(stroke
				(width 0.15)
				(type solid)
			)
			(layer "F.Fab")
		)
		(fp_line
			(start 0.201 -0.202)
			(end -0.101 0)
			(stroke
				(width 0.15)
				(type solid)
			)
			(layer "F.Fab")
		)
		(fp_line
			(start -0.101 0)
			(end 0.201 0.2)
			(stroke
				(width 0.15)
				(type solid)
			)
			(layer "F.Fab")
		)
		(fp_line
			(start -0.199 0.2)
			(end -0.199 0.1)
			(stroke
				(width 0.15)
				(type solid)
			)
			(layer "F.Fab")
		)
		(fp_line
			(start -0.199 0)
			(end -0.597 0)
			(stroke
				(width 0.15)
				(type solid)
			)
			(layer "F.Fab")
		)
		(fp_line
			(start -0.199 -0.202)
			(end -0.199 0.1)
			(stroke
				(width 0.15)
				(type solid)
			)
			(layer "F.Fab")
		)
		(fp_rect
			(start 0.848 0.4)
			(end -0.85 -0.402)
			(stroke
				(width 0.15)
				(type solid)
			)
			(fill no)
			(layer "F.Fab")
		)
		(pad "1" smd roundrect
			(at -0.7 0)
			(size 0.8 1)
			(layers "F.Cu" "F.Mask" "F.Paste")
			(roundrect_rratio 0.2)
			(net 218 "Net-(D7-C)")
			(pinfunction "C")
			(pintype "passive")
		)
		(pad "2" smd roundrect
			(at 0.7 0)
			(size 0.8 1)
			(layers "F.Cu" "F.Mask" "F.Paste")
			(roundrect_rratio 0.2)
			(net 219 "Net-(D7-A)")
			(pinfunction "A")
			(pintype "passive")
		)
	)
	(footprint "antmicro-footprints:LED_0603_1608Metric_G"
		(layer "F.Cu")
		(at 75.719 97.995 180)
		(descr "LED SMD 0603 Green")
		(tags "LED SMD 0603 Green")
		(property "Reference" "D8"
			(at -2.781 -0.405 0)
			(layer "F.SilkS")
			(effects
				(font
					(size 0.7 0.7)
					(thickness 0.15)
				)
				(justify right bottom)
			)
		)
		(property "Value" "LED_G_0603_LG_L29K-G2J1-24-Z"
			(at 0 1.6 0)
			(layer "F.Fab")
			(effects
				(font
					(size 0.7 0.7)
					(thickness 0.15)
				)
				(justify right bottom)
			)
		)
		(property "Datasheet" "https://look.ams-osram.com/m/19ee86b3ae0ee95b/original/LG-L29K.pdf"
			(at 0 0 180)
			(layer "F.Fab")
			(hide yes)
			(effects
				(font
					(size 1.27 1.27)
					(thickness 0.15)
				)
			)
		)
		(property "Description" "LED, Green, SMD, 0603, 20 mA, 1.7 V, 570 nm"
			(at 0 0 180)
			(layer "F.Fab")
			(hide yes)
			(effects
				(font
					(size 1.27 1.27)
					(thickness 0.15)
				)
			)
		)
		(property "Author" "Antmicro"
			(at 151.438 195.99 0)
			(layer "F.Fab")
			(hide yes)
			(effects
				(font
					(size 1 1)
					(thickness 0.15)
				)
			)
		)
		(property "Color" "Green"
			(at 151.438 195.99 0)
			(layer "F.Fab")
			(hide yes)
			(effects
				(font
					(size 1 1)
					(thickness 0.15)
				)
			)
		)
		(property "License" "Apache-2.0"
			(at 151.438 195.99 0)
			(layer "F.Fab")
			(hide yes)
			(effects
				(font
					(size 1 1)
					(thickness 0.15)
				)
			)
		)
		(property "MPN" "LG L29K-G2J1-24-Z"
			(at 151.438 195.99 0)
			(layer "F.Fab")
			(hide yes)
			(effects
				(font
					(size 1 1)
					(thickness 0.15)
				)
			)
		)
		(property "Manufacturer" "OSRAM"
			(at 151.438 195.99 0)
			(layer "F.Fab")
			(hide yes)
			(effects
				(font
					(size 1 1)
					(thickness 0.15)
				)
			)
		)
		(sheetname "/Power supply/")
		(sheetfile "power-supply.kicad_sch")
		(attr smd)
		(fp_line
			(start 0.22 0.35)
			(end -0.22 0.35)
			(stroke
				(width 0.15)
				(type solid)
			)
			(layer "F.SilkS")
		)
		(fp_line
			(start 0.22 -0.35)
			(end -0.22 -0.35)
			(stroke
				(width 0.15)
				(type solid)
			)
			(layer "F.SilkS")
		)
		(fp_line
			(start 0.105328 0.201008)
			(end 0.105328 -0.198992)
			(stroke
				(width 0.1)
				(type solid)
			)
			(layer "F.SilkS")
		)
		(fp_line
			(start 0.105328 0.201008)
			(end -0.094672 0.001008)
			(stroke
				(width 0.1)
				(type solid)
			)
			(layer "F.SilkS")
		)
		(fp_line
			(start 0.105328 0.001008)
			(end 0.24 0.001)
			(stroke
				(width 0.1)
				(type solid)
			)
			(layer "F.SilkS")
		)
		(fp_line
			(start -0.094672 0.201008)
			(end -0.094672 -0.198992)
			(stroke
				(width 0.1)
				(type solid)
			)
			(layer "F.SilkS")
		)
		(fp_line
			(start -0.094672 0.001008)
			(end 0.105328 -0.198992)
			(stroke
				(width 0.1)
				(type solid)
			)
			(layer "F.SilkS")
		)
		(fp_line
			(start -0.094672 0.001008)
			(end -0.24 0.001008)
			(stroke
				(width 0.1)
				(type solid)
			)
			(layer "F.SilkS")
		)
		(fp_line
			(start -1.18 -0.319)
			(end -1.18 0.321)
			(stroke
				(width 0.15)
				(type solid)
			)
			(layer "F.SilkS")
		)
		(fp_rect
			(start 1.25 0.65)
			(end -1.25 -0.65)
			(stroke
				(width 0.05)
				(type solid)
			)
			(fill no)
			(layer "F.CrtYd")
		)
		(fp_line
			(start 0.599 0)
			(end 0.201 0)
			(stroke
				(width 0.15)
				(type solid)
			)
			(layer "F.Fab")
		)
		(fp_line
			(start 0.201 0.2)
			(end 0.201 0)
			(stroke
				(width 0.15)
				(type solid)
			)
			(layer "F.Fab")
		)
		(fp_line
			(start 0.201 0)
			(end 0.201 -0.202)
			(stroke
				(width 0.15)
				(type solid)
			)
			(layer "F.Fab")
		)
		(fp_line
			(start 0.201 -0.202)
			(end -0.101 0)
			(stroke
				(width 0.15)
				(type solid)
			)
			(layer "F.Fab")
		)
		(fp_line
			(start -0.101 0)
			(end 0.201 0.2)
			(stroke
				(width 0.15)
				(type solid)
			)
			(layer "F.Fab")
		)
		(fp_line
			(start -0.199 0.2)
			(end -0.199 0.1)
			(stroke
				(width 0.15)
				(type solid)
			)
			(layer "F.Fab")
		)
		(fp_line
			(start -0.199 0)
			(end -0.597 0)
			(stroke
				(width 0.15)
				(type solid)
			)
			(layer "F.Fab")
		)
		(fp_line
			(start -0.199 -0.202)
			(end -0.199 0.1)
			(stroke
				(width 0.15)
				(type solid)
			)
			(layer "F.Fab")
		)
		(fp_rect
			(start 0.848 0.4)
			(end -0.85 -0.402)
			(stroke
				(width 0.15)
				(type solid)
			)
			(fill no)
			(layer "F.Fab")
		)
		(pad "1" smd roundrect
			(at -0.7 0)
			(size 0.8 1)
			(layers "F.Cu" "F.Mask" "F.Paste")
			(roundrect_rratio 0.2)
			(net 223 "Net-(D8-C)")
			(pinfunction "C")
			(pintype "passive")
		)
		(pad "2" smd roundrect
			(at 0.7 0)
			(size 0.8 1)
			(layers "F.Cu" "F.Mask" "F.Paste")
			(roundrect_rratio 0.2)
			(net 224 "Net-(D8-A)")
			(pinfunction "A")
			(pintype "passive")
		)
	)
	(footprint "antmicro-footprints:R_0402_1005Metric"
		(layer "F.Cu")
		(at 73.15 89.9 180)
		(descr "Resistor SMD 0402")
		(tags "resistor SMD 0402")
		(property "Reference" "R95"
			(at -1.05 0.495 0)
			(layer "F.SilkS")
			(effects
				(font
					(size 0.7 0.7)
					(thickness 0.15)
				)
				(justify right bottom)
			)
		)
		(property "Value" "R_1k_0402"
			(at 0 1.4 0)
			(layer "F.Fab")
			(effects
				(font
					(size 0.7 0.7)
					(thickness 0.15)
				)
				(justify right bottom)
			)
		)
		(property "Datasheet" "https://www.bourns.com/docs/product-datasheets/cr.pdf"
			(at 0 0 180)
			(layer "F.Fab")
			(hide yes)
			(effects
				(font
					(size 1.27 1.27)
					(thickness 0.15)
				)
			)
		)
		(property "Description" "SMD Chip Resistor, 1 kohm, ± 1%, 63 mW, 0402 [1005 Metric], Thick Film, General Purpose"
			(at 0 0 180)
			(layer "F.Fab")
			(hide yes)
			(effects
				(font
					(size 1.27 1.27)
					(thickness 0.15)
				)
			)
		)
		(property "Author" "Antmicro"
			(at 146.3 179.8 0)
			(layer "F.Fab")
			(hide yes)
			(effects
				(font
					(size 1 1)
					(thickness 0.15)
				)
			)
		)
		(property "License" "Apache-2.0"
			(at 146.3 179.8 0)
			(layer "F.Fab")
			(hide yes)
			(effects
				(font
					(size 1 1)
					(thickness 0.15)
				)
			)
		)
		(property "MPN" "CR0402-FX-1001GLF"
			(at 146.3 179.8 0)
			(layer "F.Fab")
			(hide yes)
			(effects
				(font
					(size 1 1)
					(thickness 0.15)
				)
			)
		)
		(property "Manufacturer" "Bourns"
			(at 146.3 179.8 0)
			(layer "F.Fab")
			(hide yes)
			(effects
				(font
					(size 1 1)
					(thickness 0.15)
				)
			)
		)
		(property "Tolerance" "1%"
			(at 146.3 179.8 0)
			(layer "F.Fab")
			(hide yes)
			(effects
				(font
					(size 1 1)
					(thickness 0.15)
				)
			)
		)
		(property "Val" "1k"
			(at 146.3 179.8 0)
			(layer "F.Fab")
			(hide yes)
			(effects
				(font
					(size 1 1)
					(thickness 0.15)
				)
			)
		)
		(sheetname "/Power supply/")
		(sheetfile "power-supply.kicad_sch")
		(attr smd)
		(fp_rect
			(start -0.925 -0.47)
			(end 0.925 0.47)
			(stroke
				(width 0.05)
				(type default)
			)
			(fill no)
			(layer "F.CrtYd")
		)
		(fp_rect
			(start -0.5 -0.25)
			(end 0.5 0.25)
			(stroke
				(width 0.15)
				(type solid)
			)
			(fill no)
			(layer "F.Fab")
		)
		(pad "1" smd roundrect
			(at -0.48 0 180)
			(size 0.59 0.64)
			(layers "F.Cu" "F.Mask" "F.Paste")
			(roundrect_rratio 0.25)
			(net 215 "Net-(D5-A)")
			(pintype "passive")
		)
		(pad "2" smd roundrect
			(at 0.48 0 180)
			(size 0.59 0.64)
			(layers "F.Cu" "F.Mask" "F.Paste")
			(roundrect_rratio 0.25)
			(net 2 "VCC3V3")
			(pintype "passive")
		)
	)
	(footprint "antmicro-footprints:R_0402_1005Metric"
		(layer "F.Cu")
		(at 84.19 123.645 -90)
		(descr "Resistor SMD 0402")
		(tags "resistor SMD 0402")
		(property "Reference" "R147"
			(at 0.855 -0.31 90)
			(layer "F.SilkS")
			(effects
				(font
					(size 0.7 0.7)
					(thickness 0.15)
				)
				(justify right bottom)
			)
		)
		(property "Value" "R_0R_0402"
			(at 0 1.4 90)
			(layer "F.Fab")
			(effects
				(font
					(size 0.7 0.7)
					(thickness 0.15)
				)
				(justify right bottom)
			)
		)
		(property "Datasheet" "https://industrial.panasonic.com/cdbs/www-data/pdf/RDA0000/AOA0000C301.pdf"
			(at 0 0 270)
			(layer "F.Fab")
			(hide yes)
			(effects
				(font
					(size 1.27 1.27)
					(thickness 0.15)
				)
			)
		)
		(property "Description" "SMD Chip Resistor, Jumper, 0 ohm, 100 mW, 0402 [1005 Metric], Thick Film, General Purpose"
			(at 0 0 270)
			(layer "F.Fab")
			(hide yes)
			(effects
				(font
					(size 1.27 1.27)
					(thickness 0.15)
				)
			)
		)
		(property "Author" "Antmicro"
			(at -39.455 207.835 0)
			(layer "F.Fab")
			(hide yes)
			(effects
				(font
					(size 1 1)
					(thickness 0.15)
				)
			)
		)
		(property "Current" "1A"
			(at -39.455 207.835 0)
			(layer "F.Fab")
			(hide yes)
			(effects
				(font
					(size 1 1)
					(thickness 0.15)
				)
			)
		)
		(property "License" "Apache-2.0"
			(at -39.455 207.835 0)
			(layer "F.Fab")
			(hide yes)
			(effects
				(font
					(size 1 1)
					(thickness 0.15)
				)
			)
		)
		(property "MPN" "ERJ2GE0R00X"
			(at -39.455 207.835 0)
			(layer "F.Fab")
			(hide yes)
			(effects
				(font
					(size 1 1)
					(thickness 0.15)
				)
			)
		)
		(property "Manufacturer" "Panasonic"
			(at -39.455 207.835 0)
			(layer "F.Fab")
			(hide yes)
			(effects
				(font
					(size 1 1)
					(thickness 0.15)
				)
			)
		)
		(property "Tolerance" "~"
			(at -39.455 207.835 0)
			(layer "F.Fab")
			(hide yes)
			(effects
				(font
					(size 1 1)
					(thickness 0.15)
				)
			)
		)
		(property "Val" "0R"
			(at -39.455 207.835 0)
			(layer "F.Fab")
			(hide yes)
			(effects
				(font
					(size 1 1)
					(thickness 0.15)
				)
			)
		)
		(sheetname "/Edge connector/")
		(sheetfile "edge-connector.kicad_sch")
		(attr smd)
		(fp_rect
			(start -0.925 -0.47)
			(end 0.925 0.47)
			(stroke
				(width 0.05)
				(type default)
			)
			(fill no)
			(layer "F.CrtYd")
		)
		(fp_rect
			(start -0.5 -0.25)
			(end 0.5 0.25)
			(stroke
				(width 0.15)
				(type solid)
			)
			(fill no)
			(layer "F.Fab")
		)
		(pad "1" smd roundrect
			(at -0.48 0 270)
			(size 0.59 0.64)
			(layers "F.Cu" "F.Mask" "F.Paste")
			(roundrect_rratio 0.25)
			(net 526 "SPI0_MISO_R")
			(pintype "passive")
		)
		(pad "2" smd roundrect
			(at 0.48 0 270)
			(size 0.59 0.64)
			(layers "F.Cu" "F.Mask" "F.Paste")
			(roundrect_rratio 0.25)
			(net 58 "SPI0_MISO")
			(pintype "passive")
		)
	)
	(footprint "antmicro-footprints:R_0402_1005Metric"
		(layer "F.Cu")
		(at 82.19 123.645 -90)
		(descr "Resistor SMD 0402")
		(tags "resistor SMD 0402")
		(property "Reference" "R146"
			(at 0.855 -0.31 90)
			(layer "F.SilkS")
			(effects
				(font
					(size 0.7 0.7)
					(thickness 0.15)
				)
				(justify right bottom)
			)
		)
		(property "Value" "R_0R_0402"
			(at 0 1.4 90)
			(layer "F.Fab")
			(effects
				(font
					(size 0.7 0.7)
					(thickness 0.15)
				)
				(justify right bottom)
			)
		)
		(property "Datasheet" "https://industrial.panasonic.com/cdbs/www-data/pdf/RDA0000/AOA0000C301.pdf"
			(at 0 0 270)
			(layer "F.Fab")
			(hide yes)
			(effects
				(font
					(size 1.27 1.27)
					(thickness 0.15)
				)
			)
		)
		(property "Description" "SMD Chip Resistor, Jumper, 0 ohm, 100 mW, 0402 [1005 Metric], Thick Film, General Purpose"
			(at 0 0 270)
			(layer "F.Fab")
			(hide yes)
			(effects
				(font
					(size 1.27 1.27)
					(thickness 0.15)
				)
			)
		)
		(property "Author" "Antmicro"
			(at -41.455 205.835 0)
			(layer "F.Fab")
			(hide yes)
			(effects
				(font
					(size 1 1)
					(thickness 0.15)
				)
			)
		)
		(property "Current" "1A"
			(at -41.455 205.835 0)
			(layer "F.Fab")
			(hide yes)
			(effects
				(font
					(size 1 1)
					(thickness 0.15)
				)
			)
		)
		(property "License" "Apache-2.0"
			(at -41.455 205.835 0)
			(layer "F.Fab")
			(hide yes)
			(effects
				(font
					(size 1 1)
					(thickness 0.15)
				)
			)
		)
		(property "MPN" "ERJ2GE0R00X"
			(at -41.455 205.835 0)
			(layer "F.Fab")
			(hide yes)
			(effects
				(font
					(size 1 1)
					(thickness 0.15)
				)
			)
		)
		(property "Manufacturer" "Panasonic"
			(at -41.455 205.835 0)
			(layer "F.Fab")
			(hide yes)
			(effects
				(font
					(size 1 1)
					(thickness 0.15)
				)
			)
		)
		(property "Tolerance" "~"
			(at -41.455 205.835 0)
			(layer "F.Fab")
			(hide yes)
			(effects
				(font
					(size 1 1)
					(thickness 0.15)
				)
			)
		)
		(property "Val" "0R"
			(at -41.455 205.835 0)
			(layer "F.Fab")
			(hide yes)
			(effects
				(font
					(size 1 1)
					(thickness 0.15)
				)
			)
		)
		(sheetname "/Edge connector/")
		(sheetfile "edge-connector.kicad_sch")
		(attr smd)
		(fp_rect
			(start -0.925 -0.47)
			(end 0.925 0.47)
			(stroke
				(width 0.05)
				(type default)
			)
			(fill no)
			(layer "F.CrtYd")
		)
		(fp_rect
			(start -0.5 -0.25)
			(end 0.5 0.25)
			(stroke
				(width 0.15)
				(type solid)
			)
			(fill no)
			(layer "F.Fab")
		)
		(pad "1" smd roundrect
			(at -0.48 0 270)
			(size 0.59 0.64)
			(layers "F.Cu" "F.Mask" "F.Paste")
			(roundrect_rratio 0.25)
			(net 525 "SPI0_CS_N_R")
			(pintype "passive")
		)
		(pad "2" smd roundrect
			(at 0.48 0 270)
			(size 0.59 0.64)
			(layers "F.Cu" "F.Mask" "F.Paste")
			(roundrect_rratio 0.25)
			(net 55 "SPI0_CS_N")
			(pintype "passive")
		)
	)
	(footprint "antmicro-footprints:R_0402_1005Metric"
		(layer "F.Cu")
		(at 81.19 123.645 -90)
		(descr "Resistor SMD 0402")
		(tags "resistor SMD 0402")
		(property "Reference" "R145"
			(at 0.855 -0.31 90)
			(layer "F.SilkS")
			(effects
				(font
					(size 0.7 0.7)
					(thickness 0.15)
				)
				(justify right bottom)
			)
		)
		(property "Value" "R_0R_0402"
			(at 0 1.4 90)
			(layer "F.Fab")
			(effects
				(font
					(size 0.7 0.7)
					(thickness 0.15)
				)
				(justify right bottom)
			)
		)
		(property "Datasheet" "https://industrial.panasonic.com/cdbs/www-data/pdf/RDA0000/AOA0000C301.pdf"
			(at 0 0 270)
			(layer "F.Fab")
			(hide yes)
			(effects
				(font
					(size 1.27 1.27)
					(thickness 0.15)
				)
			)
		)
		(property "Description" "SMD Chip Resistor, Jumper, 0 ohm, 100 mW, 0402 [1005 Metric], Thick Film, General Purpose"
			(at 0 0 270)
			(layer "F.Fab")
			(hide yes)
			(effects
				(font
					(size 1.27 1.27)
					(thickness 0.15)
				)
			)
		)
		(property "Author" "Antmicro"
			(at -42.455 204.835 0)
			(layer "F.Fab")
			(hide yes)
			(effects
				(font
					(size 1 1)
					(thickness 0.15)
				)
			)
		)
		(property "Current" "1A"
			(at -42.455 204.835 0)
			(layer "F.Fab")
			(hide yes)
			(effects
				(font
					(size 1 1)
					(thickness 0.15)
				)
			)
		)
		(property "License" "Apache-2.0"
			(at -42.455 204.835 0)
			(layer "F.Fab")
			(hide yes)
			(effects
				(font
					(size 1 1)
					(thickness 0.15)
				)
			)
		)
		(property "MPN" "ERJ2GE0R00X"
			(at -42.455 204.835 0)
			(layer "F.Fab")
			(hide yes)
			(effects
				(font
					(size 1 1)
					(thickness 0.15)
				)
			)
		)
		(property "Manufacturer" "Panasonic"
			(at -42.455 204.835 0)
			(layer "F.Fab")
			(hide yes)
			(effects
				(font
					(size 1 1)
					(thickness 0.15)
				)
			)
		)
		(property "Tolerance" "~"
			(at -42.455 204.835 0)
			(layer "F.Fab")
			(hide yes)
			(effects
				(font
					(size 1 1)
					(thickness 0.15)
				)
			)
		)
		(property "Val" "0R"
			(at -42.455 204.835 0)
			(layer "F.Fab")
			(hide yes)
			(effects
				(font
					(size 1 1)
					(thickness 0.15)
				)
			)
		)
		(sheetname "/Edge connector/")
		(sheetfile "edge-connector.kicad_sch")
		(attr smd)
		(fp_rect
			(start -0.925 -0.47)
			(end 0.925 0.47)
			(stroke
				(width 0.05)
				(type default)
			)
			(fill no)
			(layer "F.CrtYd")
		)
		(fp_rect
			(start -0.5 -0.25)
			(end 0.5 0.25)
			(stroke
				(width 0.15)
				(type solid)
			)
			(fill no)
			(layer "F.Fab")
		)
		(pad "1" smd roundrect
			(at -0.48 0 270)
			(size 0.59 0.64)
			(layers "F.Cu" "F.Mask" "F.Paste")
			(roundrect_rratio 0.25)
			(net 524 "SPI0_CLK_R")
			(pintype "passive")
		)
		(pad "2" smd roundrect
			(at 0.48 0 270)
			(size 0.59 0.64)
			(layers "F.Cu" "F.Mask" "F.Paste")
			(roundrect_rratio 0.25)
			(net 56 "SPI0_CLK")
			(pintype "passive")
		)
	)
	(footprint "antmicro-footprints:R_0603_1608Metric"
		(layer "F.Cu")
		(at 79.925 72.1 90)
		(descr "Resistor SMD 0603")
		(tags "resistor SMD 0603")
		(property "Reference" "R188"
			(at -0.3 -16.514 90)
			(layer "F.SilkS")
			(effects
				(font
					(size 0.7 0.7)
					(thickness 0.15)
				)
				(justify left bottom)
			)
		)
		(property "Value" "R_0R_0603"
			(at 0 1.6 90)
			(layer "F.Fab")
			(effects
				(font
					(size 0.7 0.7)
					(thickness 0.15)
				)
				(justify left bottom)
			)
		)
		(property "Datasheet" "https://www.bourns.com/docs/product-datasheets/cr.pdf?sfvrsn=574d41f6_14"
			(at 0 0 90)
			(layer "F.Fab")
			(hide yes)
			(effects
				(font
					(size 1.27 1.27)
					(thickness 0.15)
				)
			)
		)
		(property "Description" "Zero Ohm Resistor, Jumper, 0603 [1608 Metric], Thick Film, 100 mW, 1 A, Surface Mount Device, CR"
			(at 0 0 90)
			(layer "F.Fab")
			(hide yes)
			(effects
				(font
					(size 1.27 1.27)
					(thickness 0.15)
				)
			)
		)
		(property "Author" "Antmicro"
			(at 152.025 -7.825 0)
			(layer "F.Fab")
			(hide yes)
			(effects
				(font
					(size 1 1)
					(thickness 0.15)
				)
			)
		)
		(property "Current" "1A"
			(at 152.025 -7.825 0)
			(layer "F.Fab")
			(hide yes)
			(effects
				(font
					(size 1 1)
					(thickness 0.15)
				)
			)
		)
		(property "License" "Apache-2.0"
			(at 152.025 -7.825 0)
			(layer "F.Fab")
			(hide yes)
			(effects
				(font
					(size 1 1)
					(thickness 0.15)
				)
			)
		)
		(property "MPN" "CR0603-J/-000ELF"
			(at 152.025 -7.825 0)
			(layer "F.Fab")
			(hide yes)
			(effects
				(font
					(size 1 1)
					(thickness 0.15)
				)
			)
		)
		(property "Manufacturer" "Bourns"
			(at 152.025 -7.825 0)
			(layer "F.Fab")
			(hide yes)
			(effects
				(font
					(size 1 1)
					(thickness 0.15)
				)
			)
		)
		(property "Tolerance" "~"
			(at 152.025 -7.825 0)
			(layer "F.Fab")
			(hide yes)
			(effects
				(font
					(size 1 1)
					(thickness 0.15)
				)
			)
		)
		(property "Val" "0R"
			(at 152.025 -7.825 0)
			(layer "F.Fab")
			(hide yes)
			(effects
				(font
					(size 1 1)
					(thickness 0.15)
				)
			)
		)
		(sheetname "/Power supply/")
		(sheetfile "power-supply.kicad_sch")
		(attr smd)
		(fp_line
			(start -0.15 -0.4)
			(end 0.15 -0.4)
			(stroke
				(width 0.15)
				(type solid)
			)
			(layer "F.SilkS")
		)
		(fp_line
			(start -0.15 0.4)
			(end 0.15 0.4)
			(stroke
				(width 0.15)
				(type solid)
			)
			(layer "F.SilkS")
		)
		(fp_rect
			(start -1.25 -0.65)
			(end 1.25 0.65)
			(stroke
				(width 0.05)
				(type solid)
			)
			(fill no)
			(layer "F.CrtYd")
		)
		(fp_rect
			(start -0.8 -0.4)
			(end 0.8 0.4)
			(stroke
				(width 0.15)
				(type solid)
			)
			(fill no)
			(layer "F.Fab")
		)
		(pad "1" smd roundrect
			(at -0.7 0 90)
			(size 0.8 1)
			(layers "F.Cu" "F.Mask" "F.Paste")
			(roundrect_rratio 0.2)
			(net 339 "VCC1V2")
			(pintype "passive")
		)
		(pad "2" smd roundrect
			(at 0.7 0 90)
			(size 0.8 1)
			(layers "F.Cu" "F.Mask" "F.Paste")
			(roundrect_rratio 0.2)
			(net 60 "Net-(C101-Pad2)")
			(pintype "passive")
		)
	)
	(footprint "antmicro-footprints:QFN-8_2x1.5mm"
		(layer "F.Cu")
		(at 86.975 74.6 180)
		(property "Reference" "U16"
			(at 0.425 1.21 180)
			(layer "F.SilkS")
			(effects
				(font
					(size 0.7 0.7)
					(thickness 0.15)
				)
				(justify left bottom)
			)
		)
		(property "Value" "TPS62823DLCT"
			(at 0 2.2 180)
			(layer "F.Fab")
			(effects
				(font
					(size 0.7 0.7)
					(thickness 0.15)
				)
				(justify left bottom)
			)
		)
		(property "Datasheet" "https://www.ti.com/lit/ds/symlink/tps62823.pdf?ts=1685970309606&ref_url=https%253A%252F%252Fwww.ti.com%252Fproduct%252FTPS62823%252Fpart-details%252FTPS62823DLCT"
			(at 0 0 180)
			(layer "F.Fab")
			(hide yes)
			(effects
				(font
					(size 1.27 1.27)
					(thickness 0.15)
				)
			)
		)
		(property "Description" "DC/DC converter"
			(at 0 0 180)
			(layer "F.Fab")
			(hide yes)
			(effects
				(font
					(size 1.27 1.27)
					(thickness 0.15)
				)
			)
		)
		(property "Author" "Antmicro"
			(at 173.95 149.2 0)
			(layer "F.Fab")
			(hide yes)
			(effects
				(font
					(size 1 1)
					(thickness 0.15)
				)
			)
		)
		(property "License" "Apache-2.0"
			(at 173.95 149.2 0)
			(layer "F.Fab")
			(hide yes)
			(effects
				(font
					(size 1 1)
					(thickness 0.15)
				)
			)
		)
		(property "MPN" "TPS62823DLCT"
			(at 173.95 149.2 0)
			(layer "F.Fab")
			(hide yes)
			(effects
				(font
					(size 1 1)
					(thickness 0.15)
				)
			)
		)
		(property "Manufacturer" "Texas Instruments"
			(at 173.95 149.2 0)
			(layer "F.Fab")
			(hide yes)
			(effects
				(font
					(size 1 1)
					(thickness 0.15)
				)
			)
		)
		(sheetname "/Power supply/")
		(sheetfile "power-supply.kicad_sch")
		(attr smd)
		(fp_line
			(start -0.25 -1.05)
			(end 0.9 -1.05)
			(stroke
				(width 0.15)
				(type solid)
			)
			(layer "F.SilkS")
		)
		(fp_line
			(start -0.9 1.05)
			(end 0.9 1.05)
			(stroke
				(width 0.15)
				(type solid)
			)
			(layer "F.SilkS")
		)
		(fp_circle
			(center -0.9 -1.05)
			(end -0.849 -1.05)
			(stroke
				(width 0.15)
				(type solid)
			)
			(fill yes)
			(layer "F.SilkS")
		)
		(fp_rect
			(start -1.1 -1.25)
			(end 1.1 1.25)
			(stroke
				(width 0.05)
				(type solid)
			)
			(fill no)
			(layer "F.CrtYd")
		)
		(fp_line
			(start 0.998 0.998)
			(end -1 0.998)
			(stroke
				(width 0.15)
				(type solid)
			)
			(layer "F.Fab")
		)
		(fp_line
			(start 0.998 -1)
			(end 0.998 0.998)
			(stroke
				(width 0.15)
				(type solid)
			)
			(layer "F.Fab")
		)
		(fp_line
			(start -0.5 -1)
			(end 0.998 -1)
			(stroke
				(width 0.15)
				(type solid)
			)
			(layer "F.Fab")
		)
		(fp_line
			(start -1 0.998)
			(end -1 -0.5)
			(stroke
				(width 0.15)
				(type solid)
			)
			(layer "F.Fab")
		)
		(fp_line
			(start -1 -0.5)
			(end -0.5 -1)
			(stroke
				(width 0.15)
				(type solid)
			)
			(layer "F.Fab")
		)
		(pad "1" smd rect
			(at -0.677 -0.75 180)
			(size 0.55 0.25)
			(layers "F.Cu" "F.Mask" "F.Paste")
			(net 347 "Net-(U16-EN)")
			(pinfunction "EN")
			(pintype "input")
		)
		(pad "2" smd rect
			(at -0.677 -0.25 180)
			(size 0.55 0.25)
			(layers "F.Cu" "F.Mask" "F.Paste")
			(net 10 "Net-(U16-FB)")
			(pinfunction "FB")
			(pintype "bidirectional")
		)
		(pad "3" smd rect
			(at -0.677 0.248 180)
			(size 0.55 0.25)
			(layers "F.Cu" "F.Mask" "F.Paste")
			(net 1 "GND")
			(pinfunction "AGND")
			(pintype "power_in")
		)
		(pad "4" smd rect
			(at -0.677 0.748 180)
			(size 0.55 0.25)
			(layers "F.Cu" "F.Mask" "F.Paste")
			(net 646 "unconnected-(U16-NC-Pad4)")
			(pinfunction "NC")
			(pintype "no_connect")
		)
		(pad "5" smd rect
			(at 0.675 0.748 180)
			(size 0.55 0.25)
			(layers "F.Cu" "F.Mask" "F.Paste")
			(net 1 "GND")
			(pinfunction "PGND")
			(pintype "power_in")
		)
		(pad "6" smd rect
			(at 0.675 0.248 180)
			(size 0.55 0.25)
			(layers "F.Cu" "F.Mask" "F.Paste")
			(net 291 "Net-(U16-SW)")
			(pinfunction "SW")
			(pintype "bidirectional")
		)
		(pad "7" smd rect
			(at 0.675 -0.25 180)
			(size 0.55 0.25)
			(layers "F.Cu" "F.Mask" "F.Paste")
			(net 4 "VCC5V0")
			(pinfunction "VIN")
			(pintype "power_in")
		)
		(pad "8" smd rect
			(at 0.675 -0.75 180)
			(size 0.55 0.25)
			(layers "F.Cu" "F.Mask" "F.Paste")
			(net 534 "/Power supply/1V2_PG")
			(pinfunction "PG")
			(pintype "output")
		)
	)
	(footprint "antmicro-footprints:L_Vishay-IHLP-1212AE"
		(layer "F.Cu")
		(at 82.5 72.4 90)
		(property "Reference" "L6"
			(at 1.8285 -17.25 90)
			(layer "F.SilkS")
			(effects
				(font
					(size 0.7 0.7)
					(thickness 0.15)
				)
				(justify left bottom)
			)
		)
		(property "Value" "L_470n_6.7A_Vishay-IHLP-1212AE-11"
			(at 1.278 3.401 90)
			(layer "F.Fab")
			(effects
				(font
					(size 0.7 0.7)
					(thickness 0.15)
				)
				(justify left bottom)
			)
		)
		(property "Datasheet" "https://www.vishay.com/docs/34300/ihlp-1212ae-11.pdf"
			(at 0 0 90)
			(layer "F.Fab")
			(hide yes)
			(effects
				(font
					(size 1.27 1.27)
					(thickness 0.15)
				)
			)
		)
		(property "Description" "Power Inductor (SMT), 470 nH, 6.7 A, Shielded, 6.7 A"
			(at 0 0 90)
			(layer "F.Fab")
			(hide yes)
			(effects
				(font
					(size 1.27 1.27)
					(thickness 0.15)
				)
			)
		)
		(property "Author" "Antmicro"
			(at 154.9 -10.1 0)
			(layer "F.Fab")
			(hide yes)
			(effects
				(font
					(size 1 1)
					(thickness 0.15)
				)
			)
		)
		(property "IMax" "6.7 A"
			(at 154.9 -10.1 0)
			(layer "F.Fab")
			(hide yes)
			(effects
				(font
					(size 1 1)
					(thickness 0.15)
				)
			)
		)
		(property "ISat" "6.7 A"
			(at 154.9 -10.1 0)
			(layer "F.Fab")
			(hide yes)
			(effects
				(font
					(size 1 1)
					(thickness 0.15)
				)
			)
		)
		(property "License" "Apache-2.0"
			(at 154.9 -10.1 0)
			(layer "F.Fab")
			(hide yes)
			(effects
				(font
					(size 1 1)
					(thickness 0.15)
				)
			)
		)
		(property "MPN" "IHLP1212AEERR47M11"
			(at 154.9 -10.1 0)
			(layer "F.Fab")
			(hide yes)
			(effects
				(font
					(size 1 1)
					(thickness 0.15)
				)
			)
		)
		(property "Manufacturer" "Vishay"
			(at 154.9 -10.1 0)
			(layer "F.Fab")
			(hide yes)
			(effects
				(font
					(size 1 1)
					(thickness 0.15)
				)
			)
		)
		(property "Size" "3.0x3.0"
			(at 154.9 -10.1 0)
			(layer "F.Fab")
			(hide yes)
			(effects
				(font
					(size 1 1)
					(thickness 0.15)
				)
			)
		)
		(property "Val" "470n/6.7A"
			(at 154.9 -10.1 0)
			(layer "F.Fab")
			(hide yes)
			(effects
				(font
					(size 1 1)
					(thickness 0.15)
				)
			)
		)
		(sheetname "/Power supply/")
		(sheetfile "power-supply.kicad_sch")
		(attr smd)
		(fp_line
			(start 1.653 -1.6)
			(end 1.653 -0.9)
			(stroke
				(width 0.15)
				(type solid)
			)
			(layer "F.SilkS")
		)
		(fp_line
			(start -1.647 -1.6)
			(end 1.653 -1.6)
			(stroke
				(width 0.15)
				(type solid)
			)
			(layer "F.SilkS")
		)
		(fp_line
			(start -1.647 -0.9)
			(end -1.647 -1.6)
			(stroke
				(width 0.15)
				(type solid)
			)
			(layer "F.SilkS")
		)
		(fp_line
			(start 1.653 0.9)
			(end 1.653 1.601)
			(stroke
				(width 0.15)
				(type solid)
			)
			(layer "F.SilkS")
		)
		(fp_line
			(start -1.647 1.6)
			(end -1.647 0.9)
			(stroke
				(width 0.15)
				(type solid)
			)
			(layer "F.SilkS")
		)
		(fp_line
			(start 1.653 1.601)
			(end -1.647 1.6)
			(stroke
				(width 0.15)
				(type solid)
			)
			(layer "F.SilkS")
		)
		(fp_rect
			(start -2.35 -1.85)
			(end 2.35 1.85)
			(stroke
				(width 0.05)
				(type solid)
			)
			(fill no)
			(layer "F.CrtYd")
		)
		(fp_rect
			(start -1.803 -1.601)
			(end 1.803 1.601)
			(stroke
				(width 0.15)
				(type solid)
			)
			(fill no)
			(layer "F.Fab")
		)
		(pad "1" smd roundrect
			(at -1.35 0 90)
			(size 1.5 1.2)
			(layers "F.Cu" "F.Mask" "F.Paste")
			(roundrect_rratio 0.1)
			(net 291 "Net-(U16-SW)")
			(pintype "passive")
		)
		(pad "2" smd roundrect
			(at 1.35 0 90)
			(size 1.5 1.2)
			(layers "F.Cu" "F.Mask" "F.Paste")
			(roundrect_rratio 0.1)
			(net 60 "Net-(C101-Pad2)")
			(pintype "passive")
		)
	)
	(footprint "antmicro-footprints:R_0402_1005Metric"
		(layer "F.Cu")
		(at 89.52 74.4 90)
		(descr "Resistor SMD 0402")
		(tags "resistor SMD 0402")
		(property "Reference" "R187"
			(at -1 3.38 90)
			(layer "F.SilkS")
			(effects
				(font
					(size 0.7 0.7)
					(thickness 0.15)
				)
				(justify left bottom)
			)
		)
		(property "Value" "R_100k_0402"
			(at 0 1.4 90)
			(layer "F.Fab")
			(effects
				(font
					(size 0.7 0.7)
					(thickness 0.15)
				)
				(justify left bottom)
			)
		)
		(property "Datasheet" "https://www.bourns.com/docs/product-datasheets/cr.pdf"
			(at 0 0 90)
			(layer "F.Fab")
			(hide yes)
			(effects
				(font
					(size 1.27 1.27)
					(thickness 0.15)
				)
			)
		)
		(property "Description" "SMD Chip Resistor, 100 kohm, ± 1%, 62.5 mW, 0402 [1005 Metric], Thick Film, General Purpose"
			(at 0 0 90)
			(layer "F.Fab")
			(hide yes)
			(effects
				(font
					(size 1.27 1.27)
					(thickness 0.15)
				)
			)
		)
		(property "Author" "Antmicro"
			(at 163.92 -15.12 0)
			(layer "F.Fab")
			(hide yes)
			(effects
				(font
					(size 1 1)
					(thickness 0.15)
				)
			)
		)
		(property "License" "Apache-2.0"
			(at 163.92 -15.12 0)
			(layer "F.Fab")
			(hide yes)
			(effects
				(font
					(size 1 1)
					(thickness 0.15)
				)
			)
		)
		(property "MPN" "CR0402-FX-1003GLF"
			(at 163.92 -15.12 0)
			(layer "F.Fab")
			(hide yes)
			(effects
				(font
					(size 1 1)
					(thickness 0.15)
				)
			)
		)
		(property "Manufacturer" "Bourns"
			(at 163.92 -15.12 0)
			(layer "F.Fab")
			(hide yes)
			(effects
				(font
					(size 1 1)
					(thickness 0.15)
				)
			)
		)
		(property "Tolerance" "1%"
			(at 163.92 -15.12 0)
			(layer "F.Fab")
			(hide yes)
			(effects
				(font
					(size 1 1)
					(thickness 0.15)
				)
			)
		)
		(property "Val" "100k"
			(at 163.92 -15.12 0)
			(layer "F.Fab")
			(hide yes)
			(effects
				(font
					(size 1 1)
					(thickness 0.15)
				)
			)
		)
		(sheetname "/Power supply/")
		(sheetfile "power-supply.kicad_sch")
		(attr smd)
		(fp_rect
			(start -0.925 -0.47)
			(end 0.925 0.47)
			(stroke
				(width 0.05)
				(type default)
			)
			(fill no)
			(layer "F.CrtYd")
		)
		(fp_rect
			(start -0.5 -0.25)
			(end 0.5 0.25)
			(stroke
				(width 0.15)
				(type solid)
			)
			(fill no)
			(layer "F.Fab")
		)
		(pad "1" smd roundrect
			(at -0.48 0 90)
			(size 0.59 0.64)
			(layers "F.Cu" "F.Mask" "F.Paste")
			(roundrect_rratio 0.25)
			(net 10 "Net-(U16-FB)")
			(pintype "passive")
		)
		(pad "2" smd roundrect
			(at 0.48 0 90)
			(size 0.59 0.64)
			(layers "F.Cu" "F.Mask" "F.Paste")
			(roundrect_rratio 0.25)
			(net 1 "GND")
			(pintype "passive")
		)
	)
	(footprint "antmicro-footprints:C_0402_1005Metric"
		(layer "F.Cu")
		(at 91.52 74.4 90)
		(descr "Capacitor SMD 0402")
		(tags "capacitor SMD 0402")
		(property "Reference" "C3"
			(at -1 3.58 90)
			(layer "F.SilkS")
			(effects
				(font
					(size 0.7 0.7)
					(thickness 0.15)
				)
				(justify left bottom)
			)
		)
		(property "Value" "C_120p_0402"
			(at 0 1.4 90)
			(layer "F.Fab")
			(effects
				(font
					(size 0.7 0.7)
					(thickness 0.15)
				)
				(justify left bottom)
			)
		)
		(property "Datasheet" "https://www.kemet.com/en/us/capacitors/product/C0402C121J5GACTU.html"
			(at 0 0 90)
			(layer "F.Fab")
			(hide yes)
			(effects
				(font
					(size 1.27 1.27)
					(thickness 0.15)
				)
			)
		)
		(property "Description" "120 pF ±2% 100V Ceramic Capacitor C0G, NP0 0402 (1005 Metric)"
			(at 0 0 90)
			(layer "F.Fab")
			(hide yes)
			(effects
				(font
					(size 1.27 1.27)
					(thickness 0.15)
				)
			)
		)
		(property "Author" "Antmicro"
			(at 165.92 -17.12 0)
			(layer "F.Fab")
			(hide yes)
			(effects
				(font
					(size 1 1)
					(thickness 0.15)
				)
			)
		)
		(property "Dielectric" "C0G"
			(at 165.92 -17.12 0)
			(layer "F.Fab")
			(hide yes)
			(effects
				(font
					(size 1 1)
					(thickness 0.15)
				)
			)
		)
		(property "License" "Apache-2.0"
			(at 165.92 -17.12 0)
			(layer "F.Fab")
			(hide yes)
			(effects
				(font
					(size 1 1)
					(thickness 0.15)
				)
			)
		)
		(property "MPN" "C0402C121J5GACTU"
			(at 165.92 -17.12 0)
			(layer "F.Fab")
			(hide yes)
			(effects
				(font
					(size 1 1)
					(thickness 0.15)
				)
			)
		)
		(property "Manufacturer" "KEMET"
			(at 165.92 -17.12 0)
			(layer "F.Fab")
			(hide yes)
			(effects
				(font
					(size 1 1)
					(thickness 0.15)
				)
			)
		)
		(property "Val" "120p"
			(at 165.92 -17.12 0)
			(layer "F.Fab")
			(hide yes)
			(effects
				(font
					(size 1 1)
					(thickness 0.15)
				)
			)
		)
		(property "Voltage" "100V"
			(at 165.92 -17.12 0)
			(layer "F.Fab")
			(hide yes)
			(effects
				(font
					(size 1 1)
					(thickness 0.15)
				)
			)
		)
		(sheetname "/Power supply/")
		(sheetfile "power-supply.kicad_sch")
		(attr smd)
		(fp_rect
			(start -0.925 -0.47)
			(end 0.925 0.47)
			(stroke
				(width 0.05)
				(type default)
			)
			(fill no)
			(layer "F.CrtYd")
		)
		(fp_line
			(start 0.504 -0.25)
			(end 0.504 0.248)
			(stroke
				(width 0.15)
				(type solid)
			)
			(layer "F.Fab")
		)
		(fp_line
			(start -0.494 -0.25)
			(end 0.504 -0.25)
			(stroke
				(width 0.15)
				(type solid)
			)
			(layer "F.Fab")
		)
		(fp_line
			(start 0.504 0.248)
			(end -0.494 0.248)
			(stroke
				(width 0.15)
				(type solid)
			)
			(layer "F.Fab")
		)
		(fp_line
			(start -0.494 0.248)
			(end -0.494 -0.25)
			(stroke
				(width 0.15)
				(type solid)
			)
			(layer "F.Fab")
		)
		(pad "1" smd roundrect
			(at -0.48 0 90)
			(size 0.59 0.64)
			(layers "F.Cu" "F.Mask" "F.Paste")
			(roundrect_rratio 0.25)
			(net 10 "Net-(U16-FB)")
			(pintype "passive")
		)
		(pad "2" smd roundrect
			(at 0.48 0 90)
			(size 0.59 0.64)
			(layers "F.Cu" "F.Mask" "F.Paste")
			(roundrect_rratio 0.25)
			(net 60 "Net-(C101-Pad2)")
			(pintype "passive")
		)
	)
	(footprint "antmicro-footprints:C_0402_1005Metric"
		(layer "F.Cu")
		(at 85.87 72 180)
		(descr "Capacitor SMD 0402")
		(tags "capacitor SMD 0402")
		(property "Reference" "C101"
			(at -3.63 -0.4 0)
			(layer "F.SilkS")
			(effects
				(font
					(size 0.7 0.7)
					(thickness 0.15)
				)
				(justify right bottom)
			)
		)
		(property "Value" "C_10u_0402"
			(at 0 1.4 0)
			(layer "F.Fab")
			(effects
				(font
					(size 0.7 0.7)
					(thickness 0.15)
				)
				(justify right bottom)
			)
		)
		(property "Datasheet" "https://www.yageo.com/en/Chart/Download/pdf/CC0402MRX5R5BB106"
			(at 0 0 180)
			(layer "F.Fab")
			(hide yes)
			(effects
				(font
					(size 1.27 1.27)
					(thickness 0.15)
				)
			)
		)
		(property "Description" "SMD Multilayer Ceramic Capacitor, 10 µF, 6.3 V, 0402 [1005 Metric], ± 20%, X5R, CC Series"
			(at 0 0 180)
			(layer "F.Fab")
			(hide yes)
			(effects
				(font
					(size 1.27 1.27)
					(thickness 0.15)
				)
			)
		)
		(property "Author" "Antmicro"
			(at 171.74 144 0)
			(layer "F.Fab")
			(hide yes)
			(effects
				(font
					(size 1 1)
					(thickness 0.15)
				)
			)
		)
		(property "Dielectric" ""
			(at 171.74 144 0)
			(layer "F.Fab")
			(hide yes)
			(effects
				(font
					(size 1 1)
					(thickness 0.15)
				)
			)
		)
		(property "License" "Apache-2.0"
			(at 171.74 144 0)
			(layer "F.Fab")
			(hide yes)
			(effects
				(font
					(size 1 1)
					(thickness 0.15)
				)
			)
		)
		(property "MPN" "CC0402MRX5R5BB106"
			(at 171.74 144 0)
			(layer "F.Fab")
			(hide yes)
			(effects
				(font
					(size 1 1)
					(thickness 0.15)
				)
			)
		)
		(property "Manufacturer" "YAGEO"
			(at 171.74 144 0)
			(layer "F.Fab")
			(hide yes)
			(effects
				(font
					(size 1 1)
					(thickness 0.15)
				)
			)
		)
		(property "Val" "10u"
			(at 171.74 144 0)
			(layer "F.Fab")
			(hide yes)
			(effects
				(font
					(size 1 1)
					(thickness 0.15)
				)
			)
		)
		(property "Voltage" ""
			(at 171.74 144 0)
			(layer "F.Fab")
			(hide yes)
			(effects
				(font
					(size 1 1)
					(thickness 0.15)
				)
			)
		)
		(sheetname "/Power supply/")
		(sheetfile "power-supply.kicad_sch")
		(attr smd)
		(fp_rect
			(start -0.925 -0.47)
			(end 0.925 0.47)
			(stroke
				(width 0.05)
				(type default)
			)
			(fill no)
			(layer "F.CrtYd")
		)
		(fp_line
			(start 0.504 0.248)
			(end -0.494 0.248)
			(stroke
				(width 0.15)
				(type solid)
			)
			(layer "F.Fab")
		)
		(fp_line
			(start 0.504 -0.25)
			(end 0.504 0.248)
			(stroke
				(width 0.15)
				(type solid)
			)
			(layer "F.Fab")
		)
		(fp_line
			(start -0.494 0.248)
			(end -0.494 -0.25)
			(stroke
				(width 0.15)
				(type solid)
			)
			(layer "F.Fab")
		)
		(fp_line
			(start -0.494 -0.25)
			(end 0.504 -0.25)
			(stroke
				(width 0.15)
				(type solid)
			)
			(layer "F.Fab")
		)
		(pad "1" smd roundrect
			(at -0.48 0 180)
			(size 0.59 0.64)
			(layers "F.Cu" "F.Mask" "F.Paste")
			(roundrect_rratio 0.25)
			(net 1 "GND")
			(pintype "passive")
		)
		(pad "2" smd roundrect
			(at 0.48 0 180)
			(size 0.59 0.64)
			(layers "F.Cu" "F.Mask" "F.Paste")
			(roundrect_rratio 0.25)
			(net 60 "Net-(C101-Pad2)")
			(pintype "passive")
		)
	)
	(footprint "antmicro-footprints:C_0402_1005Metric"
		(layer "F.Cu")
		(at 85.875 70.665 180)
		(descr "Capacitor SMD 0402")
		(tags "capacitor SMD 0402")
		(property "Reference" "C103"
			(at -3.525 -0.435 0)
			(layer "F.SilkS")
			(effects
				(font
					(size 0.7 0.7)
					(thickness 0.15)
				)
				(justify right bottom)
			)
		)
		(property "Value" "C_10u_0402"
			(at 0 1.4 0)
			(layer "F.Fab")
			(effects
				(font
					(size 0.7 0.7)
					(thickness 0.15)
				)
				(justify right bottom)
			)
		)
		(property "Datasheet" "https://www.yageo.com/en/Chart/Download/pdf/CC0402MRX5R5BB106"
			(at 0 0 180)
			(layer "F.Fab")
			(hide yes)
			(effects
				(font
					(size 1.27 1.27)
					(thickness 0.15)
				)
			)
		)
		(property "Description" "SMD Multilayer Ceramic Capacitor, 10 µF, 6.3 V, 0402 [1005 Metric], ± 20%, X5R, CC Series"
			(at 0 0 180)
			(layer "F.Fab")
			(hide yes)
			(effects
				(font
					(size 1.27 1.27)
					(thickness 0.15)
				)
			)
		)
		(property "Author" "Antmicro"
			(at 171.75 141.33 0)
			(layer "F.Fab")
			(hide yes)
			(effects
				(font
					(size 1 1)
					(thickness 0.15)
				)
			)
		)
		(property "Dielectric" ""
			(at 171.75 141.33 0)
			(layer "F.Fab")
			(hide yes)
			(effects
				(font
					(size 1 1)
					(thickness 0.15)
				)
			)
		)
		(property "License" "Apache-2.0"
			(at 171.75 141.33 0)
			(layer "F.Fab")
			(hide yes)
			(effects
				(font
					(size 1 1)
					(thickness 0.15)
				)
			)
		)
		(property "MPN" "CC0402MRX5R5BB106"
			(at 171.75 141.33 0)
			(layer "F.Fab")
			(hide yes)
			(effects
				(font
					(size 1 1)
					(thickness 0.15)
				)
			)
		)
		(property "Manufacturer" "YAGEO"
			(at 171.75 141.33 0)
			(layer "F.Fab")
			(hide yes)
			(effects
				(font
					(size 1 1)
					(thickness 0.15)
				)
			)
		)
		(property "Val" "10u"
			(at 171.75 141.33 0)
			(layer "F.Fab")
			(hide yes)
			(effects
				(font
					(size 1 1)
					(thickness 0.15)
				)
			)
		)
		(property "Voltage" ""
			(at 171.75 141.33 0)
			(layer "F.Fab")
			(hide yes)
			(effects
				(font
					(size 1 1)
					(thickness 0.15)
				)
			)
		)
		(sheetname "/Power supply/")
		(sheetfile "power-supply.kicad_sch")
		(attr smd)
		(fp_rect
			(start -0.925 -0.47)
			(end 0.925 0.47)
			(stroke
				(width 0.05)
				(type default)
			)
			(fill no)
			(layer "F.CrtYd")
		)
		(fp_line
			(start 0.504 0.248)
			(end -0.494 0.248)
			(stroke
				(width 0.15)
				(type solid)
			)
			(layer "F.Fab")
		)
		(fp_line
			(start 0.504 -0.25)
			(end 0.504 0.248)
			(stroke
				(width 0.15)
				(type solid)
			)
			(layer "F.Fab")
		)
		(fp_line
			(start -0.494 0.248)
			(end -0.494 -0.25)
			(stroke
				(width 0.15)
				(type solid)
			)
			(layer "F.Fab")
		)
		(fp_line
			(start -0.494 -0.25)
			(end 0.504 -0.25)
			(stroke
				(width 0.15)
				(type solid)
			)
			(layer "F.Fab")
		)
		(pad "1" smd roundrect
			(at -0.48 0 180)
			(size 0.59 0.64)
			(layers "F.Cu" "F.Mask" "F.Paste")
			(roundrect_rratio 0.25)
			(net 1 "GND")
			(pintype "passive")
		)
		(pad "2" smd roundrect
			(at 0.48 0 180)
			(size 0.59 0.64)
			(layers "F.Cu" "F.Mask" "F.Paste")
			(roundrect_rratio 0.25)
			(net 60 "Net-(C101-Pad2)")
			(pintype "passive")
		)
	)
	(footprint "antmicro-footprints:SC70-3"
		(layer "F.Cu")
		(at 87.8 77.33 -90)
		(property "Reference" "Q6"
			(at -0.53 -5.55 90)
			(layer "F.SilkS")
			(effects
				(font
					(size 0.7 0.7)
					(thickness 0.15)
				)
				(justify right bottom)
			)
		)
		(property "Value" "BSS138PW"
			(at 0 2.3 90)
			(layer "F.Fab")
			(effects
				(font
					(size 0.7 0.7)
					(thickness 0.15)
				)
				(justify right bottom)
			)
		)
		(property "Datasheet" "https://assets.nexperia.com/documents/data-sheet/BSS138PW.pdf"
			(at 0 0 270)
			(layer "F.Fab")
			(hide yes)
			(effects
				(font
					(size 1.27 1.27)
					(thickness 0.15)
				)
			)
		)
		(property "Description" "Power MOSFET, N Channel, 60 V, 320 mA, 0.9 ohm, SOT-323, Surface Mount"
			(at 0 0 270)
			(layer "F.Fab")
			(hide yes)
			(effects
				(font
					(size 1.27 1.27)
					(thickness 0.15)
				)
			)
		)
		(property "Author" "Antmicro"
			(at 10.47 165.13 0)
			(layer "F.Fab")
			(hide yes)
			(effects
				(font
					(size 1 1)
					(thickness 0.15)
				)
			)
		)
		(property "License" "Apache-2.0"
			(at 10.47 165.13 0)
			(layer "F.Fab")
			(hide yes)
			(effects
				(font
					(size 1 1)
					(thickness 0.15)
				)
			)
		)
		(property "MPN" "BSS138PW"
			(at 10.47 165.13 0)
			(layer "F.Fab")
			(hide yes)
			(effects
				(font
					(size 1 1)
					(thickness 0.15)
				)
			)
		)
		(property "Manufacturer" "Nexperia"
			(at 10.47 165.13 0)
			(layer "F.Fab")
			(hide yes)
			(effects
				(font
					(size 1 1)
					(thickness 0.15)
				)
			)
		)
		(sheetname "/Power supply/")
		(sheetfile "power-supply.kicad_sch")
		(attr smd)
		(fp_line
			(start -0.3 1)
			(end 0.627 1.001)
			(stroke
				(width 0.15)
				(type solid)
			)
			(layer "F.SilkS")
		)
		(fp_line
			(start 0.627 0.6)
			(end 0.627 1.001)
			(stroke
				(width 0.15)
				(type solid)
			)
			(layer "F.SilkS")
		)
		(fp_line
			(start 0.627 -0.6)
			(end 0.627 -0.999)
			(stroke
				(width 0.15)
				(type solid)
			)
			(layer "F.SilkS")
		)
		(fp_line
			(start -0.3 -1)
			(end 0.627 -0.999)
			(stroke
				(width 0.15)
				(type solid)
			)
			(layer "F.SilkS")
		)
		(fp_line
			(start -0.9 1.3)
			(end -0.9 1)
			(stroke
				(width 0.05)
				(type solid)
			)
			(layer "F.CrtYd")
		)
		(fp_line
			(start 0.9 1.3)
			(end -0.9 1.3)
			(stroke
				(width 0.05)
				(type solid)
			)
			(layer "F.CrtYd")
		)
		(fp_line
			(start -1.4 1)
			(end -1.4 -1)
			(stroke
				(width 0.05)
				(type solid)
			)
			(layer "F.CrtYd")
		)
		(fp_line
			(start -0.9 1)
			(end -1.4 1)
			(stroke
				(width 0.05)
				(type solid)
			)
			(layer "F.CrtYd")
		)
		(fp_line
			(start 0.9 0.4)
			(end 0.9 1.3)
			(stroke
				(width 0.05)
				(type solid)
			)
			(layer "F.CrtYd")
		)
		(fp_line
			(start 1.4 0.4)
			(end 0.9 0.4)
			(stroke
				(width 0.05)
				(type solid)
			)
			(layer "F.CrtYd")
		)
		(fp_line
			(start 0.9 -0.4)
			(end 1.4 -0.4)
			(stroke
				(width 0.05)
				(type solid)
			)
			(layer "F.CrtYd")
		)
		(fp_line
			(start 1.4 -0.4)
			(end 1.4 0.4)
			(stroke
				(width 0.05)
				(type solid)
			)
			(layer "F.CrtYd")
		)
		(fp_line
			(start -0.9 -1)
			(end -1.4 -1)
			(stroke
				(width 0.05)
				(type solid)
			)
			(layer "F.CrtYd")
		)
		(fp_line
			(start -0.9 -1.3)
			(end -0.9 -1)
			(stroke
				(width 0.05)
				(type solid)
			)
			(layer "F.CrtYd")
		)
		(fp_line
			(start -0.9 -1.3)
			(end 0.9 -1.3)
			(stroke
				(width 0.05)
				(type solid)
			)
			(layer "F.CrtYd")
		)
		(fp_line
			(start 0.9 -1.3)
			(end 0.9 -0.4)
			(stroke
				(width 0.05)
				(type solid)
			)
			(layer "F.CrtYd")
		)
		(fp_rect
			(start -0.623 -0.999)
			(end 0.627 1.001)
			(stroke
				(width 0.15)
				(type solid)
			)
			(fill no)
			(layer "F.Fab")
		)
		(pad "1" smd rect
			(at -1.051 -0.65)
			(size 0.6 0.6)
			(layers "F.Cu" "F.Mask" "F.Paste")
			(net 534 "/Power supply/1V2_PG")
			(pinfunction "G")
			(pintype "input")
		)
		(pad "2" smd rect
			(at -1.051 0.65)
			(size 0.6 0.6)
			(layers "F.Cu" "F.Mask" "F.Paste")
			(net 1 "GND")
			(pinfunction "S")
			(pintype "passive")
		)
		(pad "3" smd rect
			(at 1.05 0)
			(size 0.6 0.6)
			(layers "F.Cu" "F.Mask" "F.Paste")
			(net 313 "Net-(D14-C)")
			(pinfunction "D")
			(pintype "passive")
		)
	)
	(footprint "antmicro-footprints:R_0402_1005Metric"
		(layer "F.Cu")
		(at 85.65 76.75)
		(descr "Resistor SMD 0402")
		(tags "resistor SMD 0402")
		(property "Reference" "R189"
			(at 3.75 0.945 0)
			(layer "F.SilkS")
			(effects
				(font
					(size 0.7 0.7)
					(thickness 0.15)
				)
				(justify left bottom)
			)
		)
		(property "Value" "R_10k_0402"
			(at 0 1.4 0)
			(layer "F.Fab")
			(effects
				(font
					(size 0.7 0.7)
					(thickness 0.15)
				)
				(justify left bottom)
			)
		)
		(property "Datasheet" "https://www.bourns.com/docs/product-datasheets/cr.pdf"
			(at 0 0 0)
			(layer "F.Fab")
			(hide yes)
			(effects
				(font
					(size 1.27 1.27)
					(thickness 0.15)
				)
			)
		)
		(property "Description" "SMD Chip Resistor, 10 kohm, ± 1%, 62.5 mW, 0402 [1005 Metric], Thick Film, General Purpose"
			(at 0 0 0)
			(layer "F.Fab")
			(hide yes)
			(effects
				(font
					(size 1.27 1.27)
					(thickness 0.15)
				)
			)
		)
		(property "Author" "Antmicro"
			(at 0 0 0)
			(layer "F.Fab")
			(hide yes)
			(effects
				(font
					(size 1 1)
					(thickness 0.15)
				)
			)
		)
		(property "License" "Apache-2.0"
			(at 0 0 0)
			(layer "F.Fab")
			(hide yes)
			(effects
				(font
					(size 1 1)
					(thickness 0.15)
				)
			)
		)
		(property "MPN" "CR0402-FX-1002GLF"
			(at 0 0 0)
			(layer "F.Fab")
			(hide yes)
			(effects
				(font
					(size 1 1)
					(thickness 0.15)
				)
			)
		)
		(property "Manufacturer" "Bourns"
			(at 0 0 0)
			(layer "F.Fab")
			(hide yes)
			(effects
				(font
					(size 1 1)
					(thickness 0.15)
				)
			)
		)
		(property "Tolerance" "1%"
			(at 0 0 0)
			(layer "F.Fab")
			(hide yes)
			(effects
				(font
					(size 1 1)
					(thickness 0.15)
				)
			)
		)
		(property "Val" "10k"
			(at 0 0 0)
			(layer "F.Fab")
			(hide yes)
			(effects
				(font
					(size 1 1)
					(thickness 0.15)
				)
			)
		)
		(sheetname "/Power supply/")
		(sheetfile "power-supply.kicad_sch")
		(attr smd)
		(fp_rect
			(start -0.925 -0.47)
			(end 0.925 0.47)
			(stroke
				(width 0.05)
				(type default)
			)
			(fill no)
			(layer "F.CrtYd")
		)
		(fp_rect
			(start -0.5 -0.25)
			(end 0.5 0.25)
			(stroke
				(width 0.15)
				(type solid)
			)
			(fill no)
			(layer "F.Fab")
		)
		(pad "1" smd roundrect
			(at -0.48 0)
			(size 0.59 0.64)
			(layers "F.Cu" "F.Mask" "F.Paste")
			(roundrect_rratio 0.25)
			(net 4 "VCC5V0")
			(pintype "passive")
		)
		(pad "2" smd roundrect
			(at 0.48 0)
			(size 0.59 0.64)
			(layers "F.Cu" "F.Mask" "F.Paste")
			(roundrect_rratio 0.25)
			(net 534 "/Power supply/1V2_PG")
			(pintype "passive")
		)
	)
	(footprint "antmicro-footprints:R_0402_1005Metric"
		(layer "F.Cu")
		(at 89.95 75.95)
		(descr "Resistor SMD 0402")
		(tags "resistor SMD 0402")
		(property "Reference" "R185"
			(at 0.95 0.35 0)
			(layer "F.SilkS")
			(effects
				(font
					(size 0.7 0.7)
					(thickness 0.15)
				)
				(justify left bottom)
			)
		)
		(property "Value" "R_0R_0402"
			(at 0 1.4 0)
			(layer "F.Fab")
			(effects
				(font
					(size 0.7 0.7)
					(thickness 0.15)
				)
				(justify left bottom)
			)
		)
		(property "Datasheet" "https://industrial.panasonic.com/cdbs/www-data/pdf/RDA0000/AOA0000C301.pdf"
			(at 0 0 0)
			(layer "F.Fab")
			(hide yes)
			(effects
				(font
					(size 1.27 1.27)
					(thickness 0.15)
				)
			)
		)
		(property "Description" "SMD Chip Resistor, Jumper, 0 ohm, 100 mW, 0402 [1005 Metric], Thick Film, General Purpose"
			(at 0 0 0)
			(layer "F.Fab")
			(hide yes)
			(effects
				(font
					(size 1.27 1.27)
					(thickness 0.15)
				)
			)
		)
		(property "Author" "Antmicro"
			(at 0 0 0)
			(layer "F.Fab")
			(hide yes)
			(effects
				(font
					(size 1 1)
					(thickness 0.15)
				)
			)
		)
		(property "Current" "1A"
			(at 0 0 0)
			(layer "F.Fab")
			(hide yes)
			(effects
				(font
					(size 1 1)
					(thickness 0.15)
				)
			)
		)
		(property "License" "Apache-2.0"
			(at 0 0 0)
			(layer "F.Fab")
			(hide yes)
			(effects
				(font
					(size 1 1)
					(thickness 0.15)
				)
			)
		)
		(property "MPN" "ERJ2GE0R00X"
			(at 0 0 0)
			(layer "F.Fab")
			(hide yes)
			(effects
				(font
					(size 1 1)
					(thickness 0.15)
				)
			)
		)
		(property "Manufacturer" "Panasonic"
			(at 0 0 0)
			(layer "F.Fab")
			(hide yes)
			(effects
				(font
					(size 1 1)
					(thickness 0.15)
				)
			)
		)
		(property "Tolerance" "~"
			(at 0 0 0)
			(layer "F.Fab")
			(hide yes)
			(effects
				(font
					(size 1 1)
					(thickness 0.15)
				)
			)
		)
		(property "Val" "0R"
			(at 0 0 0)
			(layer "F.Fab")
			(hide yes)
			(effects
				(font
					(size 1 1)
					(thickness 0.15)
				)
			)
		)
		(sheetname "/Power supply/")
		(sheetfile "power-supply.kicad_sch")
		(attr smd)
		(fp_rect
			(start -0.925 -0.47)
			(end 0.925 0.47)
			(stroke
				(width 0.05)
				(type default)
			)
			(fill no)
			(layer "F.CrtYd")
		)
		(fp_rect
			(start -0.5 -0.25)
			(end 0.5 0.25)
			(stroke
				(width 0.15)
				(type solid)
			)
			(fill no)
			(layer "F.Fab")
		)
		(pad "1" smd roundrect
			(at -0.48 0)
			(size 0.59 0.64)
			(layers "F.Cu" "F.Mask" "F.Paste")
			(roundrect_rratio 0.25)
			(net 347 "Net-(U16-EN)")
			(pintype "passive")
		)
		(pad "2" smd roundrect
			(at 0.48 0)
			(size 0.59 0.64)
			(layers "F.Cu" "F.Mask" "F.Paste")
			(roundrect_rratio 0.25)
			(net 297 "/Power supply/VCCIO_EN")
			(pintype "passive")
		)
	)
	(footprint "antmicro-footprints:R_0402_1005Metric"
		(layer "F.Cu")
		(at 90.525 74.4 -90)
		(descr "Resistor SMD 0402")
		(tags "resistor SMD 0402")
		(property "Reference" "R186"
			(at -1.8 -3.475 90)
			(layer "F.SilkS")
			(effects
				(font
					(size 0.7 0.7)
					(thickness 0.15)
				)
				(justify right bottom)
			)
		)
		(property "Value" "R_100k_0402"
			(at 0 1.4 90)
			(layer "F.Fab")
			(effects
				(font
					(size 0.7 0.7)
					(thickness 0.15)
				)
				(justify right bottom)
			)
		)
		(property "Datasheet" "https://www.bourns.com/docs/product-datasheets/cr.pdf"
			(at 0 0 270)
			(layer "F.Fab")
			(hide yes)
			(effects
				(font
					(size 1.27 1.27)
					(thickness 0.15)
				)
			)
		)
		(property "Description" "SMD Chip Resistor, 100 kohm, ± 1%, 62.5 mW, 0402 [1005 Metric], Thick Film, General Purpose"
			(at 0 0 270)
			(layer "F.Fab")
			(hide yes)
			(effects
				(font
					(size 1.27 1.27)
					(thickness 0.15)
				)
			)
		)
		(property "Author" "Antmicro"
			(at 16.125 164.925 0)
			(layer "F.Fab")
			(hide yes)
			(effects
				(font
					(size 1 1)
					(thickness 0.15)
				)
			)
		)
		(property "License" "Apache-2.0"
			(at 16.125 164.925 0)
			(layer "F.Fab")
			(hide yes)
			(effects
				(font
					(size 1 1)
					(thickness 0.15)
				)
			)
		)
		(property "MPN" "CR0402-FX-1003GLF"
			(at 16.125 164.925 0)
			(layer "F.Fab")
			(hide yes)
			(effects
				(font
					(size 1 1)
					(thickness 0.15)
				)
			)
		)
		(property "Manufacturer" "Bourns"
			(at 16.125 164.925 0)
			(layer "F.Fab")
			(hide yes)
			(effects
				(font
					(size 1 1)
					(thickness 0.15)
				)
			)
		)
		(property "Tolerance" "1%"
			(at 16.125 164.925 0)
			(layer "F.Fab")
			(hide yes)
			(effects
				(font
					(size 1 1)
					(thickness 0.15)
				)
			)
		)
		(property "Val" "100k"
			(at 16.125 164.925 0)
			(layer "F.Fab")
			(hide yes)
			(effects
				(font
					(size 1 1)
					(thickness 0.15)
				)
			)
		)
		(sheetname "/Power supply/")
		(sheetfile "power-supply.kicad_sch")
		(attr smd)
		(fp_rect
			(start -0.925 -0.47)
			(end 0.925 0.47)
			(stroke
				(width 0.05)
				(type default)
			)
			(fill no)
			(layer "F.CrtYd")
		)
		(fp_rect
			(start -0.5 -0.25)
			(end 0.5 0.25)
			(stroke
				(width 0.15)
				(type solid)
			)
			(fill no)
			(layer "F.Fab")
		)
		(pad "1" smd roundrect
			(at -0.48 0 270)
			(size 0.59 0.64)
			(layers "F.Cu" "F.Mask" "F.Paste")
			(roundrect_rratio 0.25)
			(net 60 "Net-(C101-Pad2)")
			(pintype "passive")
		)
		(pad "2" smd roundrect
			(at 0.48 0 270)
			(size 0.59 0.64)
			(layers "F.Cu" "F.Mask" "F.Paste")
			(roundrect_rratio 0.25)
			(net 10 "Net-(U16-FB)")
			(pintype "passive")
		)
	)
	(footprint "antmicro-footprints:C_0603_1608Metric"
		(layer "F.Cu")
		(at 85 74.35 -90)
		(descr "Capacitor SMD 0603")
		(tags "capacitor 0603")
		(property "Reference" "C2"
			(at 1.45 0.5 270)
			(layer "F.SilkS")
			(effects
				(font
					(size 0.7 0.7)
					(thickness 0.15)
				)
				(justify left bottom)
			)
		)
		(property "Value" "C_10u_0603"
			(at 0 1.6 270)
			(layer "F.Fab")
			(effects
				(font
					(size 0.7 0.7)
					(thickness 0.15)
				)
				(justify left bottom)
			)
		)
		(property "Datasheet" "https://www.murata.com/products/productdetail?partno=GRM188R61A106KE69%23"
			(at 0 0 270)
			(layer "F.Fab")
			(hide yes)
			(effects
				(font
					(size 1.27 1.27)
					(thickness 0.15)
				)
			)
		)
		(property "Description" "SMD Multilayer Ceramic Capacitor, 10 µF, 10 V, 0603 [1608 Metric], ± 10%, X5R, GRM Series"
			(at 0 0 270)
			(layer "F.Fab")
			(hide yes)
			(effects
				(font
					(size 1.27 1.27)
					(thickness 0.15)
				)
			)
		)
		(property "Author" "Antmicro"
			(at 10.65 159.35 0)
			(layer "F.Fab")
			(hide yes)
			(effects
				(font
					(size 1 1)
					(thickness 0.15)
				)
			)
		)
		(property "Dielectric" "template_dielectric"
			(at 10.65 159.35 0)
			(layer "F.Fab")
			(hide yes)
			(effects
				(font
					(size 1 1)
					(thickness 0.15)
				)
			)
		)
		(property "License" "Apache-2.0"
			(at 10.65 159.35 0)
			(layer "F.Fab")
			(hide yes)
			(effects
				(font
					(size 1 1)
					(thickness 0.15)
				)
			)
		)
		(property "MPN" "GRM188R61A106KE69D"
			(at 10.65 159.35 0)
			(layer "F.Fab")
			(hide yes)
			(effects
				(font
					(size 1 1)
					(thickness 0.15)
				)
			)
		)
		(property "Manufacturer" "Murata"
			(at 10.65 159.35 0)
			(layer "F.Fab")
			(hide yes)
			(effects
				(font
					(size 1 1)
					(thickness 0.15)
				)
			)
		)
		(property "Val" "10u"
			(at 10.65 159.35 0)
			(layer "F.Fab")
			(hide yes)
			(effects
				(font
					(size 1 1)
					(thickness 0.15)
				)
			)
		)
		(property "Voltage" ""
			(at 10.65 159.35 0)
			(layer "F.Fab")
			(hide yes)
			(effects
				(font
					(size 1 1)
					(thickness 0.15)
				)
			)
		)
		(sheetname "/Power supply/")
		(sheetfile "power-supply.kicad_sch")
		(attr smd)
		(fp_line
			(start -0.15 0.4)
			(end 0.15 0.4)
			(stroke
				(width 0.15)
				(type solid)
			)
			(layer "F.SilkS")
		)
		(fp_line
			(start -0.15 -0.4)
			(end 0.15 -0.4)
			(stroke
				(width 0.15)
				(type solid)
			)
			(layer "F.SilkS")
		)
		(fp_rect
			(start -1.25 -0.65)
			(end 1.25 0.65)
			(stroke
				(width 0.05)
				(type solid)
			)
			(fill no)
			(layer "F.CrtYd")
		)
		(fp_rect
			(start -0.8 -0.4)
			(end 0.8 0.4)
			(stroke
				(width 0.15)
				(type solid)
			)
			(fill no)
			(layer "F.Fab")
		)
		(pad "1" smd roundrect
			(at -0.7 0 270)
			(size 0.8 1)
			(layers "F.Cu" "F.Mask" "F.Paste")
			(roundrect_rratio 0.2)
			(net 1 "GND")
			(pintype "passive")
		)
		(pad "2" smd roundrect
			(at 0.7 0 270)
			(size 0.8 1)
			(layers "F.Cu" "F.Mask" "F.Paste")
			(roundrect_rratio 0.2)
			(net 4 "VCC5V0")
			(pintype "passive")
		)
	)
	(footprint "antmicro-footprints:R_0402_1005Metric"
		(layer "F.Cu")
		(at 73.515 165.865 90)
		(descr "Resistor SMD 0402")
		(tags "resistor SMD 0402")
		(property "Reference" "R53"
			(at -0.935 -1.515 90)
			(layer "F.SilkS")
			(effects
				(font
					(size 0.7 0.7)
					(thickness 0.15)
				)
				(justify left bottom)
			)
		)
		(property "Value" "R_200k_0402"
			(at 0 1.4 90)
			(layer "F.Fab")
			(effects
				(font
					(size 0.7 0.7)
					(thickness 0.15)
				)
				(justify left bottom)
			)
		)
		(property "Datasheet" "https://www.bourns.com/docs/product-datasheets/cr.pdf"
			(at 0 0 90)
			(layer "F.Fab")
			(hide yes)
			(effects
				(font
					(size 1.27 1.27)
					(thickness 0.15)
				)
			)
		)
		(property "Description" "SMD Chip Resistor, 200 kohm, ± 1%, 62.5 mW, 0402 [1005 Metric], Thick Film, General Purpose"
			(at 0 0 90)
			(layer "F.Fab")
			(hide yes)
			(effects
				(font
					(size 1.27 1.27)
					(thickness 0.15)
				)
			)
		)
		(property "Author" "Antmicro"
			(at 239.38 92.35 0)
			(layer "F.Fab")
			(hide yes)
			(effects
				(font
					(size 1 1)
					(thickness 0.15)
				)
			)
		)
		(property "License" "Apache-2.0"
			(at 239.38 92.35 0)
			(layer "F.Fab")
			(hide yes)
			(effects
				(font
					(size 1 1)
					(thickness 0.15)
				)
			)
		)
		(property "MPN" "CR0402-FX-2003GLF"
			(at 239.38 92.35 0)
			(layer "F.Fab")
			(hide yes)
			(effects
				(font
					(size 1 1)
					(thickness 0.15)
				)
			)
		)
		(property "Manufacturer" "Bourns"
			(at 239.38 92.35 0)
			(layer "F.Fab")
			(hide yes)
			(effects
				(font
					(size 1 1)
					(thickness 0.15)
				)
			)
		)
		(property "Tolerance" "1%"
			(at 239.38 92.35 0)
			(layer "F.Fab")
			(hide yes)
			(effects
				(font
					(size 1 1)
					(thickness 0.15)
				)
			)
		)
		(property "Val" "200k"
			(at 239.38 92.35 0)
			(layer "F.Fab")
			(hide yes)
			(effects
				(font
					(size 1 1)
					(thickness 0.15)
				)
			)
		)
		(sheetname "/Interfaces/")
		(sheetfile "interfaces.kicad_sch")
		(attr smd)
		(fp_rect
			(start -0.925 -0.47)
			(end 0.925 0.47)
			(stroke
				(width 0.05)
				(type default)
			)
			(fill no)
			(layer "F.CrtYd")
		)
		(fp_rect
			(start -0.5 -0.25)
			(end 0.5 0.25)
			(stroke
				(width 0.15)
				(type solid)
			)
			(fill no)
			(layer "F.Fab")
		)
		(pad "1" smd roundrect
			(at -0.48 0 90)
			(size 0.59 0.64)
			(layers "F.Cu" "F.Mask" "F.Paste")
			(roundrect_rratio 0.25)
			(net 538 "1V0_PG")
			(pintype "passive")
		)
		(pad "2" smd roundrect
			(at 0.48 0 90)
			(size 0.59 0.64)
			(layers "F.Cu" "F.Mask" "F.Paste")
			(roundrect_rratio 0.25)
			(net 7 "/Interfaces/1V0_EN")
			(pintype "passive")
		)
	)
	(footprint "antmicro-footprints:C_0402_1005Metric"
		(layer "F.Cu")
		(at 74.515 165.865 90)
		(descr "Capacitor SMD 0402")
		(tags "capacitor SMD 0402")
		(property "Reference" "C39"
			(at -0.934 -1.515 90)
			(layer "F.SilkS")
			(effects
				(font
					(size 0.7 0.7)
					(thickness 0.15)
				)
				(justify left bottom)
			)
		)
		(property "Value" "C_100n_6V3_0402"
			(at 0 1.4 90)
			(layer "F.Fab")
			(effects
				(font
					(size 0.7 0.7)
					(thickness 0.15)
				)
				(justify left bottom)
			)
		)
		(property "Datasheet" "https://www.passivecomponent.com/wp-content/uploads/datasheet/WTC_MLCC_General_Purpose.pdf"
			(at 0 0 90)
			(layer "F.Fab")
			(hide yes)
			(effects
				(font
					(size 1.27 1.27)
					(thickness 0.15)
				)
			)
		)
		(property "Description" "SMT Multilayer Ceramic Capacitor, 0.1 µF, 6.3 V, 0402 [1005 Metric], ± 10%, X5R, Walsin MLCC"
			(at 0 0 90)
			(layer "F.Fab")
			(hide yes)
			(effects
				(font
					(size 1.27 1.27)
					(thickness 0.15)
				)
			)
		)
		(property "Author" "Antmicro"
			(at 240.38 91.35 0)
			(layer "F.Fab")
			(hide yes)
			(effects
				(font
					(size 1 1)
					(thickness 0.15)
				)
			)
		)
		(property "Dielectric" ""
			(at 240.38 91.35 0)
			(layer "F.Fab")
			(hide yes)
			(effects
				(font
					(size 1 1)
					(thickness 0.15)
				)
			)
		)
		(property "License" "Apache-2.0"
			(at 240.38 91.35 0)
			(layer "F.Fab")
			(hide yes)
			(effects
				(font
					(size 1 1)
					(thickness 0.15)
				)
			)
		)
		(property "MPN" "0402X104K6R3CT"
			(at 240.38 91.35 0)
			(layer "F.Fab")
			(hide yes)
			(effects
				(font
					(size 1 1)
					(thickness 0.15)
				)
			)
		)
		(property "Manufacturer" "Walsin"
			(at 240.38 91.35 0)
			(layer "F.Fab")
			(hide yes)
			(effects
				(font
					(size 1 1)
					(thickness 0.15)
				)
			)
		)
		(property "Public" "False"
			(at 240.38 91.35 0)
			(layer "F.Fab")
			(hide yes)
			(effects
				(font
					(size 1 1)
					(thickness 0.15)
				)
			)
		)
		(property "Val" "100n"
			(at 240.38 91.35 0)
			(layer "F.Fab")
			(hide yes)
			(effects
				(font
					(size 1 1)
					(thickness 0.15)
				)
			)
		)
		(property "Voltage" ""
			(at 240.38 91.35 0)
			(layer "F.Fab")
			(hide yes)
			(effects
				(font
					(size 1 1)
					(thickness 0.15)
				)
			)
		)
		(sheetname "/Interfaces/")
		(sheetfile "interfaces.kicad_sch")
		(attr smd)
		(fp_rect
			(start -0.925 -0.47)
			(end 0.925 0.47)
			(stroke
				(width 0.05)
				(type default)
			)
			(fill no)
			(layer "F.CrtYd")
		)
		(fp_line
			(start 0.504 -0.25)
			(end 0.504 0.248)
			(stroke
				(width 0.15)
				(type solid)
			)
			(layer "F.Fab")
		)
		(fp_line
			(start -0.494 -0.25)
			(end 0.504 -0.25)
			(stroke
				(width 0.15)
				(type solid)
			)
			(layer "F.Fab")
		)
		(fp_line
			(start 0.504 0.248)
			(end -0.494 0.248)
			(stroke
				(width 0.15)
				(type solid)
			)
			(layer "F.Fab")
		)
		(fp_line
			(start -0.494 0.248)
			(end -0.494 -0.25)
			(stroke
				(width 0.15)
				(type solid)
			)
			(layer "F.Fab")
		)
		(pad "1" smd roundrect
			(at -0.48 0 90)
			(size 0.59 0.64)
			(layers "F.Cu" "F.Mask" "F.Paste")
			(roundrect_rratio 0.25)
			(net 1 "GND")
			(pintype "passive")
		)
		(pad "2" smd roundrect
			(at 0.48 0 90)
			(size 0.59 0.64)
			(layers "F.Cu" "F.Mask" "F.Paste")
			(roundrect_rratio 0.25)
			(net 7 "/Interfaces/1V0_EN")
			(pintype "passive")
		)
	)
	(footprint "antmicro-footprints:C_0603_1608Metric"
		(layer "F.Cu")
		(at 82.565 68.8 -90)
		(descr "Capacitor SMD 0603")
		(tags "capacitor 0603")
		(property "Reference" "C74"
			(at -1.625 17.154 90)
			(layer "F.SilkS")
			(effects
				(font
					(size 0.7 0.7)
					(thickness 0.15)
				)
				(justify right bottom)
			)
		)
		(property "Value" "C_47u_0603"
			(at 0 1.6 90)
			(layer "F.Fab")
			(effects
				(font
					(size 0.7 0.7)
					(thickness 0.15)
				)
				(justify right bottom)
			)
		)
		(property "Datasheet" "https://www.murata.com/products/productdetail?partno=GRM188R60J476ME15%23"
			(at 0 0 270)
			(layer "F.Fab")
			(hide yes)
			(effects
				(font
					(size 1.27 1.27)
					(thickness 0.15)
				)
			)
		)
		(property "Description" "SMD Multilayer Ceramic Capacitor, 47 µF, 6.3 V, 0603 [1608 Metric], ± 20%, X5R, GRM Series"
			(at 0 0 270)
			(layer "F.Fab")
			(hide yes)
			(effects
				(font
					(size 1.27 1.27)
					(thickness 0.15)
				)
			)
		)
		(property "Author" "Antmicro"
			(at 13.765 151.365 0)
			(layer "F.Fab")
			(hide yes)
			(effects
				(font
					(size 1 1)
					(thickness 0.15)
				)
			)
		)
		(property "Dielectric" ""
			(at 13.765 151.365 0)
			(layer "F.Fab")
			(hide yes)
			(effects
				(font
					(size 1 1)
					(thickness 0.15)
				)
			)
		)
		(property "License" "Apache-2.0"
			(at 13.765 151.365 0)
			(layer "F.Fab")
			(hide yes)
			(effects
				(font
					(size 1 1)
					(thickness 0.15)
				)
			)
		)
		(property "MPN" "GRM188R60J476ME15D"
			(at 13.765 151.365 0)
			(layer "F.Fab")
			(hide yes)
			(effects
				(font
					(size 1 1)
					(thickness 0.15)
				)
			)
		)
		(property "Manufacturer" "Murata"
			(at 13.765 151.365 0)
			(layer "F.Fab")
			(hide yes)
			(effects
				(font
					(size 1 1)
					(thickness 0.15)
				)
			)
		)
		(property "Val" "47u"
			(at 13.765 151.365 0)
			(layer "F.Fab")
			(hide yes)
			(effects
				(font
					(size 1 1)
					(thickness 0.15)
				)
			)
		)
		(property "Voltage" ""
			(at 13.765 151.365 0)
			(layer "F.Fab")
			(hide yes)
			(effects
				(font
					(size 1 1)
					(thickness 0.15)
				)
			)
		)
		(sheetname "/Power supply/")
		(sheetfile "power-supply.kicad_sch")
		(attr smd)
		(fp_line
			(start -0.15 0.4)
			(end 0.15 0.4)
			(stroke
				(width 0.15)
				(type solid)
			)
			(layer "F.SilkS")
		)
		(fp_line
			(start -0.15 -0.4)
			(end 0.15 -0.4)
			(stroke
				(width 0.15)
				(type solid)
			)
			(layer "F.SilkS")
		)
		(fp_rect
			(start -1.25 -0.65)
			(end 1.25 0.65)
			(stroke
				(width 0.05)
				(type solid)
			)
			(fill no)
			(layer "F.CrtYd")
		)
		(fp_rect
			(start -0.8 -0.4)
			(end 0.8 0.4)
			(stroke
				(width 0.15)
				(type solid)
			)
			(fill no)
			(layer "F.Fab")
		)
		(pad "1" smd roundrect
			(at -0.7 0 270)
			(size 0.8 1)
			(layers "F.Cu" "F.Mask" "F.Paste")
			(roundrect_rratio 0.2)
			(net 1 "GND")
			(pintype "passive")
		)
		(pad "2" smd roundrect
			(at 0.7 0 270)
			(size 0.8 1)
			(layers "F.Cu" "F.Mask" "F.Paste")
			(roundrect_rratio 0.2)
			(net 114 "Net-(C72-Pad2)")
			(pintype "passive")
		)
	)
	(footprint "antmicro-footprints:C_0603_1608Metric"
		(layer "F.Cu")
		(at 81.115 68.8 -90)
		(descr "Capacitor SMD 0603")
		(tags "capacitor 0603")
		(property "Reference" "C73"
			(at -1.625 16.804 90)
			(layer "F.SilkS")
			(effects
				(font
					(size 0.7 0.7)
					(thickness 0.15)
				)
				(justify right bottom)
			)
		)
		(property "Value" "C_47u_0603"
			(at 0 1.6 90)
			(layer "F.Fab")
			(effects
				(font
					(size 0.7 0.7)
					(thickness 0.15)
				)
				(justify right bottom)
			)
		)
		(property "Datasheet" "https://www.murata.com/products/productdetail?partno=GRM188R60J476ME15%23"
			(at 0 0 270)
			(layer "F.Fab")
			(hide yes)
			(effects
				(font
					(size 1.27 1.27)
					(thickness 0.15)
				)
			)
		)
		(property "Description" "SMD Multilayer Ceramic Capacitor, 47 µF, 6.3 V, 0603 [1608 Metric], ± 20%, X5R, GRM Series"
			(at 0 0 270)
			(layer "F.Fab")
			(hide yes)
			(effects
				(font
					(size 1.27 1.27)
					(thickness 0.15)
				)
			)
		)
		(property "Author" "Antmicro"
			(at 12.315 149.915 0)
			(layer "F.Fab")
			(hide yes)
			(effects
				(font
					(size 1 1)
					(thickness 0.15)
				)
			)
		)
		(property "Dielectric" ""
			(at 12.315 149.915 0)
			(layer "F.Fab")
			(hide yes)
			(effects
				(font
					(size 1 1)
					(thickness 0.15)
				)
			)
		)
		(property "License" "Apache-2.0"
			(at 12.315 149.915 0)
			(layer "F.Fab")
			(hide yes)
			(effects
				(font
					(size 1 1)
					(thickness 0.15)
				)
			)
		)
		(property "MPN" "GRM188R60J476ME15D"
			(at 12.315 149.915 0)
			(layer "F.Fab")
			(hide yes)
			(effects
				(font
					(size 1 1)
					(thickness 0.15)
				)
			)
		)
		(property "Manufacturer" "Murata"
			(at 12.315 149.915 0)
			(layer "F.Fab")
			(hide yes)
			(effects
				(font
					(size 1 1)
					(thickness 0.15)
				)
			)
		)
		(property "Val" "47u"
			(at 12.315 149.915 0)
			(layer "F.Fab")
			(hide yes)
			(effects
				(font
					(size 1 1)
					(thickness 0.15)
				)
			)
		)
		(property "Voltage" ""
			(at 12.315 149.915 0)
			(layer "F.Fab")
			(hide yes)
			(effects
				(font
					(size 1 1)
					(thickness 0.15)
				)
			)
		)
		(sheetname "/Power supply/")
		(sheetfile "power-supply.kicad_sch")
		(attr smd)
		(fp_line
			(start -0.15 0.4)
			(end 0.15 0.4)
			(stroke
				(width 0.15)
				(type solid)
			)
			(layer "F.SilkS")
		)
		(fp_line
			(start -0.15 -0.4)
			(end 0.15 -0.4)
			(stroke
				(width 0.15)
				(type solid)
			)
			(layer "F.SilkS")
		)
		(fp_rect
			(start -1.25 -0.65)
			(end 1.25 0.65)
			(stroke
				(width 0.05)
				(type solid)
			)
			(fill no)
			(layer "F.CrtYd")
		)
		(fp_rect
			(start -0.8 -0.4)
			(end 0.8 0.4)
			(stroke
				(width 0.15)
				(type solid)
			)
			(fill no)
			(layer "F.Fab")
		)
		(pad "1" smd roundrect
			(at -0.7 0 270)
			(size 0.8 1)
			(layers "F.Cu" "F.Mask" "F.Paste")
			(roundrect_rratio 0.2)
			(net 1 "GND")
			(pintype "passive")
		)
		(pad "2" smd roundrect
			(at 0.7 0 270)
			(size 0.8 1)
			(layers "F.Cu" "F.Mask" "F.Paste")
			(roundrect_rratio 0.2)
			(net 114 "Net-(C72-Pad2)")
			(pintype "passive")
		)
	)
	(footprint "antmicro-footprints:C_0603_1608Metric"
		(layer "F.Cu")
		(at 79.64 68.8 -90)
		(descr "Capacitor SMD 0603")
		(tags "capacitor 0603")
		(property "Reference" "C72"
			(at -1.625 16.44 90)
			(layer "F.SilkS")
			(effects
				(font
					(size 0.7 0.7)
					(thickness 0.15)
				)
				(justify right bottom)
			)
		)
		(property "Value" "C_47u_0603"
			(at 0 1.6 90)
			(layer "F.Fab")
			(effects
				(font
					(size 0.7 0.7)
					(thickness 0.15)
				)
				(justify right bottom)
			)
		)
		(property "Datasheet" "https://www.murata.com/products/productdetail?partno=GRM188R60J476ME15%23"
			(at 0 0 270)
			(layer "F.Fab")
			(hide yes)
			(effects
				(font
					(size 1.27 1.27)
					(thickness 0.15)
				)
			)
		)
		(property "Description" "SMD Multilayer Ceramic Capacitor, 47 µF, 6.3 V, 0603 [1608 Metric], ± 20%, X5R, GRM Series"
			(at 0 0 270)
			(layer "F.Fab")
			(hide yes)
			(effects
				(font
					(size 1.27 1.27)
					(thickness 0.15)
				)
			)
		)
		(property "Author" "Antmicro"
			(at 10.84 148.44 0)
			(layer "F.Fab")
			(hide yes)
			(effects
				(font
					(size 1 1)
					(thickness 0.15)
				)
			)
		)
		(property "Dielectric" ""
			(at 10.84 148.44 0)
			(layer "F.Fab")
			(hide yes)
			(effects
				(font
					(size 1 1)
					(thickness 0.15)
				)
			)
		)
		(property "License" "Apache-2.0"
			(at 10.84 148.44 0)
			(layer "F.Fab")
			(hide yes)
			(effects
				(font
					(size 1 1)
					(thickness 0.15)
				)
			)
		)
		(property "MPN" "GRM188R60J476ME15D"
			(at 10.84 148.44 0)
			(layer "F.Fab")
			(hide yes)
			(effects
				(font
					(size 1 1)
					(thickness 0.15)
				)
			)
		)
		(property "Manufacturer" "Murata"
			(at 10.84 148.44 0)
			(layer "F.Fab")
			(hide yes)
			(effects
				(font
					(size 1 1)
					(thickness 0.15)
				)
			)
		)
		(property "Val" "47u"
			(at 10.84 148.44 0)
			(layer "F.Fab")
			(hide yes)
			(effects
				(font
					(size 1 1)
					(thickness 0.15)
				)
			)
		)
		(property "Voltage" ""
			(at 10.84 148.44 0)
			(layer "F.Fab")
			(hide yes)
			(effects
				(font
					(size 1 1)
					(thickness 0.15)
				)
			)
		)
		(sheetname "/Power supply/")
		(sheetfile "power-supply.kicad_sch")
		(attr smd)
		(fp_line
			(start -0.15 0.4)
			(end 0.15 0.4)
			(stroke
				(width 0.15)
				(type solid)
			)
			(layer "F.SilkS")
		)
		(fp_line
			(start -0.15 -0.4)
			(end 0.15 -0.4)
			(stroke
				(width 0.15)
				(type solid)
			)
			(layer "F.SilkS")
		)
		(fp_rect
			(start -1.25 -0.65)
			(end 1.25 0.65)
			(stroke
				(width 0.05)
				(type solid)
			)
			(fill no)
			(layer "F.CrtYd")
		)
		(fp_rect
			(start -0.8 -0.4)
			(end 0.8 0.4)
			(stroke
				(width 0.15)
				(type solid)
			)
			(fill no)
			(layer "F.Fab")
		)
		(pad "1" smd roundrect
			(at -0.7 0 270)
			(size 0.8 1)
			(layers "F.Cu" "F.Mask" "F.Paste")
			(roundrect_rratio 0.2)
			(net 1 "GND")
			(pintype "passive")
		)
		(pad "2" smd roundrect
			(at 0.7 0 270)
			(size 0.8 1)
			(layers "F.Cu" "F.Mask" "F.Paste")
			(roundrect_rratio 0.2)
			(net 114 "Net-(C72-Pad2)")
			(pintype "passive")
		)
	)
	(footprint "antmicro-footprints:L_WE-PDF-1064"
		(layer "F.Cu")
		(at 71 71.705)
		(property "Reference" "L1"
			(at -3.78 -5.475 180)
			(layer "F.SilkS")
			(effects
				(font
					(size 0.7 0.7)
					(thickness 0.15)
				)
				(justify left bottom)
			)
		)
		(property "Value" "L_7u2_7.9A_WE-PDF-1064"
			(at -5.6 6.6 180)
			(layer "F.Fab")
			(effects
				(font
					(size 0.7 0.7)
					(thickness 0.15)
				)
				(justify left bottom)
			)
		)
		(property "Datasheet" "https://www.we-online.com/catalog/datasheet/7447798720.pdf"
			(at 0 0 0)
			(layer "F.Fab")
			(hide yes)
			(effects
				(font
					(size 1.27 1.27)
					(thickness 0.15)
				)
			)
		)
		(property "Description" "Power Inductor (SMD), 7.2 µH, 7.9 A, Shielded, 6 A, WE-PDF"
			(at 0 0 0)
			(layer "F.Fab")
			(hide yes)
			(effects
				(font
					(size 1.27 1.27)
					(thickness 0.15)
				)
			)
		)
		(property "Author" "Antmicro"
			(at 0 0 0)
			(layer "F.Fab")
			(hide yes)
			(effects
				(font
					(size 1 1)
					(thickness 0.15)
				)
			)
		)
		(property "IMax" "7.9 A"
			(at 0 0 0)
			(layer "F.Fab")
			(hide yes)
			(effects
				(font
					(size 1 1)
					(thickness 0.15)
				)
			)
		)
		(property "ISat" "6 A"
			(at 0 0 0)
			(layer "F.Fab")
			(hide yes)
			(effects
				(font
					(size 1 1)
					(thickness 0.15)
				)
			)
		)
		(property "License" "Apache-2.0"
			(at 0 0 0)
			(layer "F.Fab")
			(hide yes)
			(effects
				(font
					(size 1 1)
					(thickness 0.15)
				)
			)
		)
		(property "MPN" "7447798720"
			(at 0 0 0)
			(layer "F.Fab")
			(hide yes)
			(effects
				(font
					(size 1 1)
					(thickness 0.15)
				)
			)
		)
		(property "Manufacturer" "Würth Elektronik"
			(at 0 0 0)
			(layer "F.Fab")
			(hide yes)
			(effects
				(font
					(size 1 1)
					(thickness 0.15)
				)
			)
		)
		(property "Size" "10.2x10.2"
			(at 0 0 0)
			(layer "F.Fab")
			(hide yes)
			(effects
				(font
					(size 1 1)
					(thickness 0.15)
				)
			)
		)
		(property "Val" "7u2/7.9A"
			(at 0 0 0)
			(layer "F.Fab")
			(hide yes)
			(effects
				(font
					(size 1 1)
					(thickness 0.15)
				)
			)
		)
		(sheetname "/Power supply/")
		(sheetfile "power-supply.kicad_sch")
		(attr smd)
		(fp_line
			(start -5.225 -5.225)
			(end 4.125 -5.225)
			(stroke
				(width 0.15)
				(type solid)
			)
			(layer "F.SilkS")
		)
		(fp_line
			(start -5.225 -1.925)
			(end -5.225 -5.225)
			(stroke
				(width 0.15)
				(type solid)
			)
			(layer "F.SilkS")
		)
		(fp_line
			(start -5.225 5.225)
			(end -5.225 1.925)
			(stroke
				(width 0.15)
				(type solid)
			)
			(layer "F.SilkS")
		)
		(fp_line
			(start 4.125 -5.225)
			(end 5.225 -4.125)
			(stroke
				(width 0.15)
				(type solid)
			)
			(layer "F.SilkS")
		)
		(fp_line
			(start 5.225 -4.125)
			(end 5.225 -1.925)
			(stroke
				(width 0.15)
				(type solid)
			)
			(layer "F.SilkS")
		)
		(fp_line
			(start 5.225 1.925)
			(end 5.225 5.225)
			(stroke
				(width 0.15)
				(type solid)
			)
			(layer "F.SilkS")
		)
		(fp_line
			(start 5.225 5.225)
			(end -5.225 5.225)
			(stroke
				(width 0.15)
				(type solid)
			)
			(layer "F.SilkS")
		)
		(fp_line
			(start -5.55 -1.95)
			(end -5.55 1.95)
			(stroke
				(width 0.05)
				(type solid)
			)
			(layer "F.CrtYd")
		)
		(fp_line
			(start -5.55 1.95)
			(end -5.35 1.95)
			(stroke
				(width 0.05)
				(type solid)
			)
			(layer "F.CrtYd")
		)
		(fp_line
			(start -5.35 -5.35)
			(end -5.35 -1.95)
			(stroke
				(width 0.05)
				(type solid)
			)
			(layer "F.CrtYd")
		)
		(fp_line
			(start -5.35 -1.95)
			(end -5.55 -1.95)
			(stroke
				(width 0.05)
				(type solid)
			)
			(layer "F.CrtYd")
		)
		(fp_line
			(start -5.35 1.95)
			(end -5.35 5.35)
			(stroke
				(width 0.05)
				(type solid)
			)
			(layer "F.CrtYd")
		)
		(fp_line
			(start -5.35 5.35)
			(end 5.35 5.35)
			(stroke
				(width 0.05)
				(type solid)
			)
			(layer "F.CrtYd")
		)
		(fp_line
			(start 5.35 -5.35)
			(end -5.35 -5.35)
			(stroke
				(width 0.05)
				(type solid)
			)
			(layer "F.CrtYd")
		)
		(fp_line
			(start 5.35 -1.95)
			(end 5.35 -5.35)
			(stroke
				(width 0.05)
				(type solid)
			)
			(layer "F.CrtYd")
		)
		(fp_line
			(start 5.35 1.95)
			(end 5.55 1.95)
			(stroke
				(width 0.05)
				(type solid)
			)
			(layer "F.CrtYd")
		)
		(fp_line
			(start 5.35 5.35)
			(end 5.35 1.95)
			(stroke
				(width 0.05)
				(type solid)
			)
			(layer "F.CrtYd")
		)
		(fp_line
			(start 5.55 -1.95)
			(end 5.35 -1.95)
			(stroke
				(width 0.05)
				(type solid)
			)
			(layer "F.CrtYd")
		)
		(fp_line
			(start 5.55 -1.95)
			(end 5.55 1.95)
			(stroke
				(width 0.05)
				(type solid)
			)
			(layer "F.CrtYd")
		)
		(fp_rect
			(start -5.101 -5.101)
			(end 5.099 5.099)
			(stroke
				(width 0.15)
				(type solid)
			)
			(fill no)
			(layer "F.Fab")
		)
		(pad "1" smd roundrect
			(at -4.1 0 90)
			(size 3.4 2.4)
			(layers "F.Cu" "F.Mask" "F.Paste")
			(roundrect_rratio 0.1)
			(net 8 "Net-(D3-C)")
			(pintype "passive")
		)
		(pad "2" smd roundrect
			(at 4.1 0 90)
			(size 3.4 2.4)
			(layers "F.Cu" "F.Mask" "F.Paste")
			(roundrect_rratio 0.1)
			(net 114 "Net-(C72-Pad2)")
			(pintype "passive")
		)
	)
	(footprint "antmicro-footprints:R_1206_3216Metric"
		(layer "F.Cu")
		(at 79 76.3 180)
		(property "Reference" "R69"
			(at -0.2 1.105 0)
			(layer "F.SilkS")
			(effects
				(font
					(size 0.7 0.7)
					(thickness 0.15)
				)
				(justify right bottom)
			)
		)
		(property "Value" "R_0R_1206"
			(at 0 2 0)
			(layer "F.Fab")
			(effects
				(font
					(size 0.7 0.7)
					(thickness 0.15)
				)
				(justify right bottom)
			)
		)
		(property "Datasheet" "https://www.farnell.com/datasheets/2860635.pdf"
			(at 0 0 180)
			(layer "F.Fab")
			(hide yes)
			(effects
				(font
					(size 1.27 1.27)
					(thickness 0.15)
				)
			)
		)
		(property "Description" "Zero Ohm Resistor, Jumper, 1206 [3216 Metric], Thick Film, 250 mW, 2 A, Surface Mount Device"
			(at 0 0 180)
			(layer "F.Fab")
			(hide yes)
			(effects
				(font
					(size 1.27 1.27)
					(thickness 0.15)
				)
			)
		)
		(property "Author" "Antmicro"
			(at 158 152.6 0)
			(layer "F.Fab")
			(hide yes)
			(effects
				(font
					(size 1 1)
					(thickness 0.15)
				)
			)
		)
		(property "Current" "2A"
			(at 158 152.6 0)
			(layer "F.Fab")
			(hide yes)
			(effects
				(font
					(size 1 1)
					(thickness 0.15)
				)
			)
		)
		(property "License" "Apache-2.0"
			(at 158 152.6 0)
			(layer "F.Fab")
			(hide yes)
			(effects
				(font
					(size 1 1)
					(thickness 0.15)
				)
			)
		)
		(property "MPN" "MCMR12X000_PTL"
			(at 158 152.6 0)
			(layer "F.Fab")
			(hide yes)
			(effects
				(font
					(size 1 1)
					(thickness 0.15)
				)
			)
		)
		(property "Manufacturer" "Multicomp Pro"
			(at 158 152.6 0)
			(layer "F.Fab")
			(hide yes)
			(effects
				(font
					(size 1 1)
					(thickness 0.15)
				)
			)
		)
		(property "Tolerance" "~"
			(at 158 152.6 0)
			(layer "F.Fab")
			(hide yes)
			(effects
				(font
					(size 1 1)
					(thickness 0.15)
				)
			)
		)
		(property "Val" "0R"
			(at 158 152.6 0)
			(layer "F.Fab")
			(hide yes)
			(effects
				(font
					(size 1 1)
					(thickness 0.15)
				)
			)
		)
		(sheetname "/Power supply/")
		(sheetfile "power-supply.kicad_sch")
		(attr smd)
		(fp_line
			(start 0.8 0.901)
			(end -0.8 0.901)
			(stroke
				(width 0.15)
				(type solid)
			)
			(layer "F.SilkS")
		)
		(fp_line
			(start 0.8 -0.899)
			(end -0.8 -0.899)
			(stroke
				(width 0.15)
				(type solid)
			)
			(layer "F.SilkS")
		)
		(fp_rect
			(start -2.325 -1.15)
			(end 2.325 1.15)
			(stroke
				(width 0.05)
				(type default)
			)
			(fill no)
			(layer "F.CrtYd")
		)
		(fp_line
			(start 1.6 -0.802)
			(end 1.6 0.8)
			(stroke
				(width 0.15)
				(type solid)
			)
			(layer "F.Fab")
		)
		(fp_line
			(start -1.601 0.8)
			(end 1.6 0.8)
			(stroke
				(width 0.15)
				(type solid)
			)
			(layer "F.Fab")
		)
		(fp_line
			(start -1.601 -0.802)
			(end 1.6 -0.802)
			(stroke
				(width 0.15)
				(type solid)
			)
			(layer "F.Fab")
		)
		(fp_line
			(start -1.601 -0.802)
			(end -1.601 0.8)
			(stroke
				(width 0.15)
				(type solid)
			)
			(layer "F.Fab")
		)
		(pad "1" smd roundrect
			(at -1.5 0.001 180)
			(size 1.15 1.8)
			(layers "F.Cu" "F.Mask" "F.Paste")
			(roundrect_rratio 0.25)
			(net 4 "VCC5V0")
			(pintype "passive")
		)
		(pad "2" smd roundrect
			(at 1.5 0.001 180)
			(size 1.15 1.8)
			(layers "F.Cu" "F.Mask" "F.Paste")
			(roundrect_rratio 0.25)
			(net 114 "Net-(C72-Pad2)")
			(pintype "passive")
		)
	)
	(footprint "antmicro-footprints:C_0402_1005Metric"
		(layer "F.Cu")
		(at 75.065 168.715)
		(descr "Capacitor SMD 0402")
		(tags "capacitor SMD 0402")
		(property "Reference" "C17"
			(at 0.835 0.385 0)
			(layer "F.SilkS")
			(effects
				(font
					(size 0.7 0.7)
					(thickness 0.15)
				)
				(justify left bottom)
			)
		)
		(property "Value" "C_100n_6V3_0402"
			(at 0 1.4 0)
			(layer "F.Fab")
			(effects
				(font
					(size 0.7 0.7)
					(thickness 0.15)
				)
				(justify left bottom)
			)
		)
		(property "Datasheet" "https://www.passivecomponent.com/wp-content/uploads/datasheet/WTC_MLCC_General_Purpose.pdf"
			(at 0 0 0)
			(layer "F.Fab")
			(hide yes)
			(effects
				(font
					(size 1.27 1.27)
					(thickness 0.15)
				)
			)
		)
		(property "Description" "SMT Multilayer Ceramic Capacitor, 0.1 µF, 6.3 V, 0402 [1005 Metric], ± 10%, X5R, Walsin MLCC"
			(at 0 0 0)
			(layer "F.Fab")
			(hide yes)
			(effects
				(font
					(size 1.27 1.27)
					(thickness 0.15)
				)
			)
		)
		(property "Author" "Antmicro"
			(at 0 0 0)
			(layer "F.Fab")
			(hide yes)
			(effects
				(font
					(size 1 1)
					(thickness 0.15)
				)
			)
		)
		(property "Dielectric" ""
			(at 0 0 0)
			(layer "F.Fab")
			(hide yes)
			(effects
				(font
					(size 1 1)
					(thickness 0.15)
				)
			)
		)
		(property "License" "Apache-2.0"
			(at 0 0 0)
			(layer "F.Fab")
			(hide yes)
			(effects
				(font
					(size 1 1)
					(thickness 0.15)
				)
			)
		)
		(property "MPN" "0402X104K6R3CT"
			(at 0 0 0)
			(layer "F.Fab")
			(hide yes)
			(effects
				(font
					(size 1 1)
					(thickness 0.15)
				)
			)
		)
		(property "Manufacturer" "Walsin"
			(at 0 0 0)
			(layer "F.Fab")
			(hide yes)
			(effects
				(font
					(size 1 1)
					(thickness 0.15)
				)
			)
		)
		(property "Public" "False"
			(at 0 0 0)
			(layer "F.Fab")
			(hide yes)
			(effects
				(font
					(size 1 1)
					(thickness 0.15)
				)
			)
		)
		(property "Val" "100n"
			(at 0 0 0)
			(layer "F.Fab")
			(hide yes)
			(effects
				(font
					(size 1 1)
					(thickness 0.15)
				)
			)
		)
		(property "Voltage" ""
			(at 0 0 0)
			(layer "F.Fab")
			(hide yes)
			(effects
				(font
					(size 1 1)
					(thickness 0.15)
				)
			)
		)
		(sheetname "/Interfaces/")
		(sheetfile "interfaces.kicad_sch")
		(attr smd)
		(fp_rect
			(start -0.925 -0.47)
			(end 0.925 0.47)
			(stroke
				(width 0.05)
				(type default)
			)
			(fill no)
			(layer "F.CrtYd")
		)
		(fp_line
			(start -0.494 -0.25)
			(end 0.504 -0.25)
			(stroke
				(width 0.15)
				(type solid)
			)
			(layer "F.Fab")
		)
		(fp_line
			(start -0.494 0.248)
			(end -0.494 -0.25)
			(stroke
				(width 0.15)
				(type solid)
			)
			(layer "F.Fab")
		)
		(fp_line
			(start 0.504 -0.25)
			(end 0.504 0.248)
			(stroke
				(width 0.15)
				(type solid)
			)
			(layer "F.Fab")
		)
		(fp_line
			(start 0.504 0.248)
			(end -0.494 0.248)
			(stroke
				(width 0.15)
				(type solid)
			)
			(layer "F.Fab")
		)
		(pad "1" smd roundrect
			(at -0.48 0)
			(size 0.59 0.64)
			(layers "F.Cu" "F.Mask" "F.Paste")
			(roundrect_rratio 0.25)
			(net 1 "GND")
			(pintype "passive")
		)
		(pad "2" smd roundrect
			(at 0.48 0)
			(size 0.59 0.64)
			(layers "F.Cu" "F.Mask" "F.Paste")
			(roundrect_rratio 0.25)
			(net 6 "VCC1V0")
			(pintype "passive")
		)
	)
	(footprint "antmicro-footprints:TP_SMD_1mm"
		(layer "F.Cu")
		(at 84.115 62.1908)
		(property "Reference" "TP1"
			(at -0.815 -0.6908 0)
			(layer "F.SilkS")
			(effects
				(font
					(size 0.7 0.7)
					(thickness 0.15)
				)
				(justify left bottom)
			)
		)
		(property "Value" "TP_1mm_SMD"
			(at 0 1.4 0)
			(layer "F.Fab")
			(effects
				(font
					(size 0.7 0.7)
					(thickness 0.15)
				)
				(justify left bottom)
			)
		)
		(property "Description" "Test point 1mm SMD"
			(at 0 0 0)
			(layer "F.Fab")
			(hide yes)
			(effects
				(font
					(size 1.27 1.27)
					(thickness 0.15)
				)
			)
		)
		(property "Author" "Antmicro"
			(at 0 0 0)
			(layer "F.Fab")
			(hide yes)
			(effects
				(font
					(size 1 1)
					(thickness 0.15)
				)
			)
		)
		(property "License" "Apache-2.0"
			(at 0 0 0)
			(layer "F.Fab")
			(hide yes)
			(effects
				(font
					(size 1 1)
					(thickness 0.15)
				)
			)
		)
		(property "MPN" ""
			(at 0 0 0)
			(layer "F.Fab")
			(hide yes)
			(effects
				(font
					(size 1 1)
					(thickness 0.15)
				)
			)
		)
		(property "Manufacturer" ""
			(at 0 0 0)
			(layer "F.Fab")
			(hide yes)
			(effects
				(font
					(size 1 1)
					(thickness 0.15)
				)
			)
		)
		(sheetname "/Power supply/")
		(sheetfile "power-supply.kicad_sch")
		(attr exclude_from_pos_files exclude_from_bom)
		(fp_circle
			(center 0 0)
			(end 0.6 0)
			(stroke
				(width 0.05)
				(type default)
			)
			(fill no)
			(layer "F.CrtYd")
		)
		(pad "1" smd circle
			(at 0 0)
			(size 1 1)
			(layers "F.Cu" "F.Mask")
			(net 228 "Net-(U25-EN)")
			(pinfunction "1")
			(pintype "passive")
		)
	)
	(footprint "antmicro-footprints:WSON-10-1EP_4x4mm_P0.8mm_EP2.6x3mm"
		(layer "F.Cu")
		(at 79.711 64.437 180)
		(property "Reference" "U25"
			(at 2.611 2.337 0)
			(layer "F.SilkS")
			(effects
				(font
					(size 0.7 0.7)
					(thickness 0.15)
				)
				(justify left bottom)
			)
		)
		(property "Value" "TPS54561QDPRRQ1"
			(at 0 3.4 0)
			(layer "F.Fab")
			(effects
				(font
					(size 0.7 0.7)
					(thickness 0.15)
				)
				(justify left bottom)
			)
		)
		(property "Datasheet" "https://www.ti.com/lit/ds/symlink/tps54561-q1.pdf?ts=1678720110394&ref_url=https%253A%252F%252Fwww.google.com%252F"
			(at 0 0 180)
			(layer "F.Fab")
			(hide yes)
			(effects
				(font
					(size 1.27 1.27)
					(thickness 0.15)
				)
			)
		)
		(property "Description" "DC/DC converter"
			(at 0 0 180)
			(layer "F.Fab")
			(hide yes)
			(effects
				(font
					(size 1.27 1.27)
					(thickness 0.15)
				)
			)
		)
		(property "Author" "Antmicro"
			(at 159.422 128.874 0)
			(layer "F.Fab")
			(hide yes)
			(effects
				(font
					(size 1 1)
					(thickness 0.15)
				)
			)
		)
		(property "License" "Apache-2.0"
			(at 159.422 128.874 0)
			(layer "F.Fab")
			(hide yes)
			(effects
				(font
					(size 1 1)
					(thickness 0.15)
				)
			)
		)
		(property "MPN" "TPS54561QDPRRQ1"
			(at 159.422 128.874 0)
			(layer "F.Fab")
			(hide yes)
			(effects
				(font
					(size 1 1)
					(thickness 0.15)
				)
			)
		)
		(property "Manufacturer" "Texas Instruments"
			(at 159.422 128.874 0)
			(layer "F.Fab")
			(hide yes)
			(effects
				(font
					(size 1 1)
					(thickness 0.15)
				)
			)
		)
		(sheetname "/Power supply/")
		(sheetfile "power-supply.kicad_sch")
		(attr smd)
		(fp_line
			(start 2.1 2.122)
			(end 2.1 1.975)
			(stroke
				(width 0.15)
				(type solid)
			)
			(layer "F.SilkS")
		)
		(fp_line
			(start 2.1 2.122)
			(end -2.1 2.122)
			(stroke
				(width 0.15)
				(type solid)
			)
			(layer "F.SilkS")
		)
		(fp_line
			(start 2.1 -2.123)
			(end 2.1 -1.975)
			(stroke
				(width 0.15)
				(type solid)
			)
			(layer "F.SilkS")
		)
		(fp_line
			(start -2.1 2.123)
			(end -2.1 1.975)
			(stroke
				(width 0.15)
				(type solid)
			)
			(layer "F.SilkS")
		)
		(fp_line
			(start -2.1 -2.123)
			(end 2.1 -2.123)
			(stroke
				(width 0.15)
				(type solid)
			)
			(layer "F.SilkS")
		)
		(fp_line
			(start -2.1 -2.123)
			(end -2.1 -1.975)
			(stroke
				(width 0.15)
				(type solid)
			)
			(layer "F.SilkS")
		)
		(fp_circle
			(center -2.325 -2.05)
			(end -2.275 -2.05)
			(stroke
				(width 0.15)
				(type solid)
			)
			(fill yes)
			(layer "F.SilkS")
		)
		(fp_rect
			(start -2.57 -2.2)
			(end 2.469 2.2)
			(stroke
				(width 0.05)
				(type solid)
			)
			(fill no)
			(layer "F.CrtYd")
		)
		(fp_line
			(start 2 2)
			(end -2 2)
			(stroke
				(width 0.15)
				(type solid)
			)
			(layer "F.Fab")
		)
		(fp_line
			(start 2 -2)
			(end 2 2)
			(stroke
				(width 0.15)
				(type solid)
			)
			(layer "F.Fab")
		)
		(fp_line
			(start -1.5 -2)
			(end 2 -2)
			(stroke
				(width 0.15)
				(type solid)
			)
			(layer "F.Fab")
		)
		(fp_line
			(start -2 2)
			(end -2 -1.5)
			(stroke
				(width 0.15)
				(type solid)
			)
			(layer "F.Fab")
		)
		(fp_line
			(start -2 -1.5)
			(end -1.5 -2)
			(stroke
				(width 0.15)
				(type solid)
			)
			(layer "F.Fab")
		)
		(pad "1" smd roundrect
			(at -1.9 -1.6 270)
			(size 0.3 0.6)
			(layers "F.Cu" "F.Mask" "F.Paste")
			(roundrect_rratio 0.1666666667)
			(net 110 "Net-(U25-BOOT)")
			(pinfunction "BOOT")
			(pintype "output")
		)
		(pad "2" smd roundrect
			(at -1.9 -0.8 270)
			(size 0.3 0.6)
			(layers "F.Cu" "F.Mask" "F.Paste")
			(roundrect_rratio 0.1666666667)
			(net 104 "/Power supply/VCC12V")
			(pinfunction "V_{DD}")
			(pintype "power_in")
		)
		(pad "3" smd roundrect
			(at -1.9 0 270)
			(size 0.3 0.6)
			(layers "F.Cu" "F.Mask" "F.Paste")
			(roundrect_rratio 0.1666666667)
			(net 228 "Net-(U25-EN)")
			(pinfunction "EN")
			(pintype "input")
		)
		(pad "4" smd roundrect
			(at -1.9 0.8 270)
			(size 0.3 0.6)
			(layers "F.Cu" "F.Mask" "F.Paste")
			(roundrect_rratio 0.1666666667)
			(net 106 "Net-(U25-SS{slash}TR)")
			(pinfunction "SS/TR")
			(pintype "input")
		)
		(pad "5" smd roundrect
			(at -1.9 1.6 270)
			(size 0.3 0.6)
			(layers "F.Cu" "F.Mask" "F.Paste")
			(roundrect_rratio 0.1666666667)
			(net 226 "Net-(U25-RT{slash}CLK)")
			(pinfunction "RT/CLK")
			(pintype "input")
		)
		(pad "6" smd roundrect
			(at 1.9 1.6 270)
			(size 0.3 0.6)
			(layers "F.Cu" "F.Mask" "F.Paste")
			(roundrect_rratio 0.1666666667)
			(net 227 "Net-(U25-FB)")
			(pinfunction "FB")
			(pintype "input")
		)
		(pad "7" smd roundrect
			(at 1.9 0.8 270)
			(size 0.3 0.6)
			(layers "F.Cu" "F.Mask" "F.Paste")
			(roundrect_rratio 0.1666666667)
			(net 107 "Net-(U25-COMP)")
			(pinfunction "COMP")
			(pintype "output")
		)
		(pad "8" smd roundrect
			(at 1.9 0 270)
			(size 0.3 0.6)
			(layers "F.Cu" "F.Mask" "F.Paste")
			(roundrect_rratio 0.1666666667)
			(net 1 "GND")
			(pinfunction "GND")
			(pintype "power_in")
		)
		(pad "9" smd roundrect
			(at 1.9 -0.8 270)
			(size 0.3 0.6)
			(layers "F.Cu" "F.Mask" "F.Paste")
			(roundrect_rratio 0.1666666667)
			(net 8 "Net-(D3-C)")
			(pinfunction "SW")
			(pintype "power_out")
		)
		(pad "10" smd roundrect
			(at 1.9 -1.6 270)
			(size 0.3 0.6)
			(layers "F.Cu" "F.Mask" "F.Paste")
			(roundrect_rratio 0.1666666667)
			(net 573 "/Power supply/5V0_PG")
			(pinfunction "PWRGD")
			(pintype "output")
		)
		(pad "11" smd roundrect
			(at 0 0 180)
			(size 2.6 3)
			(layers "F.Cu" "F.Mask" "F.Paste")
			(roundrect_rratio 0.01923076923)
			(net 1 "GND")
			(pinfunction "GND")
			(pintype "passive")
		)
	)
	(footprint "antmicro-footprints:PowerDI5"
		(layer "F.Cu")
		(at 69.2004 62.7048 180)
		(property "Reference" "D3"
			(at 0.0004 2.5048 0)
			(layer "F.SilkS")
			(effects
				(font
					(size 0.7 0.7)
					(thickness 0.15)
				)
				(justify right bottom)
			)
		)
		(property "Value" "PDS760"
			(at 0 3.4 0)
			(layer "F.Fab")
			(effects
				(font
					(size 0.7 0.7)
					(thickness 0.15)
				)
				(justify left bottom)
			)
		)
		(property "Datasheet" "https://www.diodes.com/assets/Datasheets/ds30470.pdf"
			(at 0 0 180)
			(layer "F.Fab")
			(hide yes)
			(effects
				(font
					(size 1.27 1.27)
					(thickness 0.15)
				)
			)
		)
		(property "Description" "Schottky Rectifier, POWERDI®, 60 V, 7 A, Single, PowerDI 5, 2 Pins, 620 mV"
			(at 0 0 180)
			(layer "F.Fab")
			(hide yes)
			(effects
				(font
					(size 1.27 1.27)
					(thickness 0.15)
				)
			)
		)
		(property "Author" "Antmicro"
			(at 138.4008 125.4096 0)
			(layer "F.Fab")
			(hide yes)
			(effects
				(font
					(size 1 1)
					(thickness 0.15)
				)
			)
		)
		(property "License" "Apache-2.0"
			(at 138.4008 125.4096 0)
			(layer "F.Fab")
			(hide yes)
			(effects
				(font
					(size 1 1)
					(thickness 0.15)
				)
			)
		)
		(property "MPN" "PDS760-13"
			(at 138.4008 125.4096 0)
			(layer "F.Fab")
			(hide yes)
			(effects
				(font
					(size 1 1)
					(thickness 0.15)
				)
			)
		)
		(property "Manufacturer" "Diodes Incorporated"
			(at 138.4008 125.4096 0)
			(layer "F.Fab")
			(hide yes)
			(effects
				(font
					(size 1 1)
					(thickness 0.15)
				)
			)
		)
		(sheetname "/Power supply/")
		(sheetfile "power-supply.kicad_sch")
		(attr smd)
		(fp_line
			(start 2.7 2.023)
			(end -2.7 2.023)
			(stroke
				(width 0.12)
				(type solid)
			)
			(layer "F.SilkS")
		)
		(fp_line
			(start 2.7 1.823)
			(end 2.7 2.023)
			(stroke
				(width 0.12)
				(type solid)
			)
			(layer "F.SilkS")
		)
		(fp_line
			(start 2.7 -2)
			(end 2.7 -1.8)
			(stroke
				(width 0.12)
				(type solid)
			)
			(layer "F.SilkS")
		)
		(fp_line
			(start -2.7 2.023)
			(end -2.7 1.823)
			(stroke
				(width 0.12)
				(type solid)
			)
			(layer "F.SilkS")
		)
		(fp_line
			(start -2.7 -1.8)
			(end -2.7 -2)
			(stroke
				(width 0.12)
				(type solid)
			)
			(layer "F.SilkS")
		)
		(fp_line
			(start -2.7 -2)
			(end 2.7 -2)
			(stroke
				(width 0.12)
				(type solid)
			)
			(layer "F.SilkS")
		)
		(fp_rect
			(start -3.702 -2.3)
			(end 3.7 2.3)
			(stroke
				(width 0.05)
				(type solid)
			)
			(fill no)
			(layer "F.CrtYd")
		)
		(pad "1" smd roundrect
			(at 1.1 0 90)
			(size 3.36 4.86)
			(layers "F.Cu" "F.Mask" "F.Paste")
			(roundrect_rratio 0.05)
			(net 8 "Net-(D3-C)")
			(pinfunction "C")
			(pintype "passive")
		)
		(pad "2" smd roundrect
			(at -2.862 -0.94 270)
			(size 1.39 1.4)
			(layers "F.Cu" "F.Mask" "F.Paste")
			(roundrect_rratio 0.25)
			(net 1 "GND")
			(pinfunction "A")
			(pintype "passive")
		)
		(pad "2" smd roundrect
			(at -2.862 0.941 90)
			(size 1.39 1.4)
			(layers "F.Cu" "F.Mask" "F.Paste")
			(roundrect_rratio 0.25)
			(net 1 "GND")
			(pinfunction "A")
			(pintype "passive")
		)
	)
	(footprint "antmicro-footprints:F_1206_3216Metric"
		(layer "F.Cu")
		(at 91.665 67.49 180)
		(property "Reference" "F1"
			(at -3.035 1.19 0)
			(layer "F.SilkS")
			(effects
				(font
					(size 0.7 0.7)
					(thickness 0.15)
				)
				(justify right bottom)
			)
		)
		(property "Value" "F_3A_1206"
			(at 0 2 0)
			(layer "F.Fab")
			(effects
				(font
					(size 0.7 0.7)
					(thickness 0.15)
				)
				(justify right bottom)
			)
		)
		(property "Datasheet" "https://www.littelfuse.com/~/media/electronics/datasheets/fuses/littelfuse_fuse_466_datasheet.pdf.pdf"
			(at 0 0 180)
			(layer "F.Fab")
			(hide yes)
			(effects
				(font
					(size 1.27 1.27)
					(thickness 0.15)
				)
			)
		)
		(property "Description" "Fuse, Surface Mount, 3 A, Very Fast Acting, 32 V, 32 V, 1206 (3216 Metric), 466"
			(at 0 0 180)
			(layer "F.Fab")
			(hide yes)
			(effects
				(font
					(size 1.27 1.27)
					(thickness 0.15)
				)
			)
		)
		(property "Author" "Antmicro"
			(at 183.33 134.98 0)
			(layer "F.Fab")
			(hide yes)
			(effects
				(font
					(size 1 1)
					(thickness 0.15)
				)
			)
		)
		(property "License" "Apache-2.0"
			(at 183.33 134.98 0)
			(layer "F.Fab")
			(hide yes)
			(effects
				(font
					(size 1 1)
					(thickness 0.15)
				)
			)
		)
		(property "MPN" "0466003.NR "
			(at 183.33 134.98 0)
			(layer "F.Fab")
			(hide yes)
			(effects
				(font
					(size 1 1)
					(thickness 0.15)
				)
			)
		)
		(property "Manufacturer" "Littelfuse"
			(at 183.33 134.98 0)
			(layer "F.Fab")
			(hide yes)
			(effects
				(font
					(size 1 1)
					(thickness 0.15)
				)
			)
		)
		(sheetname "/Power supply/")
		(sheetfile "power-supply.kicad_sch")
		(attr smd)
		(fp_line
			(start 0.8 0.901)
			(end -0.8 0.901)
			(stroke
				(width 0.15)
				(type solid)
			)
			(layer "F.SilkS")
		)
		(fp_line
			(start 0.8 -0.899)
			(end -0.8 -0.899)
			(stroke
				(width 0.15)
				(type solid)
			)
			(layer "F.SilkS")
		)
		(fp_rect
			(start -2.325 -1.15)
			(end 2.325 1.15)
			(stroke
				(width 0.05)
				(type default)
			)
			(fill no)
			(layer "F.CrtYd")
		)
		(fp_line
			(start 1.624 0.792)
			(end -1.677 0.792)
			(stroke
				(width 0.15)
				(type solid)
			)
			(layer "F.Fab")
		)
		(fp_line
			(start 1.624 -0.861)
			(end 1.624 0.792)
			(stroke
				(width 0.15)
				(type solid)
			)
			(layer "F.Fab")
		)
		(fp_line
			(start -1.677 0.792)
			(end -1.677 -0.861)
			(stroke
				(width 0.15)
				(type solid)
			)
			(layer "F.Fab")
		)
		(fp_line
			(start -1.677 -0.861)
			(end 1.624 -0.861)
			(stroke
				(width 0.15)
				(type solid)
			)
			(layer "F.Fab")
		)
		(pad "1" smd roundrect
			(at -1.5 0.001 180)
			(size 1.15 1.8)
			(layers "F.Cu" "F.Mask" "F.Paste")
			(roundrect_rratio 0.25)
			(net 59 "P12V_AUX")
			(pintype "passive")
		)
		(pad "2" smd roundrect
			(at 1.5 0.001 180)
			(size 1.15 1.8)
			(layers "F.Cu" "F.Mask" "F.Paste")
			(roundrect_rratio 0.25)
			(net 104 "/Power supply/VCC12V")
			(pintype "passive")
		)
	)
	(footprint "antmicro-footprints:R_0402_1005Metric"
		(layer "F.Cu")
		(at 73.925 64.025 -90)
		(descr "Resistor SMD 0402")
		(tags "resistor SMD 0402")
		(property "Reference" "R72"
			(at -4.025 -0.275 270)
			(layer "F.SilkS")
			(effects
				(font
					(size 0.7 0.7)
					(thickness 0.15)
				)
				(justify right bottom)
			)
		)
		(property "Value" "R_10k2_0402"
			(at 0 1.4 90)
			(layer "F.Fab")
			(effects
				(font
					(size 0.7 0.7)
					(thickness 0.15)
				)
				(justify right bottom)
			)
		)
		(property "Datasheet" "https://www.bourns.com/docs/product-datasheets/cr.pdf"
			(at 0 0 270)
			(layer "F.Fab")
			(hide yes)
			(effects
				(font
					(size 1.27 1.27)
					(thickness 0.15)
				)
			)
		)
		(property "Description" "SMD Chip Resistor"
			(at 0 0 270)
			(layer "F.Fab")
			(hide yes)
			(effects
				(font
					(size 1.27 1.27)
					(thickness 0.15)
				)
			)
		)
		(property "Author" "Antmicro"
			(at 9.9 137.95 0)
			(layer "F.Fab")
			(hide yes)
			(effects
				(font
					(size 1 1)
					(thickness 0.15)
				)
			)
		)
		(property "License" "Apache-2.0"
			(at 9.9 137.95 0)
			(layer "F.Fab")
			(hide yes)
			(effects
				(font
					(size 1 1)
					(thickness 0.15)
				)
			)
		)
		(property "MPN" "CR0402-FX-1022GLF"
			(at 9.9 137.95 0)
			(layer "F.Fab")
			(hide yes)
			(effects
				(font
					(size 1 1)
					(thickness 0.15)
				)
			)
		)
		(property "Manufacturer" "Bourns"
			(at 9.9 137.95 0)
			(layer "F.Fab")
			(hide yes)
			(effects
				(font
					(size 1 1)
					(thickness 0.15)
				)
			)
		)
		(property "Tolerance" "1%"
			(at 9.9 137.95 0)
			(layer "F.Fab")
			(hide yes)
			(effects
				(font
					(size 1 1)
					(thickness 0.15)
				)
			)
		)
		(property "Val" "10k2"
			(at 9.9 137.95 0)
			(layer "F.Fab")
			(hide yes)
			(effects
				(font
					(size 1 1)
					(thickness 0.15)
				)
			)
		)
		(sheetname "/Power supply/")
		(sheetfile "power-supply.kicad_sch")
		(attr smd)
		(fp_rect
			(start -0.925 -0.47)
			(end 0.925 0.47)
			(stroke
				(width 0.05)
				(type default)
			)
			(fill no)
			(layer "F.CrtYd")
		)
		(fp_rect
			(start -0.5 -0.25)
			(end 0.5 0.25)
			(stroke
				(width 0.15)
				(type solid)
			)
			(fill no)
			(layer "F.Fab")
		)
		(pad "1" smd roundrect
			(at -0.48 0 270)
			(size 0.59 0.64)
			(layers "F.Cu" "F.Mask" "F.Paste")
			(roundrect_rratio 0.25)
			(net 227 "Net-(U25-FB)")
			(pintype "passive")
		)
		(pad "2" smd roundrect
			(at 0.48 0 270)
			(size 0.59 0.64)
			(layers "F.Cu" "F.Mask" "F.Paste")
			(roundrect_rratio 0.25)
			(net 1 "GND")
			(pintype "passive")
		)
	)
	(footprint "antmicro-footprints:R_0402_1005Metric"
		(layer "F.Cu")
		(at 78.5 71.405 90)
		(descr "Resistor SMD 0402")
		(tags "resistor SMD 0402")
		(property "Reference" "R71"
			(at 0.105 -16.4 90)
			(layer "F.SilkS")
			(effects
				(font
					(size 0.7 0.7)
					(thickness 0.15)
				)
				(justify left bottom)
			)
		)
		(property "Value" "R_53k6_0402"
			(at 0 1.4 90)
			(layer "F.Fab")
			(effects
				(font
					(size 0.7 0.7)
					(thickness 0.15)
				)
				(justify left bottom)
			)
		)
		(property "Datasheet" "https://www.bourns.com/docs/product-datasheets/cr.pdf"
			(at 0 0 90)
			(layer "F.Fab")
			(hide yes)
			(effects
				(font
					(size 1.27 1.27)
					(thickness 0.15)
				)
			)
		)
		(property "Description" "SMD Chip Resistor"
			(at 0 0 90)
			(layer "F.Fab")
			(hide yes)
			(effects
				(font
					(size 1.27 1.27)
					(thickness 0.15)
				)
			)
		)
		(property "Author" "Antmicro"
			(at 149.905 -7.095 0)
			(layer "F.Fab")
			(hide yes)
			(effects
				(font
					(size 1 1)
					(thickness 0.15)
				)
			)
		)
		(property "License" "Apache-2.0"
			(at 149.905 -7.095 0)
			(layer "F.Fab")
			(hide yes)
			(effects
				(font
					(size 1 1)
					(thickness 0.15)
				)
			)
		)
		(property "MPN" "CR0402-FX-5362GLF"
			(at 149.905 -7.095 0)
			(layer "F.Fab")
			(hide yes)
			(effects
				(font
					(size 1 1)
					(thickness 0.15)
				)
			)
		)
		(property "Manufacturer" "Bourns"
			(at 149.905 -7.095 0)
			(layer "F.Fab")
			(hide yes)
			(effects
				(font
					(size 1 1)
					(thickness 0.15)
				)
			)
		)
		(property "Tolerance" "1%"
			(at 149.905 -7.095 0)
			(layer "F.Fab")
			(hide yes)
			(effects
				(font
					(size 1 1)
					(thickness 0.15)
				)
			)
		)
		(property "Val" "53k6"
			(at 149.905 -7.095 0)
			(layer "F.Fab")
			(hide yes)
			(effects
				(font
					(size 1 1)
					(thickness 0.15)
				)
			)
		)
		(sheetname "/Power supply/")
		(sheetfile "power-supply.kicad_sch")
		(attr smd)
		(fp_rect
			(start -0.925 -0.47)
			(end 0.925 0.47)
			(stroke
				(width 0.05)
				(type default)
			)
			(fill no)
			(layer "F.CrtYd")
		)
		(fp_rect
			(start -0.5 -0.25)
			(end 0.5 0.25)
			(stroke
				(width 0.15)
				(type solid)
			)
			(fill no)
			(layer "F.Fab")
		)
		(pad "1" smd roundrect
			(at -0.48 0 90)
			(size 0.59 0.64)
			(layers "F.Cu" "F.Mask" "F.Paste")
			(roundrect_rratio 0.25)
			(net 205 "Net-(R70-Pad2)")
			(pintype "passive")
		)
		(pad "2" smd roundrect
			(at 0.48 0 90)
			(size 0.59 0.64)
			(layers "F.Cu" "F.Mask" "F.Paste")
			(roundrect_rratio 0.25)
			(net 227 "Net-(U25-FB)")
			(pintype "passive")
		)
	)
	(footprint "antmicro-footprints:R_0402_1005Metric"
		(layer "F.Cu")
		(at 81.265 61.7)
		(descr "Resistor SMD 0402")
		(tags "resistor SMD 0402")
		(property "Reference" "R67"
			(at -2.165 -0.7 0)
			(layer "F.SilkS")
			(effects
				(font
					(size 0.7 0.7)
					(thickness 0.15)
				)
				(justify left bottom)
			)
		)
		(property "Value" "R_243k_0402"
			(at 0 1.4 0)
			(layer "F.Fab")
			(effects
				(font
					(size 0.7 0.7)
					(thickness 0.15)
				)
				(justify left bottom)
			)
		)
		(property "Datasheet" "https://www.bourns.com/docs/product-datasheets/cr.pdf"
			(at 0 0 0)
			(layer "F.Fab")
			(hide yes)
			(effects
				(font
					(size 1.27 1.27)
					(thickness 0.15)
				)
			)
		)
		(property "Description" "SMD Chip Resistor"
			(at 0 0 0)
			(layer "F.Fab")
			(hide yes)
			(effects
				(font
					(size 1.27 1.27)
					(thickness 0.15)
				)
			)
		)
		(property "Author" "Antmicro"
			(at 0 0 0)
			(layer "F.Fab")
			(hide yes)
			(effects
				(font
					(size 1 1)
					(thickness 0.15)
				)
			)
		)
		(property "License" "Apache-2.0"
			(at 0 0 0)
			(layer "F.Fab")
			(hide yes)
			(effects
				(font
					(size 1 1)
					(thickness 0.15)
				)
			)
		)
		(property "MPN" "CR0402-FX-2433GLF"
			(at 0 0 0)
			(layer "F.Fab")
			(hide yes)
			(effects
				(font
					(size 1 1)
					(thickness 0.15)
				)
			)
		)
		(property "Manufacturer" "Bourns"
			(at 0 0 0)
			(layer "F.Fab")
			(hide yes)
			(effects
				(font
					(size 1 1)
					(thickness 0.15)
				)
			)
		)
		(property "Tolerance" "1%"
			(at 0 0 0)
			(layer "F.Fab")
			(hide yes)
			(effects
				(font
					(size 1 1)
					(thickness 0.15)
				)
			)
		)
		(property "Val" "243k"
			(at 0 0 0)
			(layer "F.Fab")
			(hide yes)
			(effects
				(font
					(size 1 1)
					(thickness 0.15)
				)
			)
		)
		(sheetname "/Power supply/")
		(sheetfile "power-supply.kicad_sch")
		(attr smd)
		(fp_rect
			(start -0.925 -0.47)
			(end 0.925 0.47)
			(stroke
				(width 0.05)
				(type default)
			)
			(fill no)
			(layer "F.CrtYd")
		)
		(fp_rect
			(start -0.5 -0.25)
			(end 0.5 0.25)
			(stroke
				(width 0.15)
				(type solid)
			)
			(fill no)
			(layer "F.Fab")
		)
		(pad "1" smd roundrect
			(at -0.48 0)
			(size 0.59 0.64)
			(layers "F.Cu" "F.Mask" "F.Paste")
			(roundrect_rratio 0.25)
			(net 1 "GND")
			(pintype "passive")
		)
		(pad "2" smd roundrect
			(at 0.48 0)
			(size 0.59 0.64)
			(layers "F.Cu" "F.Mask" "F.Paste")
			(roundrect_rratio 0.25)
			(net 226 "Net-(U25-RT{slash}CLK)")
			(pintype "passive")
		)
	)
	(footprint "antmicro-footprints:R_0402_1005Metric"
		(layer "F.Cu")
		(at 75.525 62.525 180)
		(descr "Resistor SMD 0402")
		(tags "resistor SMD 0402")
		(property "Reference" "R66"
			(at -0.875 2.625 180)
			(layer "F.SilkS")
			(effects
				(font
					(size 0.7 0.7)
					(thickness 0.15)
				)
				(justify right bottom)
			)
		)
		(property "Value" "R_16k9_0402"
			(at 0 1.4 0)
			(layer "F.Fab")
			(effects
				(font
					(size 0.7 0.7)
					(thickness 0.15)
				)
				(justify right bottom)
			)
		)
		(property "Datasheet" "https://www.bourns.com/docs/product-datasheets/cr.pdf"
			(at 0 0 180)
			(layer "F.Fab")
			(hide yes)
			(effects
				(font
					(size 1.27 1.27)
					(thickness 0.15)
				)
			)
		)
		(property "Description" "SMD Chip Resistor, Ceramic, 16.9 kohm, ± 1%, 62.5 mW, 0402 [1005 Metric], Thick Film"
			(at 0 0 180)
			(layer "F.Fab")
			(hide yes)
			(effects
				(font
					(size 1.27 1.27)
					(thickness 0.15)
				)
			)
		)
		(property "Author" "Antmicro"
			(at 151.05 125.05 0)
			(layer "F.Fab")
			(hide yes)
			(effects
				(font
					(size 1 1)
					(thickness 0.15)
				)
			)
		)
		(property "License" "Apache-2.0"
			(at 151.05 125.05 0)
			(layer "F.Fab")
			(hide yes)
			(effects
				(font
					(size 1 1)
					(thickness 0.15)
				)
			)
		)
		(property "MPN" "CR0402-FX-1692GLF"
			(at 151.05 125.05 0)
			(layer "F.Fab")
			(hide yes)
			(effects
				(font
					(size 1 1)
					(thickness 0.15)
				)
			)
		)
		(property "Manufacturer" "Bourns"
			(at 151.05 125.05 0)
			(layer "F.Fab")
			(hide yes)
			(effects
				(font
					(size 1 1)
					(thickness 0.15)
				)
			)
		)
		(property "Tolerance" "1%"
			(at 151.05 125.05 0)
			(layer "F.Fab")
			(hide yes)
			(effects
				(font
					(size 1 1)
					(thickness 0.15)
				)
			)
		)
		(property "Val" "16k9"
			(at 151.05 125.05 0)
			(layer "F.Fab")
			(hide yes)
			(effects
				(font
					(size 1 1)
					(thickness 0.15)
				)
			)
		)
		(sheetname "/Power supply/")
		(sheetfile "power-supply.kicad_sch")
		(attr smd)
		(fp_rect
			(start -0.925 -0.47)
			(end 0.925 0.47)
			(stroke
				(width 0.05)
				(type default)
			)
			(fill no)
			(layer "F.CrtYd")
		)
		(fp_rect
			(start -0.5 -0.25)
			(end 0.5 0.25)
			(stroke
				(width 0.15)
				(type solid)
			)
			(fill no)
			(layer "F.Fab")
		)
		(pad "1" smd roundrect
			(at -0.48 0 180)
			(size 0.59 0.64)
			(layers "F.Cu" "F.Mask" "F.Paste")
			(roundrect_rratio 0.25)
			(net 107 "Net-(U25-COMP)")
			(pintype "passive")
		)
		(pad "2" smd roundrect
			(at 0.48 0 180)
			(size 0.59 0.64)
			(layers "F.Cu" "F.Mask" "F.Paste")
			(roundrect_rratio 0.25)
			(net 111 "Net-(C68-Pad2)")
			(pintype "passive")
		)
	)
	(footprint "antmicro-footprints:C_0402_1005Metric"
		(layer "F.Cu")
		(at 82.25 67.075)
		(descr "Capacitor SMD 0402")
		(tags "capacitor SMD 0402")
		(property "Reference" "C71"
			(at -18.84 0.075 0)
			(layer "F.SilkS")
			(effects
				(font
					(size 0.7 0.7)
					(thickness 0.15)
				)
				(justify left bottom)
			)
		)
		(property "Value" "C_100n_6V3_0402"
			(at 0 1.4 0)
			(layer "F.Fab")
			(effects
				(font
					(size 0.7 0.7)
					(thickness 0.15)
				)
				(justify left bottom)
			)
		)
		(property "Datasheet" "https://www.passivecomponent.com/wp-content/uploads/datasheet/WTC_MLCC_General_Purpose.pdf"
			(at 0 0 0)
			(layer "F.Fab")
			(hide yes)
			(effects
				(font
					(size 1.27 1.27)
					(thickness 0.15)
				)
			)
		)
		(property "Description" "SMT Multilayer Ceramic Capacitor, 0.1 µF, 6.3 V, 0402 [1005 Metric], ± 10%, X5R, Walsin MLCC"
			(at 0 0 0)
			(layer "F.Fab")
			(hide yes)
			(effects
				(font
					(size 1.27 1.27)
					(thickness 0.15)
				)
			)
		)
		(property "Author" "Antmicro"
			(at 0 0 0)
			(layer "F.Fab")
			(hide yes)
			(effects
				(font
					(size 1 1)
					(thickness 0.15)
				)
			)
		)
		(property "Dielectric" ""
			(at 0 0 0)
			(layer "F.Fab")
			(hide yes)
			(effects
				(font
					(size 1 1)
					(thickness 0.15)
				)
			)
		)
		(property "License" "Apache-2.0"
			(at 0 0 0)
			(layer "F.Fab")
			(hide yes)
			(effects
				(font
					(size 1 1)
					(thickness 0.15)
				)
			)
		)
		(property "MPN" "0402X104K6R3CT"
			(at 0 0 0)
			(layer "F.Fab")
			(hide yes)
			(effects
				(font
					(size 1 1)
					(thickness 0.15)
				)
			)
		)
		(property "Manufacturer" "Walsin"
			(at 0 0 0)
			(layer "F.Fab")
			(hide yes)
			(effects
				(font
					(size 1 1)
					(thickness 0.15)
				)
			)
		)
		(property "Public" "False"
			(at 0 0 0)
			(layer "F.Fab")
			(hide yes)
			(effects
				(font
					(size 1 1)
					(thickness 0.15)
				)
			)
		)
		(property "Val" "100n"
			(at 0 0 0)
			(layer "F.Fab")
			(hide yes)
			(effects
				(font
					(size 1 1)
					(thickness 0.15)
				)
			)
		)
		(property "Voltage" ""
			(at 0 0 0)
			(layer "F.Fab")
			(hide yes)
			(effects
				(font
					(size 1 1)
					(thickness 0.15)
				)
			)
		)
		(sheetname "/Power supply/")
		(sheetfile "power-supply.kicad_sch")
		(attr smd)
		(fp_rect
			(start -0.925 -0.47)
			(end 0.925 0.47)
			(stroke
				(width 0.05)
				(type default)
			)
			(fill no)
			(layer "F.CrtYd")
		)
		(fp_line
			(start -0.494 -0.25)
			(end 0.504 -0.25)
			(stroke
				(width 0.15)
				(type solid)
			)
			(layer "F.Fab")
		)
		(fp_line
			(start -0.494 0.248)
			(end -0.494 -0.25)
			(stroke
				(width 0.15)
				(type solid)
			)
			(layer "F.Fab")
		)
		(fp_line
			(start 0.504 -0.25)
			(end 0.504 0.248)
			(stroke
				(width 0.15)
				(type solid)
			)
			(layer "F.Fab")
		)
		(fp_line
			(start 0.504 0.248)
			(end -0.494 0.248)
			(stroke
				(width 0.15)
				(type solid)
			)
			(layer "F.Fab")
		)
		(pad "1" smd roundrect
			(at -0.48 0)
			(size 0.59 0.64)
			(layers "F.Cu" "F.Mask" "F.Paste")
			(roundrect_rratio 0.25)
			(net 110 "Net-(U25-BOOT)")
			(pintype "passive")
		)
		(pad "2" smd roundrect
			(at 0.48 0)
			(size 0.59 0.64)
			(layers "F.Cu" "F.Mask" "F.Paste")
			(roundrect_rratio 0.25)
			(net 8 "Net-(D3-C)")
			(pintype "passive")
		)
	)
	(footprint "antmicro-footprints:C_0402_1005Metric"
		(layer "F.Cu")
		(at 76.125 64.025 90)
		(descr "Capacitor SMD 0402")
		(tags "capacitor SMD 0402")
		(property "Reference" "C70"
			(at 1.825 0.175 90)
			(layer "F.SilkS")
			(effects
				(font
					(size 0.7 0.7)
					(thickness 0.15)
				)
				(justify left bottom)
			)
		)
		(property "Value" "C_47p_0402"
			(at 0 1.4 90)
			(layer "F.Fab")
			(effects
				(font
					(size 0.7 0.7)
					(thickness 0.15)
				)
				(justify left bottom)
			)
		)
		(property "Datasheet" "https://www.kemet.com/en/us/capacitors/product/C0402C470J5GACTU.html"
			(at 0 0 90)
			(layer "F.Fab")
			(hide yes)
			(effects
				(font
					(size 1.27 1.27)
					(thickness 0.15)
				)
			)
		)
		(property "Description" "SMD Multilayer Ceramic Capacitor, 47 pF, 50 V, 0402 [1005 Metric], ± 5%, C0G / NP0, C Series KEMET"
			(at 0 0 90)
			(layer "F.Fab")
			(hide yes)
			(effects
				(font
					(size 1.27 1.27)
					(thickness 0.15)
				)
			)
		)
		(property "Author" "Antmicro"
			(at 140.15 -12.1 0)
			(layer "F.Fab")
			(hide yes)
			(effects
				(font
					(size 1 1)
					(thickness 0.15)
				)
			)
		)
		(property "Dielectric" "C0G"
			(at 140.15 -12.1 0)
			(layer "F.Fab")
			(hide yes)
			(effects
				(font
					(size 1 1)
					(thickness 0.15)
				)
			)
		)
		(property "License" "Apache-2.0"
			(at 140.15 -12.1 0)
			(layer "F.Fab")
			(hide yes)
			(effects
				(font
					(size 1 1)
					(thickness 0.15)
				)
			)
		)
		(property "MPN" "C0402C470J5GACTU"
			(at 140.15 -12.1 0)
			(layer "F.Fab")
			(hide yes)
			(effects
				(font
					(size 1 1)
					(thickness 0.15)
				)
			)
		)
		(property "Manufacturer" "KEMET"
			(at 140.15 -12.1 0)
			(layer "F.Fab")
			(hide yes)
			(effects
				(font
					(size 1 1)
					(thickness 0.15)
				)
			)
		)
		(property "Val" "47p"
			(at 140.15 -12.1 0)
			(layer "F.Fab")
			(hide yes)
			(effects
				(font
					(size 1 1)
					(thickness 0.15)
				)
			)
		)
		(property "Voltage" ""
			(at 140.15 -12.1 0)
			(layer "F.Fab")
			(hide yes)
			(effects
				(font
					(size 1 1)
					(thickness 0.15)
				)
			)
		)
		(sheetname "/Power supply/")
		(sheetfile "power-supply.kicad_sch")
		(attr smd)
		(fp_rect
			(start -0.925 -0.47)
			(end 0.925 0.47)
			(stroke
				(width 0.05)
				(type default)
			)
			(fill no)
			(layer "F.CrtYd")
		)
		(fp_line
			(start 0.504 -0.25)
			(end 0.504 0.248)
			(stroke
				(width 0.15)
				(type solid)
			)
			(layer "F.Fab")
		)
		(fp_line
			(start -0.494 -0.25)
			(end 0.504 -0.25)
			(stroke
				(width 0.15)
				(type solid)
			)
			(layer "F.Fab")
		)
		(fp_line
			(start 0.504 0.248)
			(end -0.494 0.248)
			(stroke
				(width 0.15)
				(type solid)
			)
			(layer "F.Fab")
		)
		(fp_line
			(start -0.494 0.248)
			(end -0.494 -0.25)
			(stroke
				(width 0.15)
				(type solid)
			)
			(layer "F.Fab")
		)
		(pad "1" smd roundrect
			(at -0.48 0 90)
			(size 0.59 0.64)
			(layers "F.Cu" "F.Mask" "F.Paste")
			(roundrect_rratio 0.25)
			(net 1 "GND")
			(pintype "passive")
		)
		(pad "2" smd roundrect
			(at 0.48 0 90)
			(size 0.59 0.64)
			(layers "F.Cu" "F.Mask" "F.Paste")
			(roundrect_rratio 0.25)
			(net 107 "Net-(U25-COMP)")
			(pintype "passive")
		)
	)
	(footprint "antmicro-footprints:C_0402_1005Metric"
		(layer "F.Cu")
		(at 82.765 61.45 -90)
		(descr "Capacitor SMD 0402")
		(tags "capacitor SMD 0402")
		(property "Reference" "C69"
			(at -2.45 0.565 90)
			(layer "F.SilkS")
			(effects
				(font
					(size 0.7 0.7)
					(thickness 0.15)
				)
				(justify right bottom)
			)
		)
		(property "Value" "C_10n_0402"
			(at 0 1.4 90)
			(layer "F.Fab")
			(effects
				(font
					(size 0.7 0.7)
					(thickness 0.15)
				)
				(justify right bottom)
			)
		)
		(property "Datasheet" "https://www.murata.com/products/productdetail?partno=GRM155R71H103KA88%23"
			(at 0 0 270)
			(layer "F.Fab")
			(hide yes)
			(effects
				(font
					(size 1.27 1.27)
					(thickness 0.15)
				)
			)
		)
		(property "Description" "SMD Multilayer Ceramic Capacitor, 10000 pF, 50 V, 0402 [1005 Metric], ± 10%, X7R, GRM Series"
			(at 0 0 270)
			(layer "F.Fab")
			(hide yes)
			(effects
				(font
					(size 1.27 1.27)
					(thickness 0.15)
				)
			)
		)
		(property "Author" "Antmicro"
			(at 21.315 144.215 0)
			(layer "F.Fab")
			(hide yes)
			(effects
				(font
					(size 1 1)
					(thickness 0.15)
				)
			)
		)
		(property "Dielectric" "X7R"
			(at 21.315 144.215 0)
			(layer "F.Fab")
			(hide yes)
			(effects
				(font
					(size 1 1)
					(thickness 0.15)
				)
			)
		)
		(property "License" "Apache-2.0"
			(at 21.315 144.215 0)
			(layer "F.Fab")
			(hide yes)
			(effects
				(font
					(size 1 1)
					(thickness 0.15)
				)
			)
		)
		(property "MPN" "GRM155R71H103KA88D"
			(at 21.315 144.215 0)
			(layer "F.Fab")
			(hide yes)
			(effects
				(font
					(size 1 1)
					(thickness 0.15)
				)
			)
		)
		(property "Manufacturer" "Murata"
			(at 21.315 144.215 0)
			(layer "F.Fab")
			(hide yes)
			(effects
				(font
					(size 1 1)
					(thickness 0.15)
				)
			)
		)
		(property "Val" "10n"
			(at 21.315 144.215 0)
			(layer "F.Fab")
			(hide yes)
			(effects
				(font
					(size 1 1)
					(thickness 0.15)
				)
			)
		)
		(property "Voltage" "50V"
			(at 21.315 144.215 0)
			(layer "F.Fab")
			(hide yes)
			(effects
				(font
					(size 1 1)
					(thickness 0.15)
				)
			)
		)
		(sheetname "/Power supply/")
		(sheetfile "power-supply.kicad_sch")
		(attr smd)
		(fp_rect
			(start -0.925 -0.47)
			(end 0.925 0.47)
			(stroke
				(width 0.05)
				(type default)
			)
			(fill no)
			(layer "F.CrtYd")
		)
		(fp_line
			(start -0.494 0.248)
			(end -0.494 -0.25)
			(stroke
				(width 0.15)
				(type solid)
			)
			(layer "F.Fab")
		)
		(fp_line
			(start 0.504 0.248)
			(end -0.494 0.248)
			(stroke
				(width 0.15)
				(type solid)
			)
			(layer "F.Fab")
		)
		(fp_line
			(start -0.494 -0.25)
			(end 0.504 -0.25)
			(stroke
				(width 0.15)
				(type solid)
			)
			(layer "F.Fab")
		)
		(fp_line
			(start 0.504 -0.25)
			(end 0.504 0.248)
			(stroke
				(width 0.15)
				(type solid)
			)
			(layer "F.Fab")
		)
		(pad "1" smd roundrect
			(at -0.48 0 270)
			(size 0.59 0.64)
			(layers "F.Cu" "F.Mask" "F.Paste")
			(roundrect_rratio 0.25)
			(net 1 "GND")
			(pintype "passive")
		)
		(pad "2" smd roundrect
			(at 0.48 0 270)
			(size 0.59 0.64)
			(layers "F.Cu" "F.Mask" "F.Paste")
			(roundrect_rratio 0.25)
			(net 106 "Net-(U25-SS{slash}TR)")
			(pintype "passive")
		)
	)
	(footprint "antmicro-footprints:C_0402_1005Metric"
		(layer "F.Cu")
		(at 75.025 64.025 90)
		(descr "Capacitor SMD 0402")
		(tags "capacitor SMD 0402")
		(property "Reference" "C68"
			(at 1.825 0.175 90)
			(layer "F.SilkS")
			(effects
				(font
					(size 0.7 0.7)
					(thickness 0.15)
				)
				(justify left bottom)
			)
		)
		(property "Value" "C_4n7_0402"
			(at 0 1.4 90)
			(layer "F.Fab")
			(effects
				(font
					(size 0.7 0.7)
					(thickness 0.15)
				)
				(justify left bottom)
			)
		)
		(property "Datasheet" "https://product.tdk.com/en/search/capacitor/ceramic/mlcc/info?part_no=CGA2B3X7S2A472K050BB"
			(at 0 0 90)
			(layer "F.Fab")
			(hide yes)
			(effects
				(font
					(size 1.27 1.27)
					(thickness 0.15)
				)
			)
		)
		(property "Description" "SMD Multilayer Ceramic Capacitor, 4700 pF, 100 V, 0402 [1005 Metric], ± 10%, X7S, CGA"
			(at 0 0 90)
			(layer "F.Fab")
			(hide yes)
			(effects
				(font
					(size 1.27 1.27)
					(thickness 0.15)
				)
			)
		)
		(property "Author" "Antmicro"
			(at 139.05 -11 0)
			(layer "F.Fab")
			(hide yes)
			(effects
				(font
					(size 1 1)
					(thickness 0.15)
				)
			)
		)
		(property "Dielectric" ""
			(at 139.05 -11 0)
			(layer "F.Fab")
			(hide yes)
			(effects
				(font
					(size 1 1)
					(thickness 0.15)
				)
			)
		)
		(property "License" "Apache-2.0"
			(at 139.05 -11 0)
			(layer "F.Fab")
			(hide yes)
			(effects
				(font
					(size 1 1)
					(thickness 0.15)
				)
			)
		)
		(property "MPN" "CGA2B3X7S2A472K050BB"
			(at 139.05 -11 0)
			(layer "F.Fab")
			(hide yes)
			(effects
				(font
					(size 1 1)
					(thickness 0.15)
				)
			)
		)
		(property "Manufacturer" "TDK"
			(at 139.05 -11 0)
			(layer "F.Fab")
			(hide yes)
			(effects
				(font
					(size 1 1)
					(thickness 0.15)
				)
			)
		)
		(property "Val" "4n7"
			(at 139.05 -11 0)
			(layer "F.Fab")
			(hide yes)
			(effects
				(font
					(size 1 1)
					(thickness 0.15)
				)
			)
		)
		(property "Voltage" ""
			(at 139.05 -11 0)
			(layer "F.Fab")
			(hide yes)
			(effects
				(font
					(size 1 1)
					(thickness 0.15)
				)
			)
		)
		(sheetname "/Power supply/")
		(sheetfile "power-supply.kicad_sch")
		(attr smd)
		(fp_rect
			(start -0.925 -0.47)
			(end 0.925 0.47)
			(stroke
				(width 0.05)
				(type default)
			)
			(fill no)
			(layer "F.CrtYd")
		)
		(fp_line
			(start 0.504 -0.25)
			(end 0.504 0.248)
			(stroke
				(width 0.15)
				(type solid)
			)
			(layer "F.Fab")
		)
		(fp_line
			(start -0.494 -0.25)
			(end 0.504 -0.25)
			(stroke
				(width 0.15)
				(type solid)
			)
			(layer "F.Fab")
		)
		(fp_line
			(start 0.504 0.248)
			(end -0.494 0.248)
			(stroke
				(width 0.15)
				(type solid)
			)
			(layer "F.Fab")
		)
		(fp_line
			(start -0.494 0.248)
			(end -0.494 -0.25)
			(stroke
				(width 0.15)
				(type solid)
			)
			(layer "F.Fab")
		)
		(pad "1" smd roundrect
			(at -0.48 0 90)
			(size 0.59 0.64)
			(layers "F.Cu" "F.Mask" "F.Paste")
			(roundrect_rratio 0.25)
			(net 1 "GND")
			(pintype "passive")
		)
		(pad "2" smd roundrect
			(at 0.48 0 90)
			(size 0.59 0.64)
			(layers "F.Cu" "F.Mask" "F.Paste")
			(roundrect_rratio 0.25)
			(net 111 "Net-(C68-Pad2)")
			(pintype "passive")
		)
	)
	(footprint "antmicro-footprints:LED_0603_1608Metric_G"
		(layer "F.Cu")
		(at 138.99 61.165 90)
		(descr "LED SMD 0603 Green")
		(tags "LED SMD 0603 Green")
		(property "Reference" "D11"
			(at -1.435 5.61 90)
			(layer "F.SilkS")
			(effects
				(font
					(size 0.7 0.7)
					(thickness 0.15)
				)
				(justify left bottom)
			)
		)
		(property "Value" "LED_G_0603_LG_L29K-G2J1-24-Z"
			(at 0 1.6 90)
			(layer "F.Fab")
			(effects
				(font
					(size 0.7 0.7)
					(thickness 0.15)
				)
				(justify left bottom)
			)
		)
		(property "Datasheet" "https://look.ams-osram.com/m/19ee86b3ae0ee95b/original/LG-L29K.pdf"
			(at 0 0 90)
			(layer "F.Fab")
			(hide yes)
			(effects
				(font
					(size 1.27 1.27)
					(thickness 0.15)
				)
			)
		)
		(property "Description" "LED, Green, SMD, 0603, 20 mA, 1.7 V, 570 nm"
			(at 0 0 90)
			(layer "F.Fab")
			(hide yes)
			(effects
				(font
					(size 1.27 1.27)
					(thickness 0.15)
				)
			)
		)
		(property "Author" "Antmicro"
			(at 200.155 -77.825 0)
			(layer "F.Fab")
			(hide yes)
			(effects
				(font
					(size 1 1)
					(thickness 0.15)
				)
			)
		)
		(property "Color" "Green"
			(at 200.155 -77.825 0)
			(layer "F.Fab")
			(hide yes)
			(effects
				(font
					(size 1 1)
					(thickness 0.15)
				)
			)
		)
		(property "License" "Apache-2.0"
			(at 200.155 -77.825 0)
			(layer "F.Fab")
			(hide yes)
			(effects
				(font
					(size 1 1)
					(thickness 0.15)
				)
			)
		)
		(property "MPN" "LG L29K-G2J1-24-Z"
			(at 200.155 -77.825 0)
			(layer "F.Fab")
			(hide yes)
			(effects
				(font
					(size 1 1)
					(thickness 0.15)
				)
			)
		)
		(property "Manufacturer" "OSRAM"
			(at 200.155 -77.825 0)
			(layer "F.Fab")
			(hide yes)
			(effects
				(font
					(size 1 1)
					(thickness 0.15)
				)
			)
		)
		(sheetname "/FPGA banks 34-35 & CFG/")
		(sheetfile "fpga-banks-34-25-cfg.kicad_sch")
		(attr smd)
		(fp_line
			(start 0.22 -0.35)
			(end -0.22 -0.35)
			(stroke
				(width 0.15)
				(type solid)
			)
			(layer "F.SilkS")
		)
		(fp_line
			(start -1.18 -0.319)
			(end -1.18 0.321)
			(stroke
				(width 0.15)
				(type solid)
			)
			(layer "F.SilkS")
		)
		(fp_line
			(start 0.105328 0.001008)
			(end 0.24 0.001)
			(stroke
				(width 0.1)
				(type solid)
			)
			(layer "F.SilkS")
		)
		(fp_line
			(start -0.094672 0.001008)
			(end 0.105328 -0.198992)
			(stroke
				(width 0.1)
				(type solid)
			)
			(layer "F.SilkS")
		)
		(fp_line
			(start -0.094672 0.001008)
			(end -0.24 0.001008)
			(stroke
				(width 0.1)
				(type solid)
			)
			(layer "F.SilkS")
		)
		(fp_line
			(start 0.105328 0.201008)
			(end 0.105328 -0.198992)
			(stroke
				(width 0.1)
				(type solid)
			)
			(layer "F.SilkS")
		)
		(fp_line
			(start 0.105328 0.201008)
			(end -0.094672 0.001008)
			(stroke
				(width 0.1)
				(type solid)
			)
			(layer "F.SilkS")
		)
		(fp_line
			(start -0.094672 0.201008)
			(end -0.094672 -0.198992)
			(stroke
				(width 0.1)
				(type solid)
			)
			(layer "F.SilkS")
		)
		(fp_line
			(start 0.22 0.35)
			(end -0.22 0.35)
			(stroke
				(width 0.15)
				(type solid)
			)
			(layer "F.SilkS")
		)
		(fp_rect
			(start 1.25 0.65)
			(end -1.25 -0.65)
			(stroke
				(width 0.05)
				(type solid)
			)
			(fill no)
			(layer "F.CrtYd")
		)
		(fp_line
			(start 0.201 -0.202)
			(end -0.101 0)
			(stroke
				(width 0.15)
				(type solid)
			)
			(layer "F.Fab")
		)
		(fp_line
			(start -0.199 -0.202)
			(end -0.199 0.1)
			(stroke
				(width 0.15)
				(type solid)
			)
			(layer "F.Fab")
		)
		(fp_line
			(start 0.599 0)
			(end 0.201 0)
			(stroke
				(width 0.15)
				(type solid)
			)
			(layer "F.Fab")
		)
		(fp_line
			(start 0.201 0)
			(end 0.201 -0.202)
			(stroke
				(width 0.15)
				(type solid)
			)
			(layer "F.Fab")
		)
		(fp_line
			(start -0.101 0)
			(end 0.201 0.2)
			(stroke
				(width 0.15)
				(type solid)
			)
			(layer "F.Fab")
		)
		(fp_line
			(start -0.199 0)
			(end -0.597 0)
			(stroke
				(width 0.15)
				(type solid)
			)
			(layer "F.Fab")
		)
		(fp_line
			(start 0.201 0.2)
			(end 0.201 0)
			(stroke
				(width 0.15)
				(type solid)
			)
			(layer "F.Fab")
		)
		(fp_line
			(start -0.199 0.2)
			(end -0.199 0.1)
			(stroke
				(width 0.15)
				(type solid)
			)
			(layer "F.Fab")
		)
		(fp_rect
			(start 0.848 0.4)
			(end -0.85 -0.402)
			(stroke
				(width 0.15)
				(type solid)
			)
			(fill no)
			(layer "F.Fab")
		)
		(pad "1" smd roundrect
			(at -0.7 0 270)
			(size 0.8 1)
			(layers "F.Cu" "F.Mask" "F.Paste")
			(roundrect_rratio 0.2)
			(net 284 "Net-(D11-C)")
			(pinfunction "C")
			(pintype "passive")
		)
		(pad "2" smd roundrect
			(at 0.7 0 270)
			(size 0.8 1)
			(layers "F.Cu" "F.Mask" "F.Paste")
			(roundrect_rratio 0.2)
			(net 286 "Net-(D11-A)")
			(pinfunction "A")
			(pintype "passive")
		)
	)
	(footprint "antmicro-footprints:C_0402_1005Metric"
		(layer "F.Cu")
		(at 85.6 110.57 180)
		(descr "Capacitor SMD 0402")
		(tags "capacitor SMD 0402")
		(property "Reference" "C233"
			(at -1.78 0.545 0)
			(layer "F.SilkS")
			(effects
				(font
					(size 0.7 0.7)
					(thickness 0.15)
				)
				(justify right bottom)
			)
		)
		(property "Value" "C_100n_0402"
			(at 0 1.4 0)
			(layer "F.Fab")
			(effects
				(font
					(size 0.7 0.7)
					(thickness 0.15)
				)
				(justify right bottom)
			)
		)
		(property "Datasheet" "https://www.murata.com/products/productdetail?partno=GRM155R61H104KE14%23"
			(at 0 0 180)
			(layer "F.Fab")
			(hide yes)
			(effects
				(font
					(size 1.27 1.27)
					(thickness 0.15)
				)
			)
		)
		(property "Description" "SMD Multilayer Ceramic Capacitor, 0.1 µF, 50 V, 0402 [1005 Metric], ± 10%, X5R, GRM Series"
			(at 0 0 180)
			(layer "F.Fab")
			(hide yes)
			(effects
				(font
					(size 1.27 1.27)
					(thickness 0.15)
				)
			)
		)
		(property "Author" "Antmicro"
			(at 171.2 221.14 0)
			(layer "F.Fab")
			(hide yes)
			(effects
				(font
					(size 1 1)
					(thickness 0.15)
				)
			)
		)
		(property "Dielectric" "X5R"
			(at 171.2 221.14 0)
			(layer "F.Fab")
			(hide yes)
			(effects
				(font
					(size 1 1)
					(thickness 0.15)
				)
			)
		)
		(property "License" "Apache-2.0"
			(at 171.2 221.14 0)
			(layer "F.Fab")
			(hide yes)
			(effects
				(font
					(size 1 1)
					(thickness 0.15)
				)
			)
		)
		(property "MPN" "GRM155R61H104KE14D"
			(at 171.2 221.14 0)
			(layer "F.Fab")
			(hide yes)
			(effects
				(font
					(size 1 1)
					(thickness 0.15)
				)
			)
		)
		(property "Manufacturer" "Murata"
			(at 171.2 221.14 0)
			(layer "F.Fab")
			(hide yes)
			(effects
				(font
					(size 1 1)
					(thickness 0.15)
				)
			)
		)
		(property "Val" "100n"
			(at 171.2 221.14 0)
			(layer "F.Fab")
			(hide yes)
			(effects
				(font
					(size 1 1)
					(thickness 0.15)
				)
			)
		)
		(property "Voltage" "50V"
			(at 171.2 221.14 0)
			(layer "F.Fab")
			(hide yes)
			(effects
				(font
					(size 1 1)
					(thickness 0.15)
				)
			)
		)
		(property "DNP" ""
			(at 0 0 180)
			(unlocked yes)
			(layer "F.Fab")
			(hide yes)
			(effects
				(font
					(size 1 1)
					(thickness 0.15)
				)
			)
		)
		(sheetname "/FPGA banks 13-16/")
		(sheetfile "fpga-banks-13-16.kicad_sch")
		(attr smd)
		(fp_rect
			(start -0.925 -0.47)
			(end 0.925 0.47)
			(stroke
				(width 0.05)
				(type default)
			)
			(fill no)
			(layer "F.CrtYd")
		)
		(fp_line
			(start 0.504 0.248)
			(end -0.494 0.248)
			(stroke
				(width 0.15)
				(type solid)
			)
			(layer "F.Fab")
		)
		(fp_line
			(start 0.504 -0.25)
			(end 0.504 0.248)
			(stroke
				(width 0.15)
				(type solid)
			)
			(layer "F.Fab")
		)
		(fp_line
			(start -0.494 0.248)
			(end -0.494 -0.25)
			(stroke
				(width 0.15)
				(type solid)
			)
			(layer "F.Fab")
		)
		(fp_line
			(start -0.494 -0.25)
			(end 0.504 -0.25)
			(stroke
				(width 0.15)
				(type solid)
			)
			(layer "F.Fab")
		)
		(pad "1" smd roundrect
			(at -0.48 0 180)
			(size 0.59 0.64)
			(layers "F.Cu" "F.Mask" "F.Paste")
			(roundrect_rratio 0.25)
			(net 1 "GND")
			(pintype "passive")
		)
		(pad "2" smd roundrect
			(at 0.48 0 180)
			(size 0.59 0.64)
			(layers "F.Cu" "F.Mask" "F.Paste")
			(roundrect_rratio 0.25)
			(net 2 "VCC3V3")
			(pintype "passive")
		)
	)
	(footprint "antmicro-footprints:Oscillator_SMD_Abracon_AMJM_3.2x2.5mm"
		(layer "F.Cu")
		(at 82.938 111.624)
		(descr "Oscillator SMD, AMJM, 3.2x2.5mm")
		(property "Reference" "U15"
			(at -1.863 -2.374 0)
			(layer "F.SilkS")
			(effects
				(font
					(size 0.7 0.7)
					(thickness 0.15)
				)
				(justify left bottom)
			)
		)
		(property "Value" "Oscillator_100MHz_AMJMEFB"
			(at 1.05 3.798 0)
			(layer "F.Fab")
			(effects
				(font
					(size 0.7 0.7)
					(thickness 0.15)
				)
				(justify left bottom)
			)
		)
		(property "Datasheet" "https://abracon.com/datasheets/AMJM.pdf"
			(at 0 0 0)
			(layer "F.Fab")
			(hide yes)
			(effects
				(font
					(size 1.27 1.27)
					(thickness 0.15)
				)
			)
		)
		(property "Description" "MEMS Oscillator, 100 MHz, SMT, 3.2mm x 2.5mm, 25 ppm, 2.5 V, AMJM"
			(at 0 0 0)
			(layer "F.Fab")
			(hide yes)
			(effects
				(font
					(size 1.27 1.27)
					(thickness 0.15)
				)
			)
		)
		(property "Author" "Antmicro"
			(at 0 0 0)
			(layer "F.Fab")
			(hide yes)
			(effects
				(font
					(size 1 1)
					(thickness 0.15)
				)
			)
		)
		(property "License" "Apache-2.0"
			(at 0 0 0)
			(layer "F.Fab")
			(hide yes)
			(effects
				(font
					(size 1 1)
					(thickness 0.15)
				)
			)
		)
		(property "MPN" "AMJMEFB-100.0000T"
			(at 0 0 0)
			(layer "F.Fab")
			(hide yes)
			(effects
				(font
					(size 1 1)
					(thickness 0.15)
				)
			)
		)
		(property "Manufacturer" "Abracon"
			(at 0 0 0)
			(layer "F.Fab")
			(hide yes)
			(effects
				(font
					(size 1 1)
					(thickness 0.15)
				)
			)
		)
		(property "Val" "100 MHz"
			(at 0 0 0)
			(layer "F.Fab")
			(hide yes)
			(effects
				(font
					(size 1 1)
					(thickness 0.15)
				)
			)
		)
		(sheetname "/FPGA banks 13-16/")
		(sheetfile "fpga-banks-13-16.kicad_sch")
		(attr smd)
		(fp_circle
			(center -1.448 -1.754)
			(end -1.397 -1.754)
			(stroke
				(width 0.15)
				(type solid)
			)
			(fill yes)
			(layer "F.SilkS")
		)
		(fp_rect
			(start -1.5 -1.8)
			(end 1.6 1.8)
			(stroke
				(width 0.05)
				(type solid)
			)
			(fill no)
			(layer "F.CrtYd")
		)
		(fp_line
			(start -0.977 -0.822)
			(end -0.554 -1.246)
			(stroke
				(width 0.15)
				(type solid)
			)
			(layer "F.Fab")
		)
		(pad "1" smd roundrect
			(at -0.876 -1.045)
			(size 1 0.9)
			(layers "F.Cu" "F.Mask" "F.Paste")
			(roundrect_rratio 0.1)
			(chamfer_ratio 0.2)
			(chamfer top_left)
			(net 2 "VCC3V3")
			(pinfunction "EN")
			(pintype "input")
		)
		(pad "2" smd roundrect
			(at -0.876 1.056)
			(size 1 0.9)
			(layers "F.Cu" "F.Mask" "F.Paste")
			(roundrect_rratio 0.1)
			(net 1 "GND")
			(pinfunction "GND")
			(pintype "power_in")
		)
		(pad "3" smd roundrect
			(at 0.922 1.056)
			(size 1 0.9)
			(layers "F.Cu" "F.Mask" "F.Paste")
			(roundrect_rratio 0.1)
			(net 503 "/FPGA banks 13-16/GCLK100")
			(pinfunction "OUT")
			(pintype "output")
		)
		(pad "4" smd roundrect
			(at 0.922 -1.045)
			(size 1 0.9)
			(layers "F.Cu" "F.Mask" "F.Paste")
			(roundrect_rratio 0.1)
			(net 2 "VCC3V3")
			(pinfunction "VDD")
			(pintype "power_in")
		)
	)
	(footprint "antmicro-footprints:C_0402_1005Metric"
		(layer "F.Cu")
		(at 132.275 154.43 -90)
		(descr "Capacitor SMD 0402")
		(tags "capacitor SMD 0402")
		(property "Reference" "C31"
			(at -2.98 -0.33 90)
			(layer "F.SilkS")
			(effects
				(font
					(size 0.7 0.7)
					(thickness 0.15)
				)
				(justify right bottom)
			)
		)
		(property "Value" "C_10u_0402"
			(at 0 1.4 90)
			(layer "F.Fab")
			(effects
				(font
					(size 0.7 0.7)
					(thickness 0.15)
				)
				(justify right bottom)
			)
		)
		(property "Datasheet" "https://www.yageo.com/en/Chart/Download/pdf/CC0402MRX5R5BB106"
			(at 0 0 270)
			(layer "F.Fab")
			(hide yes)
			(effects
				(font
					(size 1.27 1.27)
					(thickness 0.15)
				)
			)
		)
		(property "Description" "SMD Multilayer Ceramic Capacitor, 10 µF, 6.3 V, 0402 [1005 Metric], ± 20%, X5R, CC Series"
			(at 0 0 270)
			(layer "F.Fab")
			(hide yes)
			(effects
				(font
					(size 1.27 1.27)
					(thickness 0.15)
				)
			)
		)
		(property "Author" "Antmicro"
			(at -22.155 286.705 0)
			(layer "F.Fab")
			(hide yes)
			(effects
				(font
					(size 1 1)
					(thickness 0.15)
				)
			)
		)
		(property "Dielectric" ""
			(at -22.155 286.705 0)
			(layer "F.Fab")
			(hide yes)
			(effects
				(font
					(size 1 1)
					(thickness 0.15)
				)
			)
		)
		(property "License" "Apache-2.0"
			(at -22.155 286.705 0)
			(layer "F.Fab")
			(hide yes)
			(effects
				(font
					(size 1 1)
					(thickness 0.15)
				)
			)
		)
		(property "MPN" "CC0402MRX5R5BB106"
			(at -22.155 286.705 0)
			(layer "F.Fab")
			(hide yes)
			(effects
				(font
					(size 1 1)
					(thickness 0.15)
				)
			)
		)
		(property "Manufacturer" "YAGEO"
			(at -22.155 286.705 0)
			(layer "F.Fab")
			(hide yes)
			(effects
				(font
					(size 1 1)
					(thickness 0.15)
				)
			)
		)
		(property "Val" "10u"
			(at -22.155 286.705 0)
			(layer "F.Fab")
			(hide yes)
			(effects
				(font
					(size 1 1)
					(thickness 0.15)
				)
			)
		)
		(property "Voltage" ""
			(at -22.155 286.705 0)
			(layer "F.Fab")
			(hide yes)
			(effects
				(font
					(size 1 1)
					(thickness 0.15)
				)
			)
		)
		(sheetname "/PCIe-connector/")
		(sheetfile "pcie-conn.kicad_sch")
		(attr smd)
		(fp_rect
			(start -0.925 -0.47)
			(end 0.925 0.47)
			(stroke
				(width 0.05)
				(type default)
			)
			(fill no)
			(layer "F.CrtYd")
		)
		(fp_line
			(start -0.494 0.248)
			(end -0.494 -0.25)
			(stroke
				(width 0.15)
				(type solid)
			)
			(layer "F.Fab")
		)
		(fp_line
			(start 0.504 0.248)
			(end -0.494 0.248)
			(stroke
				(width 0.15)
				(type solid)
			)
			(layer "F.Fab")
		)
		(fp_line
			(start -0.494 -0.25)
			(end 0.504 -0.25)
			(stroke
				(width 0.15)
				(type solid)
			)
			(layer "F.Fab")
		)
		(fp_line
			(start 0.504 -0.25)
			(end 0.504 0.248)
			(stroke
				(width 0.15)
				(type solid)
			)
			(layer "F.Fab")
		)
		(pad "1" smd roundrect
			(at -0.48 0 270)
			(size 0.59 0.64)
			(layers "F.Cu" "F.Mask" "F.Paste")
			(roundrect_rratio 0.25)
			(net 1 "GND")
			(pintype "passive")
		)
		(pad "2" smd roundrect
			(at 0.48 0 270)
			(size 0.59 0.64)
			(layers "F.Cu" "F.Mask" "F.Paste")
			(roundrect_rratio 0.25)
			(net 2 "VCC3V3")
			(pintype "passive")
		)
	)
	(footprint "antmicro-footprints:R_0402_1005Metric"
		(layer "F.Cu")
		(at 78 73.705)
		(descr "Resistor SMD 0402")
		(tags "resistor SMD 0402")
		(property "Reference" "R70"
			(at -17.7 -1.505 0)
			(layer "F.SilkS")
			(effects
				(font
					(size 0.7 0.7)
					(thickness 0.15)
				)
				(justify left bottom)
			)
		)
		(property "Value" "R_49R9_0402"
			(at 0 1.4 0)
			(layer "F.Fab")
			(effects
				(font
					(size 0.7 0.7)
					(thickness 0.15)
				)
				(justify left bottom)
			)
		)
		(property "Datasheet" "https://www.bourns.com/docs/product-datasheets/cr.pdf"
			(at 0 0 0)
			(layer "F.Fab")
			(hide yes)
			(effects
				(font
					(size 1.27 1.27)
					(thickness 0.15)
				)
			)
		)
		(property "Description" "SMD Chip Resistor, 49.9 ohm, ± 1%, 62.5 mW, 0402 [1005 Metric], Thick Film, General Purpose"
			(at 0 0 0)
			(layer "F.Fab")
			(hide yes)
			(effects
				(font
					(size 1.27 1.27)
					(thickness 0.15)
				)
			)
		)
		(property "Author" "Antmicro"
			(at 0 0 0)
			(layer "F.Fab")
			(hide yes)
			(effects
				(font
					(size 1 1)
					(thickness 0.15)
				)
			)
		)
		(property "License" "Apache-2.0"
			(at 0 0 0)
			(layer "F.Fab")
			(hide yes)
			(effects
				(font
					(size 1 1)
					(thickness 0.15)
				)
			)
		)
		(property "MPN" "CR0402-FX-49R9GLF"
			(at 0 0 0)
			(layer "F.Fab")
			(hide yes)
			(effects
				(font
					(size 1 1)
					(thickness 0.15)
				)
			)
		)
		(property "Manufacturer" "Bourns"
			(at 0 0 0)
			(layer "F.Fab")
			(hide yes)
			(effects
				(font
					(size 1 1)
					(thickness 0.15)
				)
			)
		)
		(property "Tolerance" "1%"
			(at 0 0 0)
			(layer "F.Fab")
			(hide yes)
			(effects
				(font
					(size 1 1)
					(thickness 0.15)
				)
			)
		)
		(property "Val" "49R9"
			(at 0 0 0)
			(layer "F.Fab")
			(hide yes)
			(effects
				(font
					(size 1 1)
					(thickness 0.15)
				)
			)
		)
		(sheetname "/Power supply/")
		(sheetfile "power-supply.kicad_sch")
		(attr smd)
		(fp_rect
			(start -0.925 -0.47)
			(end 0.925 0.47)
			(stroke
				(width 0.05)
				(type default)
			)
			(fill no)
			(layer "F.CrtYd")
		)
		(fp_rect
			(start -0.5 -0.25)
			(end 0.5 0.25)
			(stroke
				(width 0.15)
				(type solid)
			)
			(fill no)
			(layer "F.Fab")
		)
		(pad "1" smd roundrect
			(at -0.48 0)
			(size 0.59 0.64)
			(layers "F.Cu" "F.Mask" "F.Paste")
			(roundrect_rratio 0.25)
			(net 114 "Net-(C72-Pad2)")
			(pintype "passive")
		)
		(pad "2" smd roundrect
			(at 0.48 0)
			(size 0.59 0.64)
			(layers "F.Cu" "F.Mask" "F.Paste")
			(roundrect_rratio 0.25)
			(net 205 "Net-(R70-Pad2)")
			(pintype "passive")
		)
	)
	(footprint "antmicro-footprints:TP_SMD_1mm"
		(layer "F.Cu")
		(at 124.95 66.7808)
		(property "Reference" "TP7"
			(at 0.55 0.4192 0)
			(layer "F.SilkS")
			(effects
				(font
					(size 0.7 0.7)
					(thickness 0.15)
				)
				(justify left bottom)
			)
		)
		(property "Value" "TP_1mm_SMD"
			(at 0 1.4 0)
			(layer "F.Fab")
			(effects
				(font
					(size 0.7 0.7)
					(thickness 0.15)
				)
				(justify left bottom)
			)
		)
		(property "Description" "Test point 1mm SMD"
			(at 0 0 0)
			(layer "F.Fab")
			(hide yes)
			(effects
				(font
					(size 1.27 1.27)
					(thickness 0.15)
				)
			)
		)
		(property "Author" "Antmicro"
			(at 0 0 0)
			(layer "F.Fab")
			(hide yes)
			(effects
				(font
					(size 1 1)
					(thickness 0.15)
				)
			)
		)
		(property "License" "Apache-2.0"
			(at 0 0 0)
			(layer "F.Fab")
			(hide yes)
			(effects
				(font
					(size 1 1)
					(thickness 0.15)
				)
			)
		)
		(property "MPN" ""
			(at 0 0 0)
			(layer "F.Fab")
			(hide yes)
			(effects
				(font
					(size 1 1)
					(thickness 0.15)
				)
			)
		)
		(property "Manufacturer" ""
			(at 0 0 0)
			(layer "F.Fab")
			(hide yes)
			(effects
				(font
					(size 1 1)
					(thickness 0.15)
				)
			)
		)
		(sheetname "/Interfaces/")
		(sheetfile "interfaces.kicad_sch")
		(attr exclude_from_pos_files exclude_from_bom)
		(fp_circle
			(center 0 0)
			(end 0.6 0)
			(stroke
				(width 0.05)
				(type default)
			)
			(fill no)
			(layer "F.CrtYd")
		)
		(pad "1" smd circle
			(at 0 0)
			(size 1 1)
			(layers "F.Cu" "F.Mask")
			(net 282 "Net-(J3-ID)")
			(pinfunction "1")
			(pintype "passive")
		)
	)
	(footprint "antmicro-footprints:USB-Micro-B_Receptacle_Amphenol_10118192"
		(layer "F.Cu")
		(at 126.225 61.655 180)
		(property "Reference" "J3"
			(at 5.025 -4.145 180)
			(layer "F.SilkS")
			(effects
				(font
					(size 0.7 0.7)
					(thickness 0.15)
				)
				(justify left bottom)
			)
		)
		(property "Value" "USB-Micro-B_Amphenol_10118192-0001LF"
			(at 0 4 180)
			(layer "F.Fab")
			(effects
				(font
					(size 0.7 0.7)
					(thickness 0.15)
				)
				(justify left bottom)
			)
		)
		(property "Datasheet" "http://www.amphenol-icc.com/media/wysiwyg/files/drawing/10118192.pdf"
			(at 0 0 180)
			(layer "F.Fab")
			(hide yes)
			(effects
				(font
					(size 1.27 1.27)
					(thickness 0.15)
				)
			)
		)
		(property "Description" "USB - micro B USB 2.0 Receptacle Connector 5 Position Surface Mount, Right Angle"
			(at 0 0 180)
			(layer "F.Fab")
			(hide yes)
			(effects
				(font
					(size 1.27 1.27)
					(thickness 0.15)
				)
			)
		)
		(property "Author" "Antmicro"
			(at 252.45 123.31 0)
			(layer "F.Fab")
			(hide yes)
			(effects
				(font
					(size 1 1)
					(thickness 0.15)
				)
			)
		)
		(property "License" "Apache-2.0"
			(at 252.45 123.31 0)
			(layer "F.Fab")
			(hide yes)
			(effects
				(font
					(size 1 1)
					(thickness 0.15)
				)
			)
		)
		(property "MPN" "10118192-0001LF"
			(at 252.45 123.31 0)
			(layer "F.Fab")
			(hide yes)
			(effects
				(font
					(size 1 1)
					(thickness 0.15)
				)
			)
		)
		(property "Manufacturer" "Amphenol"
			(at 252.45 123.31 0)
			(layer "F.Fab")
			(hide yes)
			(effects
				(font
					(size 1 1)
					(thickness 0.15)
				)
			)
		)
		(property "VSD_class" "USB Micro"
			(at 252.45 123.31 0)
			(layer "F.Fab")
			(hide yes)
			(effects
				(font
					(size 1 1)
					(thickness 0.15)
				)
			)
		)
		(sheetname "/Interfaces/")
		(sheetfile "interfaces.kicad_sch")
		(attr smd)
		(fp_line
			(start 4.049 -1.151)
			(end 4.049 -0.652)
			(stroke
				(width 0.15)
				(type solid)
			)
			(layer "F.SilkS")
		)
		(fp_line
			(start 1.65 -2.902)
			(end 1.949 -2.902)
			(stroke
				(width 0.15)
				(type solid)
			)
			(layer "F.SilkS")
		)
		(fp_line
			(start -1.901 -2.902)
			(end -1.601 -2.902)
			(stroke
				(width 0.15)
				(type solid)
			)
			(layer "F.SilkS")
		)
		(fp_line
			(start -4.05 -1.151)
			(end -4.05 -0.701)
			(stroke
				(width 0.15)
				(type solid)
			)
			(layer "F.SilkS")
		)
		(fp_circle
			(center -1.75 -3.15)
			(end -1.7 -3.15)
			(stroke
				(width 0.15)
				(type solid)
			)
			(fill no)
			(layer "F.SilkS")
		)
		(fp_rect
			(start -4.758 -3.051)
			(end 4.755 3.048)
			(stroke
				(width 0.05)
				(type solid)
			)
			(fill no)
			(layer "F.CrtYd")
		)
		(fp_line
			(start 3.95 2.769)
			(end 3.95 -2.801)
			(stroke
				(width 0.15)
				(type solid)
			)
			(layer "F.Fab")
		)
		(fp_line
			(start 3.95 -2.801)
			(end -3.5 -2.801)
			(stroke
				(width 0.15)
				(type solid)
			)
			(layer "F.Fab")
		)
		(fp_line
			(start -3.951 2.769)
			(end 3.95 2.769)
			(stroke
				(width 0.15)
				(type solid)
			)
			(layer "F.Fab")
		)
		(fp_line
			(start -3.951 -2.351)
			(end -3.5 -2.801)
			(stroke
				(width 0.15)
				(type solid)
			)
			(layer "F.Fab")
		)
		(fp_line
			(start -3.951 -2.351)
			(end -3.951 2.749)
			(stroke
				(width 0.15)
				(type solid)
			)
			(layer "F.Fab")
		)
		(pad "1" smd rect
			(at -1.301 -2.226 180)
			(size 0.4 1.35)
			(layers "F.Cu" "F.Mask" "F.Paste")
			(net 240 "/Interfaces/VBUS")
			(pinfunction "VBUS")
			(pintype "passive")
		)
		(pad "2" smd rect
			(at -0.651 -2.226 180)
			(size 0.4 1.35)
			(layers "F.Cu" "F.Mask" "F.Paste")
			(net 213 "/Interfaces/DBG_USB_D_N")
			(pinfunction "D-")
			(pintype "bidirectional")
		)
		(pad "3" smd rect
			(at 0 -2.226 180)
			(size 0.4 1.35)
			(layers "F.Cu" "F.Mask" "F.Paste")
			(net 212 "/Interfaces/DBG_USB_D_P")
			(pinfunction "D+")
			(pintype "bidirectional")
		)
		(pad "4" smd rect
			(at 0.65 -2.226 180)
			(size 0.4 1.35)
			(layers "F.Cu" "F.Mask" "F.Paste")
			(net 282 "Net-(J3-ID)")
			(pinfunction "ID")
			(pintype "bidirectional")
		)
		(pad "5" smd rect
			(at 1.3 -2.226 180)
			(size 0.4 1.35)
			(layers "F.Cu" "F.Mask" "F.Paste")
			(net 1 "GND")
			(pinfunction "GND")
			(pintype "power_in")
		)
		(pad "SH" smd roundrect
			(at -3.801 0.449 180)
			(size 1.8 1.9)
			(layers "F.Cu" "F.Mask" "F.Paste")
			(roundrect_rratio 0.1)
			(net 1 "GND")
			(pinfunction "SHIELD")
			(pintype "passive")
		)
		(pad "SH" smd roundrect
			(at -3.101 -2.101 180)
			(size 2.1 1.6)
			(layers "F.Cu" "F.Mask" "F.Paste")
			(roundrect_rratio 0.1)
			(net 1 "GND")
			(pinfunction "SHIELD")
			(pintype "passive")
		)
		(pad "SH" smd roundrect
			(at -1.2 0.449 180)
			(size 1.9 1.9)
			(layers "F.Cu" "F.Mask" "F.Paste")
			(roundrect_rratio 0.1)
			(net 1 "GND")
			(pinfunction "SHIELD")
			(pintype "passive")
		)
		(pad "SH" smd roundrect
			(at 1.199 0.449 180)
			(size 1.9 1.9)
			(layers "F.Cu" "F.Mask" "F.Paste")
			(roundrect_rratio 0.1)
			(net 1 "GND")
			(pinfunction "SHIELD")
			(pintype "passive")
		)
		(pad "SH" smd roundrect
			(at 3.1 -2.101 180)
			(size 2.1 1.6)
			(layers "F.Cu" "F.Mask" "F.Paste")
			(roundrect_rratio 0.1)
			(net 1 "GND")
			(pinfunction "SHIELD")
			(pintype "passive")
		)
		(pad "SH" smd roundrect
			(at 3.8 0.449 180)
			(size 1.8 1.9)
			(layers "F.Cu" "F.Mask" "F.Paste")
			(roundrect_rratio 0.1)
			(net 1 "GND")
			(pinfunction "SHIELD")
			(pintype "passive")
		)
	)
	(footprint "antmicro-footprints:PinHeader_2x7_P2mm_Drill0.9mm_878311420"
		(layer "F.Cu")
		(at 142.625 68.555 180)
		(descr "2.00mm Pitch, Milli-Grid PCB Header, Dual Row, Vertical, Through Hole, Shrouded, 14 Circuits, 0.38µm Gold (Au) Plating, with Center Polarization Slot, with Locking Window, without PCB Locator, Tube")
		(tags "PINSTRIP, HEADER ")
		(property "Reference" "J6"
			(at 0 -5.555 180)
			(layer "F.SilkS")
			(effects
				(font
					(size 0.7 0.7)
					(thickness 0.15)
				)
				(justify left bottom)
			)
		)
		(property "Value" "PinHeader_2x7_P2mm_Drill0.9mm_878311420"
			(at 0 3.4 180)
			(layer "F.Fab")
			(effects
				(font
					(size 0.7 0.7)
					(thickness 0.15)
				)
				(justify left bottom)
			)
		)
		(property "Datasheet" "https://www.molex.com/en-us/products/part-detail-pdf/878311420?display=pdf"
			(at 0 0 180)
			(layer "F.Fab")
			(hide yes)
			(effects
				(font
					(size 1.27 1.27)
					(thickness 0.15)
				)
			)
		)
		(property "Description" "2.00mm Pitch, Milli-Grid PCB Header, Dual Row, Vertical, Through Hole, Shrouded, 14 Circuits, 0.38µm Gold (Au) Plating, with Center Polarization Slot, with Locking Window, without PCB Locator, Tube"
			(at 0 0 180)
			(layer "F.Fab")
			(hide yes)
			(effects
				(font
					(size 1.27 1.27)
					(thickness 0.15)
				)
			)
		)
		(property "Author" "Antmicro"
			(at 285.25 137.11 0)
			(layer "F.Fab")
			(hide yes)
			(effects
				(font
					(size 1 1)
					(thickness 0.15)
				)
			)
		)
		(property "License" "Apache-2.0"
			(at 285.25 137.11 0)
			(layer "F.Fab")
			(hide yes)
			(effects
				(font
					(size 1 1)
					(thickness 0.15)
				)
			)
		)
		(property "MPN" "878311420"
			(at 285.25 137.11 0)
			(layer "F.Fab")
			(hide yes)
			(effects
				(font
					(size 1 1)
					(thickness 0.15)
				)
			)
		)
		(property "Manufacturer" "Molex"
			(at 285.25 137.11 0)
			(layer "F.Fab")
			(hide yes)
			(effects
				(font
					(size 1 1)
					(thickness 0.15)
				)
			)
		)
		(sheetname "/Interfaces/")
		(sheetfile "interfaces.kicad_sch")
		(attr through_hole)
		(fp_line
			(start 14.4 2.2)
			(end 7.3 2.2)
			(stroke
				(width 0.15)
				(type solid)
			)
			(layer "F.SilkS")
		)
		(fp_line
			(start 14.4 -4.2)
			(end 14.4 2.2)
			(stroke
				(width 0.15)
				(type solid)
			)
			(layer "F.SilkS")
		)
		(fp_line
			(start -2.4 2.2)
			(end -2.4 -4.2)
			(stroke
				(width 0.15)
				(type solid)
			)
			(layer "F.SilkS")
		)
		(fp_line
			(start -2.4 -4.2)
			(end 14.4 -4.2)
			(stroke
				(width 0.15)
				(type solid)
			)
			(layer "F.SilkS")
		)
		(fp_line
			(start -2.41 2.2)
			(end 4.7 2.2)
			(stroke
				(width 0.15)
				(type solid)
			)
			(layer "F.SilkS")
		)
		(fp_line
			(start 14.51 2.34)
			(end 14.51 -4.34)
			(stroke
				(width 0.05)
				(type solid)
			)
			(layer "F.CrtYd")
		)
		(fp_line
			(start -2.51 2.34)
			(end 14.51 2.34)
			(stroke
				(width 0.05)
				(type solid)
			)
			(layer "F.CrtYd")
		)
		(fp_line
			(start -2.51 2.34)
			(end -2.51 -4.34)
			(stroke
				(width 0.05)
				(type solid)
			)
			(layer "F.CrtYd")
		)
		(fp_line
			(start -2.51 -4.34)
			(end 14.51 -4.34)
			(stroke
				(width 0.05)
				(type solid)
			)
			(layer "F.CrtYd")
		)
		(fp_line
			(start 14.356 2.15)
			(end -2.293 2.15)
			(stroke
				(width 0.15)
				(type solid)
			)
			(layer "F.Fab")
		)
		(fp_line
			(start 14.356 1.898)
			(end 14.356 -4.15)
			(stroke
				(width 0.15)
				(type solid)
			)
			(layer "F.Fab")
		)
		(fp_line
			(start 14.356 -4.15)
			(end -2.32 -4.15)
			(stroke
				(width 0.15)
				(type solid)
			)
			(layer "F.Fab")
		)
		(fp_line
			(start -2.33 2.15)
			(end -2.33 -4.13)
			(stroke
				(width 0.15)
				(type solid)
			)
			(layer "F.Fab")
		)
		(pad "1" thru_hole rect
			(at 0 0)
			(size 1.6 1.6)
			(drill 0.9)
			(layers "*.Cu" "*.Mask")
			(remove_unused_layers no)
			(net 1 "GND")
			(pintype "passive")
		)
		(pad "2" thru_hole circle
			(at 0 -2)
			(size 1.6 1.6)
			(drill 0.9)
			(layers "*.Cu" "*.Mask")
			(remove_unused_layers no)
			(net 2 "VCC3V3")
			(pintype "passive")
		)
		(pad "3" thru_hole circle
			(at 2 0)
			(size 1.6 1.6)
			(drill 0.9)
			(layers "*.Cu" "*.Mask")
			(remove_unused_layers no)
			(net 1 "GND")
			(pintype "passive")
		)
		(pad "4" thru_hole circle
			(at 2 -2)
			(size 1.6 1.6)
			(drill 0.9)
			(layers "*.Cu" "*.Mask")
			(remove_unused_layers no)
			(net 16 "JTAG_TMS")
			(pintype "passive")
		)
		(pad "5" thru_hole circle
			(at 4 0)
			(size 1.6 1.6)
			(drill 0.9)
			(layers "*.Cu" "*.Mask")
			(remove_unused_layers no)
			(net 1 "GND")
			(pintype "passive")
		)
		(pad "6" thru_hole circle
			(at 4 -2)
			(size 1.6 1.6)
			(drill 0.9)
			(layers "*.Cu" "*.Mask")
			(remove_unused_layers no)
			(net 15 "JTAG_TCK")
			(pintype "passive")
		)
		(pad "7" thru_hole circle
			(at 6 0)
			(size 1.6 1.6)
			(drill 0.9)
			(layers "*.Cu" "*.Mask")
			(remove_unused_layers no)
			(net 1 "GND")
			(pintype "passive")
		)
		(pad "8" thru_hole circle
			(at 6 -2)
			(size 1.6 1.6)
			(drill 0.9)
			(layers "*.Cu" "*.Mask")
			(remove_unused_layers no)
			(net 14 "JTAG_TDO")
			(pintype "passive")
		)
		(pad "9" thru_hole circle
			(at 8 0)
			(size 1.6 1.6)
			(drill 0.9)
			(layers "*.Cu" "*.Mask")
			(remove_unused_layers no)
			(net 1 "GND")
			(pintype "passive")
		)
		(pad "10" thru_hole circle
			(at 8 -2)
			(size 1.6 1.6)
			(drill 0.9)
			(layers "*.Cu" "*.Mask")
			(remove_unused_layers no)
			(net 13 "JTAG_TDI")
			(pintype "passive")
		)
		(pad "11" thru_hole circle
			(at 10 0)
			(size 1.6 1.6)
			(drill 0.9)
			(layers "*.Cu" "*.Mask")
			(remove_unused_layers no)
			(net 1 "GND")
			(pintype "passive")
		)
		(pad "12" thru_hole circle
			(at 10 -2)
			(size 1.6 1.6)
			(drill 0.9)
			(layers "*.Cu" "*.Mask")
			(remove_unused_layers no)
			(net 242 "unconnected-(J6-Pad12)")
			(pintype "passive+no_connect")
		)
		(pad "13" thru_hole circle
			(at 12 0)
			(size 1.6 1.6)
			(drill 0.9)
			(layers "*.Cu" "*.Mask")
			(remove_unused_layers no)
			(net 1 "GND")
			(pintype "passive")
		)
		(pad "14" thru_hole circle
			(at 12 -2)
			(size 1.6 1.6)
			(drill 0.9)
			(layers "*.Cu" "*.Mask")
			(remove_unused_layers no)
			(net 241 "unconnected-(J6-Pad14)")
			(pintype "passive+no_connect")
		)
	)
	(footprint "antmicro-footprints:Conn_Plug_Molex_SlimStack_2x25_529910508"
		(layer "F.Cu")
		(at 74.071 156.39412)
		(property "Reference" "J8"
			(at 0 -4.4 0)
			(layer "F.SilkS")
			(effects
				(font
					(size 0.7 0.7)
					(thickness 0.15)
				)
				(justify left bottom)
			)
		)
		(property "Value" "Plug_Molex_SlimStack_2x25_529910508"
			(at 0 4.75 0)
			(layer "F.Fab")
			(effects
				(font
					(size 0.7 0.7)
					(thickness 0.15)
				)
				(justify left bottom)
			)
		)
		(property "Datasheet" "https://www.molex.com/en-us/products/part-detail/529910508?display=pdf"
			(at 0 0 0)
			(layer "F.Fab")
			(hide yes)
			(effects
				(font
					(size 1.27 1.27)
					(thickness 0.15)
				)
			)
		)
		(property "Description" "Mezzanine Connector, Receptacle, 0.5mm, 2Rows, 50Contacts, Surface Mount, Phosphor Bronze"
			(at 0 0 0)
			(layer "F.Fab")
			(hide yes)
			(effects
				(font
					(size 1.27 1.27)
					(thickness 0.15)
				)
			)
		)
		(property "Author" "Antmicro"
			(at 0 0 0)
			(layer "F.Fab")
			(hide yes)
			(effects
				(font
					(size 1 1)
					(thickness 0.15)
				)
			)
		)
		(property "License" "Apache-2.0"
			(at 0 0 0)
			(layer "F.Fab")
			(hide yes)
			(effects
				(font
					(size 1 1)
					(thickness 0.15)
				)
			)
		)
		(property "MPN" "529910508"
			(at 0 0 0)
			(layer "F.Fab")
			(hide yes)
			(effects
				(font
					(size 1 1)
					(thickness 0.15)
				)
			)
		)
		(property "Manufacturer" "Molex"
			(at 0 0 0)
			(layer "F.Fab")
			(hide yes)
			(effects
				(font
					(size 1 1)
					(thickness 0.15)
				)
			)
		)
		(property "Pitch " "0.5 mm"
			(at 0 0 0)
			(layer "F.Fab")
			(hide yes)
			(effects
				(font
					(size 1 1)
					(thickness 0.15)
				)
			)
		)
		(sheetname "/RoT/")
		(sheetfile "rot.kicad_sch")
		(attr smd)
		(fp_line
			(start -8.15 -2.7)
			(end -8.15 2.7)
			(stroke
				(width 0.15)
				(type solid)
			)
			(layer "F.SilkS")
		)
		(fp_line
			(start -6.7 -2.7)
			(end -8.15 -2.7)
			(stroke
				(width 0.15)
				(type solid)
			)
			(layer "F.SilkS")
		)
		(fp_line
			(start -6.7 2.7)
			(end -8.15 2.7)
			(stroke
				(width 0.15)
				(type solid)
			)
			(layer "F.SilkS")
		)
		(fp_line
			(start 6.7 -2.7)
			(end 8.15 -2.7)
			(stroke
				(width 0.15)
				(type solid)
			)
			(layer "F.SilkS")
		)
		(fp_line
			(start 6.7 2.7)
			(end 8.15 2.7)
			(stroke
				(width 0.15)
				(type solid)
			)
			(layer "F.SilkS")
		)
		(fp_line
			(start 8.15 2.7)
			(end 8.15 -2.7)
			(stroke
				(width 0.15)
				(type solid)
			)
			(layer "F.SilkS")
		)
		(fp_circle
			(center -6.45 -3.05)
			(end -6.45 -3.1)
			(stroke
				(width 0.15)
				(type solid)
			)
			(fill yes)
			(layer "F.SilkS")
		)
		(fp_line
			(start -8.657 -3.399)
			(end -8.657 3.401)
			(stroke
				(width 0.05)
				(type solid)
			)
			(layer "F.CrtYd")
		)
		(fp_line
			(start -8.657 3.401)
			(end 8.643 3.401)
			(stroke
				(width 0.05)
				(type solid)
			)
			(layer "F.CrtYd")
		)
		(fp_line
			(start 8.643 -3.399)
			(end -8.657 -3.399)
			(stroke
				(width 0.05)
				(type solid)
			)
			(layer "F.CrtYd")
		)
		(fp_line
			(start 8.643 3.401)
			(end 8.643 -3.399)
			(stroke
				(width 0.05)
				(type solid)
			)
			(layer "F.CrtYd")
		)
		(pad "1" smd rect
			(at -6.007 -2.041 180)
			(size 0.3 1.8)
			(layers "F.Cu" "F.Mask" "F.Paste")
			(net 2 "VCC3V3")
			(pintype "passive")
		)
		(pad "2" smd rect
			(at -6.007 2.058 180)
			(size 0.3 1.8)
			(layers "F.Cu" "F.Mask" "F.Paste")
			(net 1 "GND")
			(pintype "passive")
		)
		(pad "3" smd rect
			(at -5.507 -2.041 180)
			(size 0.3 1.8)
			(layers "F.Cu" "F.Mask" "F.Paste")
			(net 2 "VCC3V3")
			(pintype "passive")
		)
		(pad "4" smd rect
			(at -5.507 2.058 180)
			(size 0.3 1.8)
			(layers "F.Cu" "F.Mask" "F.Paste")
			(net 1 "GND")
			(pintype "passive")
		)
		(pad "5" smd rect
			(at -5.006 -2.05 180)
			(size 0.3 1.8)
			(layers "F.Cu" "F.Mask" "F.Paste")
			(net 566 "ROT_GPIO1")
			(pintype "passive")
		)
		(pad "6" smd rect
			(at -5.006 2.058 180)
			(size 0.3 1.8)
			(layers "F.Cu" "F.Mask" "F.Paste")
			(net 565 "ROT_GPIO2")
			(pintype "passive")
		)
		(pad "7" smd rect
			(at -4.506 -2.041 180)
			(size 0.3 1.8)
			(layers "F.Cu" "F.Mask" "F.Paste")
			(net 96 "QSPI0_CS1_N")
			(pintype "passive")
		)
		(pad "8" smd rect
			(at -4.506 2.058 180)
			(size 0.3 1.8)
			(layers "F.Cu" "F.Mask" "F.Paste")
			(net 133 "QSPIA1_D2")
			(pintype "passive")
		)
		(pad "9" smd rect
			(at -4.007 -2.041 180)
			(size 0.3 1.8)
			(layers "F.Cu" "F.Mask" "F.Paste")
			(net 138 "QSPIA2_D2")
			(pintype "passive")
		)
		(pad "10" smd rect
			(at -4.007 2.058 180)
			(size 0.3 1.8)
			(layers "F.Cu" "F.Mask" "F.Paste")
			(net 132 "QSPIA1_D1")
			(pintype "passive")
		)
		(pad "11" smd rect
			(at -3.507 -2.041 180)
			(size 0.3 1.8)
			(layers "F.Cu" "F.Mask" "F.Paste")
			(net 137 "QSPIA2_D1")
			(pintype "passive")
		)
		(pad "12" smd rect
			(at -3.507 2.058 180)
			(size 0.3 1.8)
			(layers "F.Cu" "F.Mask" "F.Paste")
			(net 135 "QSPIA1_CS_N")
			(pintype "passive")
		)
		(pad "13" smd rect
			(at -3.007 -2.041 180)
			(size 0.3 1.8)
			(layers "F.Cu" "F.Mask" "F.Paste")
			(net 140 "QSPIA2_CS_N")
			(pintype "passive")
		)
		(pad "14" smd rect
			(at -3.007 2.058 180)
			(size 0.3 1.8)
			(layers "F.Cu" "F.Mask" "F.Paste")
			(net 134 "QSPIA1_D3")
			(pintype "passive")
		)
		(pad "15" smd rect
			(at -2.507 -2.041 180)
			(size 0.3 1.8)
			(layers "F.Cu" "F.Mask" "F.Paste")
			(net 139 "QSPIA2_D3")
			(pintype "passive")
		)
		(pad "16" smd rect
			(at -2.507 2.058 180)
			(size 0.3 1.8)
			(layers "F.Cu" "F.Mask" "F.Paste")
			(net 131 "QSPIA1_D0")
			(pintype "passive")
		)
		(pad "17" smd rect
			(at -2.005 -2.041 180)
			(size 0.3 1.8)
			(layers "F.Cu" "F.Mask" "F.Paste")
			(net 130 "QSPIA_CLK")
			(pintype "passive")
		)
		(pad "18" smd rect
			(at -2.005 2.058 180)
			(size 0.3 1.8)
			(layers "F.Cu" "F.Mask" "F.Paste")
			(net 70 "QSPI0_CLK")
			(pintype "passive")
		)
		(pad "19" smd rect
			(at -1.505 -2.041 180)
			(size 0.3 1.8)
			(layers "F.Cu" "F.Mask" "F.Paste")
			(net 136 "QSPIA2_D0")
			(pintype "passive")
		)
		(pad "20" smd rect
			(at -1.505 2.058 180)
			(size 0.3 1.8)
			(layers "F.Cu" "F.Mask" "F.Paste")
			(net 71 "QSPI0_CS0_N")
			(pintype "passive")
		)
		(pad "21" smd rect
			(at -1.005 -2.041 180)
			(size 0.3 1.8)
			(layers "F.Cu" "F.Mask" "F.Paste")
			(net 122 "QSPIB1_D2")
			(pintype "passive")
		)
		(pad "22" smd rect
			(at -1.005 2.058 180)
			(size 0.3 1.8)
			(layers "F.Cu" "F.Mask" "F.Paste")
			(net 72 "QSPI0_D0")
			(pintype "passive")
		)
		(pad "23" smd rect
			(at -0.505 -2.041 180)
			(size 0.3 1.8)
			(layers "F.Cu" "F.Mask" "F.Paste")
			(net 121 "QSPIB1_D1")
			(pintype "passive")
		)
		(pad "24" smd rect
			(at -0.505 2.058 180)
			(size 0.3 1.8)
			(layers "F.Cu" "F.Mask" "F.Paste")
			(net 73 "QSPI0_D1")
			(pintype "passive")
		)
		(pad "25" smd rect
			(at -0.005 -2.041 180)
			(size 0.3 1.8)
			(layers "F.Cu" "F.Mask" "F.Paste")
			(net 124 "QSPIB1_CS_N")
			(pintype "passive")
		)
		(pad "26" smd rect
			(at -0.005 2.058 180)
			(size 0.3 1.8)
			(layers "F.Cu" "F.Mask" "F.Paste")
			(net 74 "QSPI0_D2")
			(pintype "passive")
		)
		(pad "27" smd rect
			(at 0.493 -2.041 180)
			(size 0.3 1.8)
			(layers "F.Cu" "F.Mask" "F.Paste")
			(net 123 "QSPIB1_D3")
			(pintype "passive")
		)
		(pad "28" smd rect
			(at 0.493 2.058 180)
			(size 0.3 1.8)
			(layers "F.Cu" "F.Mask" "F.Paste")
			(net 75 "QSPI0_D3")
			(pintype "passive")
		)
		(pad "29" smd rect
			(at 0.994 -2.041 180)
			(size 0.3 1.8)
			(layers "F.Cu" "F.Mask" "F.Paste")
			(net 120 "QSPIB1_D0")
			(pintype "passive")
		)
		(pad "30" smd rect
			(at 0.994 2.058 180)
			(size 0.3 1.8)
			(layers "F.Cu" "F.Mask" "F.Paste")
			(net 320 "ROT_QSPI_SCK")
			(pintype "passive")
		)
		(pad "31" smd rect
			(at 1.494 -2.041 180)
			(size 0.3 1.8)
			(layers "F.Cu" "F.Mask" "F.Paste")
			(net 127 "QSPIB2_D2")
			(pintype "passive")
		)
		(pad "32" smd rect
			(at 1.494 2.058 180)
			(size 0.3 1.8)
			(layers "F.Cu" "F.Mask" "F.Paste")
			(net 333 "ROT_QSPI_DQ3")
			(pintype "passive")
		)
		(pad "33" smd rect
			(at 1.993 -2.041 180)
			(size 0.3 1.8)
			(layers "F.Cu" "F.Mask" "F.Paste")
			(net 126 "QSPIB2_D1")
			(pintype "passive")
		)
		(pad "34" smd rect
			(at 1.993 2.058 180)
			(size 0.3 1.8)
			(layers "F.Cu" "F.Mask" "F.Paste")
			(net 332 "ROT_QSPI_DQ2")
			(pintype "passive")
		)
		(pad "35" smd rect
			(at 2.493 -2.041 180)
			(size 0.3 1.8)
			(layers "F.Cu" "F.Mask" "F.Paste")
			(net 129 "QSPIB2_CS_N")
			(pintype "passive")
		)
		(pad "36" smd rect
			(at 2.493 2.058 180)
			(size 0.3 1.8)
			(layers "F.Cu" "F.Mask" "F.Paste")
			(net 336 "ROT_QSPI_DQ1")
			(pintype "passive")
		)
		(pad "37" smd rect
			(at 2.993 -2.041 180)
			(size 0.3 1.8)
			(layers "F.Cu" "F.Mask" "F.Paste")
			(net 128 "QSPIB2_D3")
			(pintype "passive")
		)
		(pad "38" smd rect
			(at 2.993 2.058 180)
			(size 0.3 1.8)
			(layers "F.Cu" "F.Mask" "F.Paste")
			(net 335 "ROT_QSPI_DQ0")
			(pintype "passive")
		)
		(pad "39" smd rect
			(at 3.493 -2.041 180)
			(size 0.3 1.8)
			(layers "F.Cu" "F.Mask" "F.Paste")
			(net 119 "QSPIB_CLK")
			(pintype "passive")
		)
		(pad "40" smd rect
			(at 3.493 2.058 180)
			(size 0.3 1.8)
			(layers "F.Cu" "F.Mask" "F.Paste")
			(net 221 "PROGRAM")
			(pintype "passive")
		)
		(pad "41" smd rect
			(at 3.994 -2.041 180)
			(size 0.3 1.8)
			(layers "F.Cu" "F.Mask" "F.Paste")
			(net 125 "QSPIB2_D0")
			(pintype "passive")
		)
		(pad "42" smd rect
			(at 3.994 2.058 180)
			(size 0.3 1.8)
			(layers "F.Cu" "F.Mask" "F.Paste")
			(net 222 "INIT")
			(pintype "passive")
		)
		(pad "43" smd rect
			(at 4.494 -2.041 180)
			(size 0.3 1.8)
			(layers "F.Cu" "F.Mask" "F.Paste")
			(net 350 "ROT_QSPI_CS_B")
			(pintype "passive")
		)
		(pad "44" smd rect
			(at 4.494 2.058 180)
			(size 0.3 1.8)
			(layers "F.Cu" "F.Mask" "F.Paste")
			(net 301 "ROT_RDY\\ROT_GPIO0")
			(pintype "passive")
		)
		(pad "45" smd rect
			(at 4.994 -2.041 180)
			(size 0.3 1.8)
			(layers "F.Cu" "F.Mask" "F.Paste")
			(net 561 "ROT_SS")
			(pintype "passive")
		)
		(pad "46" smd rect
			(at 4.994 2.058 180)
			(size 0.3 1.8)
			(layers "F.Cu" "F.Mask" "F.Paste")
			(net 562 "ROT_TX")
			(pintype "passive")
		)
		(pad "47" smd rect
			(at 5.494 -2.041 180)
			(size 0.3 1.8)
			(layers "F.Cu" "F.Mask" "F.Paste")
			(net 559 "ROT_MISO")
			(pintype "passive")
		)
		(pad "48" smd rect
			(at 5.494 2.058 180)
			(size 0.3 1.8)
			(layers "F.Cu" "F.Mask" "F.Paste")
			(net 563 "ROT_RX")
			(pintype "passive")
		)
		(pad "49" smd rect
			(at 5.994 -2.041 180)
			(size 0.3 1.8)
			(layers "F.Cu" "F.Mask" "F.Paste")
			(net 560 "ROT_MOSI")
			(pintype "passive")
		)
		(pad "50" smd rect
			(at 5.994 2.058 180)
			(size 0.3 1.8)
			(layers "F.Cu" "F.Mask" "F.Paste")
			(net 564 "ROT_SCLK")
			(pintype "passive")
		)
	)
	(footprint "antmicro-footprints:C_0603_1608Metric"
		(layer "F.Cu")
		(at 84.59 66.74 180)
		(descr "Capacitor SMD 0603")
		(tags "capacitor 0603")
		(property "Reference" "C67"
			(at -7.31 -4.86 0)
			(layer "F.SilkS")
			(effects
				(font
					(size 0.7 0.7)
					(thickness 0.15)
				)
				(justify right bottom)
			)
		)
		(property "Value" "C_2u2_0603_25V"
			(at 0 1.6 0)
			(layer "F.Fab")
			(effects
				(font
					(size 0.7 0.7)
					(thickness 0.15)
				)
				(justify right bottom)
			)
		)
		(property "Datasheet" "https://www.murata.com/products/productdetail?partno=GRM188R61E225KA12%23"
			(at 0 0 180)
			(layer "F.Fab")
			(hide yes)
			(effects
				(font
					(size 1.27 1.27)
					(thickness 0.15)
				)
			)
		)
		(property "Description" "SMD Multilayer Ceramic Capacitor, 2.2 µF, 25 V, 0603 [1608 Metric], ± 10%, X5R, GRM Series"
			(at 0 0 180)
			(layer "F.Fab")
			(hide yes)
			(effects
				(font
					(size 1.27 1.27)
					(thickness 0.15)
				)
			)
		)
		(property "Author" "Antmicro"
			(at 169.18 133.48 0)
			(layer "F.Fab")
			(hide yes)
			(effects
				(font
					(size 1 1)
					(thickness 0.15)
				)
			)
		)
		(property "Dielectric" ""
			(at 169.18 133.48 0)
			(layer "F.Fab")
			(hide yes)
			(effects
				(font
					(size 1 1)
					(thickness 0.15)
				)
			)
		)
		(property "License" "Apache-2.0"
			(at 169.18 133.48 0)
			(layer "F.Fab")
			(hide yes)
			(effects
				(font
					(size 1 1)
					(thickness 0.15)
				)
			)
		)
		(property "MPN" "GRM188R61E225KA12D"
			(at 169.18 133.48 0)
			(layer "F.Fab")
			(hide yes)
			(effects
				(font
					(size 1 1)
					(thickness 0.15)
				)
			)
		)
		(property "Manufacturer" "Murata"
			(at 169.18 133.48 0)
			(layer "F.Fab")
			(hide yes)
			(effects
				(font
					(size 1 1)
					(thickness 0.15)
				)
			)
		)
		(property "Public" "False"
			(at 169.18 133.48 0)
			(layer "F.Fab")
			(hide yes)
			(effects
				(font
					(size 1 1)
					(thickness 0.15)
				)
			)
		)
		(property "Val" "2u2"
			(at 169.18 133.48 0)
			(layer "F.Fab")
			(hide yes)
			(effects
				(font
					(size 1 1)
					(thickness 0.15)
				)
			)
		)
		(property "Voltage" ""
			(at 169.18 133.48 0)
			(layer "F.Fab")
			(hide yes)
			(effects
				(font
					(size 1 1)
					(thickness 0.15)
				)
			)
		)
		(sheetname "/Power supply/")
		(sheetfile "power-supply.kicad_sch")
		(attr smd)
		(fp_line
			(start -0.15 0.4)
			(end 0.15 0.4)
			(stroke
				(width 0.15)
				(type solid)
			)
			(layer "F.SilkS")
		)
		(fp_line
			(start -0.15 -0.4)
			(end 0.15 -0.4)
			(stroke
				(width 0.15)
				(type solid)
			)
			(layer "F.SilkS")
		)
		(fp_rect
			(start -1.25 -0.65)
			(end 1.25 0.65)
			(stroke
				(width 0.05)
				(type solid)
			)
			(fill no)
			(layer "F.CrtYd")
		)
		(fp_rect
			(start -0.8 -0.4)
			(end 0.8 0.4)
			(stroke
				(width 0.15)
				(type solid)
			)
			(fill no)
			(layer "F.Fab")
		)
		(pad "1" smd roundrect
			(at -0.7 0 180)
			(size 0.8 1)
			(layers "F.Cu" "F.Mask" "F.Paste")
			(roundrect_rratio 0.2)
			(net 1 "GND")
			(pintype "passive")
		)
		(pad "2" smd roundrect
			(at 0.7 0 180)
			(size 0.8 1)
			(layers "F.Cu" "F.Mask" "F.Paste")
			(roundrect_rratio 0.2)
			(net 104 "/Power supply/VCC12V")
			(pintype "passive")
		)
	)
	(footprint "antmicro-footprints:C_0603_1608Metric"
		(layer "F.Cu")
		(at 84.59 65.265 180)
		(descr "Capacitor SMD 0603")
		(tags "capacitor 0603")
		(property "Reference" "C66"
			(at -7.31 -5.335 0)
			(layer "F.SilkS")
			(effects
				(font
					(size 0.7 0.7)
					(thickness 0.15)
				)
				(justify right bottom)
			)
		)
		(property "Value" "C_2u2_0603_25V"
			(at 0 1.6 0)
			(layer "F.Fab")
			(effects
				(font
					(size 0.7 0.7)
					(thickness 0.15)
				)
				(justify right bottom)
			)
		)
		(property "Datasheet" "https://www.murata.com/products/productdetail?partno=GRM188R61E225KA12%23"
			(at 0 0 180)
			(layer "F.Fab")
			(hide yes)
			(effects
				(font
					(size 1.27 1.27)
					(thickness 0.15)
				)
			)
		)
		(property "Description" "SMD Multilayer Ceramic Capacitor, 2.2 µF, 25 V, 0603 [1608 Metric], ± 10%, X5R, GRM Series"
			(at 0 0 180)
			(layer "F.Fab")
			(hide yes)
			(effects
				(font
					(size 1.27 1.27)
					(thickness 0.15)
				)
			)
		)
		(property "Author" "Antmicro"
			(at 169.18 130.53 0)
			(layer "F.Fab")
			(hide yes)
			(effects
				(font
					(size 1 1)
					(thickness 0.15)
				)
			)
		)
		(property "Dielectric" ""
			(at 169.18 130.53 0)
			(layer "F.Fab")
			(hide yes)
			(effects
				(font
					(size 1 1)
					(thickness 0.15)
				)
			)
		)
		(property "License" "Apache-2.0"
			(at 169.18 130.53 0)
			(layer "F.Fab")
			(hide yes)
			(effects
				(font
					(size 1 1)
					(thickness 0.15)
				)
			)
		)
		(property "MPN" "GRM188R61E225KA12D"
			(at 169.18 130.53 0)
			(layer "F.Fab")
			(hide yes)
			(effects
				(font
					(size 1 1)
					(thickness 0.15)
				)
			)
		)
		(property "Manufacturer" "Murata"
			(at 169.18 130.53 0)
			(layer "F.Fab")
			(hide yes)
			(effects
				(font
					(size 1 1)
					(thickness 0.15)
				)
			)
		)
		(property "Public" "False"
			(at 169.18 130.53 0)
			(layer "F.Fab")
			(hide yes)
			(effects
				(font
					(size 1 1)
					(thickness 0.15)
				)
			)
		)
		(property "Val" "2u2"
			(at 169.18 130.53 0)
			(layer "F.Fab")
			(hide yes)
			(effects
				(font
					(size 1 1)
					(thickness 0.15)
				)
			)
		)
		(property "Voltage" ""
			(at 169.18 130.53 0)
			(layer "F.Fab")
			(hide yes)
			(effects
				(font
					(size 1 1)
					(thickness 0.15)
				)
			)
		)
		(sheetname "/Power supply/")
		(sheetfile "power-supply.kicad_sch")
		(attr smd)
		(fp_line
			(start -0.15 0.4)
			(end 0.15 0.4)
			(stroke
				(width 0.15)
				(type solid)
			)
			(layer "F.SilkS")
		)
		(fp_line
			(start -0.15 -0.4)
			(end 0.15 -0.4)
			(stroke
				(width 0.15)
				(type solid)
			)
			(layer "F.SilkS")
		)
		(fp_rect
			(start -1.25 -0.65)
			(end 1.25 0.65)
			(stroke
				(width 0.05)
				(type solid)
			)
			(fill no)
			(layer "F.CrtYd")
		)
		(fp_rect
			(start -0.8 -0.4)
			(end 0.8 0.4)
			(stroke
				(width 0.15)
				(type solid)
			)
			(fill no)
			(layer "F.Fab")
		)
		(pad "1" smd roundrect
			(at -0.7 0 180)
			(size 0.8 1)
			(layers "F.Cu" "F.Mask" "F.Paste")
			(roundrect_rratio 0.2)
			(net 1 "GND")
			(pintype "passive")
		)
		(pad "2" smd roundrect
			(at 0.7 0 180)
			(size 0.8 1)
			(layers "F.Cu" "F.Mask" "F.Paste")
			(roundrect_rratio 0.2)
			(net 104 "/Power supply/VCC12V")
			(pintype "passive")
		)
	)
	(footprint "antmicro-footprints:C_0603_1608Metric"
		(layer "F.Cu")
		(at 84.59 63.79 180)
		(descr "Capacitor SMD 0603")
		(tags "capacitor 0603")
		(property "Reference" "C65"
			(at -7.31 -5.81 0)
			(layer "F.SilkS")
			(effects
				(font
					(size 0.7 0.7)
					(thickness 0.15)
				)
				(justify right bottom)
			)
		)
		(property "Value" "C_2u2_0603_25V"
			(at 0 1.6 0)
			(layer "F.Fab")
			(effects
				(font
					(size 0.7 0.7)
					(thickness 0.15)
				)
				(justify right bottom)
			)
		)
		(property "Datasheet" "https://www.murata.com/products/productdetail?partno=GRM188R61E225KA12%23"
			(at 0 0 180)
			(layer "F.Fab")
			(hide yes)
			(effects
				(font
					(size 1.27 1.27)
					(thickness 0.15)
				)
			)
		)
		(property "Description" "SMD Multilayer Ceramic Capacitor, 2.2 µF, 25 V, 0603 [1608 Metric], ± 10%, X5R, GRM Series"
			(at 0 0 180)
			(layer "F.Fab")
			(hide yes)
			(effects
				(font
					(size 1.27 1.27)
					(thickness 0.15)
				)
			)
		)
		(property "Author" "Antmicro"
			(at 169.18 127.58 0)
			(layer "F.Fab")
			(hide yes)
			(effects
				(font
					(size 1 1)
					(thickness 0.15)
				)
			)
		)
		(property "Dielectric" ""
			(at 169.18 127.58 0)
			(layer "F.Fab")
			(hide yes)
			(effects
				(font
					(size 1 1)
					(thickness 0.15)
				)
			)
		)
		(property "License" "Apache-2.0"
			(at 169.18 127.58 0)
			(layer "F.Fab")
			(hide yes)
			(effects
				(font
					(size 1 1)
					(thickness 0.15)
				)
			)
		)
		(property "MPN" "GRM188R61E225KA12D"
			(at 169.18 127.58 0)
			(layer "F.Fab")
			(hide yes)
			(effects
				(font
					(size 1 1)
					(thickness 0.15)
				)
			)
		)
		(property "Manufacturer" "Murata"
			(at 169.18 127.58 0)
			(layer "F.Fab")
			(hide yes)
			(effects
				(font
					(size 1 1)
					(thickness 0.15)
				)
			)
		)
		(property "Public" "False"
			(at 169.18 127.58 0)
			(layer "F.Fab")
			(hide yes)
			(effects
				(font
					(size 1 1)
					(thickness 0.15)
				)
			)
		)
		(property "Val" "2u2"
			(at 169.18 127.58 0)
			(layer "F.Fab")
			(hide yes)
			(effects
				(font
					(size 1 1)
					(thickness 0.15)
				)
			)
		)
		(property "Voltage" ""
			(at 169.18 127.58 0)
			(layer "F.Fab")
			(hide yes)
			(effects
				(font
					(size 1 1)
					(thickness 0.15)
				)
			)
		)
		(sheetname "/Power supply/")
		(sheetfile "power-supply.kicad_sch")
		(attr smd)
		(fp_line
			(start -0.15 0.4)
			(end 0.15 0.4)
			(stroke
				(width 0.15)
				(type solid)
			)
			(layer "F.SilkS")
		)
		(fp_line
			(start -0.15 -0.4)
			(end 0.15 -0.4)
			(stroke
				(width 0.15)
				(type solid)
			)
			(layer "F.SilkS")
		)
		(fp_rect
			(start -1.25 -0.65)
			(end 1.25 0.65)
			(stroke
				(width 0.05)
				(type solid)
			)
			(fill no)
			(layer "F.CrtYd")
		)
		(fp_rect
			(start -0.8 -0.4)
			(end 0.8 0.4)
			(stroke
				(width 0.15)
				(type solid)
			)
			(fill no)
			(layer "F.Fab")
		)
		(pad "1" smd roundrect
			(at -0.7 0 180)
			(size 0.8 1)
			(layers "F.Cu" "F.Mask" "F.Paste")
			(roundrect_rratio 0.2)
			(net 1 "GND")
			(pintype "passive")
		)
		(pad "2" smd roundrect
			(at 0.7 0 180)
			(size 0.8 1)
			(layers "F.Cu" "F.Mask" "F.Paste")
			(roundrect_rratio 0.2)
			(net 104 "/Power supply/VCC12V")
			(pintype "passive")
		)
	)
	(footprint "antmicro-footprints:C_0603_1608Metric"
		(layer "F.Cu")
		(at 85.265 68.765 -90)
		(descr "Capacitor SMD 0603")
		(tags "capacitor 0603")
		(property "Reference" "C14"
			(at -1.115 0.795 90)
			(layer "F.SilkS")
			(effects
				(font
					(size 0.7 0.7)
					(thickness 0.15)
				)
				(justify right bottom)
			)
		)
		(property "Value" "C_10u_25V_0603"
			(at 0 1.6 90)
			(layer "F.Fab")
			(effects
				(font
					(size 0.7 0.7)
					(thickness 0.15)
				)
				(justify right bottom)
			)
		)
		(property "Datasheet" "https://product.tdk.com/en/search/capacitor/ceramic/mlcc/info?part_no=C1608X5R1E106M080AC"
			(at 0 0 270)
			(layer "F.Fab")
			(hide yes)
			(effects
				(font
					(size 1.27 1.27)
					(thickness 0.15)
				)
			)
		)
		(property "Description" "SMD Multilayer Ceramic Capacitor, 10 µF, 25 V, 0603 [1608 Metric], ± 20%, X5R, C"
			(at 0 0 270)
			(layer "F.Fab")
			(hide yes)
			(effects
				(font
					(size 1.27 1.27)
					(thickness 0.15)
				)
			)
		)
		(property "Author" "Antmicro"
			(at 16.5 154.03 0)
			(layer "F.Fab")
			(hide yes)
			(effects
				(font
					(size 1 1)
					(thickness 0.15)
				)
			)
		)
		(property "Dielectric" ""
			(at 16.5 154.03 0)
			(layer "F.Fab")
			(hide yes)
			(effects
				(font
					(size 1 1)
					(thickness 0.15)
				)
			)
		)
		(property "License" "Apache-2.0"
			(at 16.5 154.03 0)
			(layer "F.Fab")
			(hide yes)
			(effects
				(font
					(size 1 1)
					(thickness 0.15)
				)
			)
		)
		(property "MPN" "C1608X5R1E106M080AC"
			(at 16.5 154.03 0)
			(layer "F.Fab")
			(hide yes)
			(effects
				(font
					(size 1 1)
					(thickness 0.15)
				)
			)
		)
		(property "Manufacturer" "TDK"
			(at 16.5 154.03 0)
			(layer "F.Fab")
			(hide yes)
			(effects
				(font
					(size 1 1)
					(thickness 0.15)
				)
			)
		)
		(property "Val" "10u"
			(at 16.5 154.03 0)
			(layer "F.Fab")
			(hide yes)
			(effects
				(font
					(size 1 1)
					(thickness 0.15)
				)
			)
		)
		(property "Voltage" "25V"
			(at 16.5 154.03 0)
			(layer "F.Fab")
			(hide yes)
			(effects
				(font
					(size 1 1)
					(thickness 0.15)
				)
			)
		)
		(sheetname "/Power supply/")
		(sheetfile "power-supply.kicad_sch")
		(attr smd)
		(fp_line
			(start -0.15 0.4)
			(end 0.15 0.4)
			(stroke
				(width 0.15)
				(type solid)
			)
			(layer "F.SilkS")
		)
		(fp_line
			(start -0.15 -0.4)
			(end 0.15 -0.4)
			(stroke
				(width 0.15)
				(type solid)
			)
			(layer "F.SilkS")
		)
		(fp_rect
			(start -1.25 -0.65)
			(end 1.25 0.65)
			(stroke
				(width 0.05)
				(type solid)
			)
			(fill no)
			(layer "F.CrtYd")
		)
		(fp_rect
			(start -0.8 -0.4)
			(end 0.8 0.4)
			(stroke
				(width 0.15)
				(type solid)
			)
			(fill no)
			(layer "F.Fab")
		)
		(pad "1" smd roundrect
			(at -0.7 0 270)
			(size 0.8 1)
			(layers "F.Cu" "F.Mask" "F.Paste")
			(roundrect_rratio 0.2)
			(net 1 "GND")
			(pintype "passive")
		)
		(pad "2" smd roundrect
			(at 0.7 0 270)
			(size 0.8 1)
			(layers "F.Cu" "F.Mask" "F.Paste")
			(roundrect_rratio 0.2)
			(net 104 "/Power supply/VCC12V")
			(pintype "passive")
		)
	)
	(footprint "antmicro-footprints:C_0603_1608Metric"
		(layer "F.Cu")
		(at 88.215 68.765 -90)
		(descr "Capacitor SMD 0603")
		(tags "capacitor 0603")
		(property "Reference" "C15"
			(at -3.365 -0.185 90)
			(layer "F.SilkS")
			(effects
				(font
					(size 0.7 0.7)
					(thickness 0.15)
				)
				(justify right bottom)
			)
		)
		(property "Value" "C_10u_25V_0603"
			(at 0 1.6 90)
			(layer "F.Fab")
			(effects
				(font
					(size 0.7 0.7)
					(thickness 0.15)
				)
				(justify right bottom)
			)
		)
		(property "Datasheet" "https://product.tdk.com/en/search/capacitor/ceramic/mlcc/info?part_no=C1608X5R1E106M080AC"
			(at 0 0 270)
			(layer "F.Fab")
			(hide yes)
			(effects
				(font
					(size 1.27 1.27)
					(thickness 0.15)
				)
			)
		)
		(property "Description" "SMD Multilayer Ceramic Capacitor, 10 µF, 25 V, 0603 [1608 Metric], ± 20%, X5R, C"
			(at 0 0 270)
			(layer "F.Fab")
			(hide yes)
			(effects
				(font
					(size 1.27 1.27)
					(thickness 0.15)
				)
			)
		)
		(property "Author" "Antmicro"
			(at 19.45 156.98 0)
			(layer "F.Fab")
			(hide yes)
			(effects
				(font
					(size 1 1)
					(thickness 0.15)
				)
			)
		)
		(property "Dielectric" ""
			(at 19.45 156.98 0)
			(layer "F.Fab")
			(hide yes)
			(effects
				(font
					(size 1 1)
					(thickness 0.15)
				)
			)
		)
		(property "License" "Apache-2.0"
			(at 19.45 156.98 0)
			(layer "F.Fab")
			(hide yes)
			(effects
				(font
					(size 1 1)
					(thickness 0.15)
				)
			)
		)
		(property "MPN" "C1608X5R1E106M080AC"
			(at 19.45 156.98 0)
			(layer "F.Fab")
			(hide yes)
			(effects
				(font
					(size 1 1)
					(thickness 0.15)
				)
			)
		)
		(property "Manufacturer" "TDK"
			(at 19.45 156.98 0)
			(layer "F.Fab")
			(hide yes)
			(effects
				(font
					(size 1 1)
					(thickness 0.15)
				)
			)
		)
		(property "Val" "10u"
			(at 19.45 156.98 0)
			(layer "F.Fab")
			(hide yes)
			(effects
				(font
					(size 1 1)
					(thickness 0.15)
				)
			)
		)
		(property "Voltage" "25V"
			(at 19.45 156.98 0)
			(layer "F.Fab")
			(hide yes)
			(effects
				(font
					(size 1 1)
					(thickness 0.15)
				)
			)
		)
		(sheetname "/Power supply/")
		(sheetfile "power-supply.kicad_sch")
		(attr smd)
		(fp_line
			(start -0.15 0.4)
			(end 0.15 0.4)
			(stroke
				(width 0.15)
				(type solid)
			)
			(layer "F.SilkS")
		)
		(fp_line
			(start -0.15 -0.4)
			(end 0.15 -0.4)
			(stroke
				(width 0.15)
				(type solid)
			)
			(layer "F.SilkS")
		)
		(fp_rect
			(start -1.25 -0.65)
			(end 1.25 0.65)
			(stroke
				(width 0.05)
				(type solid)
			)
			(fill no)
			(layer "F.CrtYd")
		)
		(fp_rect
			(start -0.8 -0.4)
			(end 0.8 0.4)
			(stroke
				(width 0.15)
				(type solid)
			)
			(fill no)
			(layer "F.Fab")
		)
		(pad "1" smd roundrect
			(at -0.7 0 270)
			(size 0.8 1)
			(layers "F.Cu" "F.Mask" "F.Paste")
			(roundrect_rratio 0.2)
			(net 1 "GND")
			(pintype "passive")
		)
		(pad "2" smd roundrect
			(at 0.7 0 270)
			(size 0.8 1)
			(layers "F.Cu" "F.Mask" "F.Paste")
			(roundrect_rratio 0.2)
			(net 104 "/Power supply/VCC12V")
			(pintype "passive")
		)
	)
	(footprint "antmicro-footprints:C_0603_1608Metric"
		(layer "F.Cu")
		(at 86.74 68.765 -90)
		(descr "Capacitor SMD 0603")
		(tags "capacitor 0603")
		(property "Reference" "C16"
			(at -3.355 -0.4735 90)
			(layer "F.SilkS")
			(effects
				(font
					(size 0.7 0.7)
					(thickness 0.15)
				)
				(justify right bottom)
			)
		)
		(property "Value" "C_10u_25V_0603"
			(at 0 1.6 90)
			(layer "F.Fab")
			(effects
				(font
					(size 0.7 0.7)
					(thickness 0.15)
				)
				(justify right bottom)
			)
		)
		(property "Datasheet" "https://product.tdk.com/en/search/capacitor/ceramic/mlcc/info?part_no=C1608X5R1E106M080AC"
			(at 0 0 270)
			(layer "F.Fab")
			(hide yes)
			(effects
				(font
					(size 1.27 1.27)
					(thickness 0.15)
				)
			)
		)
		(property "Description" "SMD Multilayer Ceramic Capacitor, 10 µF, 25 V, 0603 [1608 Metric], ± 20%, X5R, C"
			(at 0 0 270)
			(layer "F.Fab")
			(hide yes)
			(effects
				(font
					(size 1.27 1.27)
					(thickness 0.15)
				)
			)
		)
		(property "Author" "Antmicro"
			(at 17.975 155.505 0)
			(layer "F.Fab")
			(hide yes)
			(effects
				(font
					(size 1 1)
					(thickness 0.15)
				)
			)
		)
		(property "Dielectric" ""
			(at 17.975 155.505 0)
			(layer "F.Fab")
			(hide yes)
			(effects
				(font
					(size 1 1)
					(thickness 0.15)
				)
			)
		)
		(property "License" "Apache-2.0"
			(at 17.975 155.505 0)
			(layer "F.Fab")
			(hide yes)
			(effects
				(font
					(size 1 1)
					(thickness 0.15)
				)
			)
		)
		(property "MPN" "C1608X5R1E106M080AC"
			(at 17.975 155.505 0)
			(layer "F.Fab")
			(hide yes)
			(effects
				(font
					(size 1 1)
					(thickness 0.15)
				)
			)
		)
		(property "Manufacturer" "TDK"
			(at 17.975 155.505 0)
			(layer "F.Fab")
			(hide yes)
			(effects
				(font
					(size 1 1)
					(thickness 0.15)
				)
			)
		)
		(property "Val" "10u"
			(at 17.975 155.505 0)
			(layer "F.Fab")
			(hide yes)
			(effects
				(font
					(size 1 1)
					(thickness 0.15)
				)
			)
		)
		(property "Voltage" "25V"
			(at 17.975 155.505 0)
			(layer "F.Fab")
			(hide yes)
			(effects
				(font
					(size 1 1)
					(thickness 0.15)
				)
			)
		)
		(sheetname "/Power supply/")
		(sheetfile "power-supply.kicad_sch")
		(attr smd)
		(fp_line
			(start -0.15 0.4)
			(end 0.15 0.4)
			(stroke
				(width 0.15)
				(type solid)
			)
			(layer "F.SilkS")
		)
		(fp_line
			(start -0.15 -0.4)
			(end 0.15 -0.4)
			(stroke
				(width 0.15)
				(type solid)
			)
			(layer "F.SilkS")
		)
		(fp_rect
			(start -1.25 -0.65)
			(end 1.25 0.65)
			(stroke
				(width 0.05)
				(type solid)
			)
			(fill no)
			(layer "F.CrtYd")
		)
		(fp_rect
			(start -0.8 -0.4)
			(end 0.8 0.4)
			(stroke
				(width 0.15)
				(type solid)
			)
			(fill no)
			(layer "F.Fab")
		)
		(pad "1" smd roundrect
			(at -0.7 0 270)
			(size 0.8 1)
			(layers "F.Cu" "F.Mask" "F.Paste")
			(roundrect_rratio 0.2)
			(net 1 "GND")
			(pintype "passive")
		)
		(pad "2" smd roundrect
			(at 0.7 0 270)
			(size 0.8 1)
			(layers "F.Cu" "F.Mask" "F.Paste")
			(roundrect_rratio 0.2)
			(net 104 "/Power supply/VCC12V")
			(pintype "passive")
		)
	)
	(footprint "antmicro-footprints:Conn_Molex_Pico-Lock_1x2_504050-0291"
		(layer "F.Cu")
		(at 89.6 62.55 180)
		(property "Reference" "J5"
			(at 5.55 2.55 180)
			(layer "F.SilkS")
			(effects
				(font
					(size 0.7 0.7)
					(thickness 0.15)
				)
				(justify left bottom)
			)
		)
		(property "Value" "Molex_Pico-Lock_1x2_504050-0291"
			(at -0.749 4.35 180)
			(layer "F.Fab")
			(effects
				(font
					(size 0.7 0.7)
					(thickness 0.15)
				)
				(justify left bottom)
			)
		)
		(property "Datasheet" "https://www.molex.com/en-us/products/part-detail-pdf/5040500291?display=pdf"
			(at 0 0 180)
			(layer "F.Fab")
			(hide yes)
			(effects
				(font
					(size 1.27 1.27)
					(thickness 0.15)
				)
			)
		)
		(property "Description" "Connector Header Surface Mount, Right Angle 2 position 0.059\" (1.50mm)"
			(at 0 0 180)
			(layer "F.Fab")
			(hide yes)
			(effects
				(font
					(size 1.27 1.27)
					(thickness 0.15)
				)
			)
		)
		(property "Author" "Antmicro"
			(at 179.2 125.1 0)
			(layer "F.Fab")
			(hide yes)
			(effects
				(font
					(size 1 1)
					(thickness 0.15)
				)
			)
		)
		(property "License" "Apache-2.0"
			(at 179.2 125.1 0)
			(layer "F.Fab")
			(hide yes)
			(effects
				(font
					(size 1 1)
					(thickness 0.15)
				)
			)
		)
		(property "MPN" "504050-0291"
			(at 179.2 125.1 0)
			(layer "F.Fab")
			(hide yes)
			(effects
				(font
					(size 1 1)
					(thickness 0.15)
				)
			)
		)
		(property "Manufacturer" "Molex"
			(at 179.2 125.1 0)
			(layer "F.Fab")
			(hide yes)
			(effects
				(font
					(size 1 1)
					(thickness 0.15)
				)
			)
		)
		(sheetname "/Power supply/")
		(sheetfile "power-supply.kicad_sch")
		(attr smd)
		(fp_line
			(start 3.374 -2.86)
			(end 3.374 1.088)
			(stroke
				(width 0.15)
				(type solid)
			)
			(layer "F.SilkS")
		)
		(fp_line
			(start 1.649 1.289)
			(end 1.649 3.228)
			(stroke
				(width 0.15)
				(type solid)
			)
			(layer "F.SilkS")
		)
		(fp_line
			(start 1.649 1.289)
			(end -1.639 1.289)
			(stroke
				(width 0.15)
				(type solid)
			)
			(layer "F.SilkS")
		)
		(fp_line
			(start 1.399 -2.86)
			(end 3.374 -2.86)
			(stroke
				(width 0.15)
				(type solid)
			)
			(layer "F.SilkS")
		)
		(fp_line
			(start -1.639 3.239)
			(end -1.639 1.289)
			(stroke
				(width 0.15)
				(type solid)
			)
			(layer "F.SilkS")
		)
		(fp_line
			(start -3.374 1.088)
			(end -3.374 -2.86)
			(stroke
				(width 0.15)
				(type solid)
			)
			(layer "F.SilkS")
		)
		(fp_line
			(start -3.374 -2.86)
			(end -1.4 -2.86)
			(stroke
				(width 0.15)
				(type solid)
			)
			(layer "F.SilkS")
		)
		(fp_circle
			(center -1.249 -3.15)
			(end -1.199 -3.15)
			(stroke
				(width 0.15)
				(type solid)
			)
			(fill yes)
			(layer "F.SilkS")
		)
		(fp_line
			(start 4.231 3.47)
			(end -4.249 3.47)
			(stroke
				(width 0.05)
				(type solid)
			)
			(layer "F.CrtYd")
		)
		(fp_line
			(start 4.231 1.18)
			(end 4.231 3.47)
			(stroke
				(width 0.05)
				(type solid)
			)
			(layer "F.CrtYd")
		)
		(fp_line
			(start 3.621 1.18)
			(end 4.231 1.18)
			(stroke
				(width 0.05)
				(type solid)
			)
			(layer "F.CrtYd")
		)
		(fp_line
			(start 3.621 -3.61)
			(end 3.621 1.18)
			(stroke
				(width 0.05)
				(type solid)
			)
			(layer "F.CrtYd")
		)
		(fp_line
			(start -3.629 1.18)
			(end -3.629 -3.61)
			(stroke
				(width 0.05)
				(type solid)
			)
			(layer "F.CrtYd")
		)
		(fp_line
			(start -3.629 -3.61)
			(end 3.621 -3.61)
			(stroke
				(width 0.05)
				(type solid)
			)
			(layer "F.CrtYd")
		)
		(fp_line
			(start -4.249 3.47)
			(end -4.249 1.18)
			(stroke
				(width 0.05)
				(type solid)
			)
			(layer "F.CrtYd")
		)
		(fp_line
			(start -4.249 1.18)
			(end -3.629 1.18)
			(stroke
				(width 0.05)
				(type solid)
			)
			(layer "F.CrtYd")
		)
		(fp_line
			(start 3.374 -2.86)
			(end 3.374 3.239)
			(stroke
				(width 0.15)
				(type solid)
			)
			(layer "F.Fab")
		)
		(fp_line
			(start 1.75 3.239)
			(end 3.374 3.239)
			(stroke
				(width 0.15)
				(type solid)
			)
			(layer "F.Fab")
		)
		(fp_line
			(start 1.75 1.188)
			(end 1.75 3.239)
			(stroke
				(width 0.15)
				(type solid)
			)
			(layer "F.Fab")
		)
		(fp_line
			(start 1.75 1.188)
			(end -1.749 1.188)
			(stroke
				(width 0.15)
				(type solid)
			)
			(layer "F.Fab")
		)
		(fp_line
			(start -1.749 3.249)
			(end -1.749 1.188)
			(stroke
				(width 0.15)
				(type solid)
			)
			(layer "F.Fab")
		)
		(fp_line
			(start -3.374 3.239)
			(end -1.749 3.239)
			(stroke
				(width 0.15)
				(type solid)
			)
			(layer "F.Fab")
		)
		(fp_line
			(start -3.374 3.239)
			(end -3.374 -2.86)
			(stroke
				(width 0.15)
				(type solid)
			)
			(layer "F.Fab")
		)
		(fp_line
			(start -3.374 -2.86)
			(end 3.374 -2.86)
			(stroke
				(width 0.15)
				(type solid)
			)
			(layer "F.Fab")
		)
		(fp_text user "${REFERENCE}"
			(at -3.481 10.175 180)
			(layer "F.Fab")
			(effects
				(font
					(size 0.7 0.7)
					(thickness 0.15)
				)
				(justify left bottom)
			)
		)
		(fp_text user "Author: Antmicro"
			(at -3.481 11.374 180)
			(layer "F.Fab")
			(effects
				(font
					(size 0.7 0.7)
					(thickness 0.15)
				)
				(justify left bottom)
			)
		)
		(fp_text user "License: Apache-2.0"
			(at -3.481 12.573 180)
			(layer "F.Fab")
			(effects
				(font
					(size 0.7 0.7)
					(thickness 0.15)
				)
				(justify left bottom)
			)
		)
		(pad "1" smd roundrect
			(at -0.749 -2.85 180)
			(size 0.6 1)
			(layers "F.Cu" "F.Mask" "F.Paste")
			(roundrect_rratio 0.25)
			(net 104 "/Power supply/VCC12V")
			(pinfunction "1")
			(pintype "passive")
		)
		(pad "2" smd roundrect
			(at 0.75 -2.85 180)
			(size 0.6 1)
			(layers "F.Cu" "F.Mask" "F.Paste")
			(roundrect_rratio 0.25)
			(net 1 "GND")
			(pinfunction "2")
			(pintype "passive")
		)
		(pad "MP1" smd roundrect
			(at -3.354 2.338 180)
			(size 1.25 1.8)
			(layers "F.Cu" "F.Mask" "F.Paste")
			(roundrect_rratio 0.25)
			(net 1 "GND")
			(pinfunction "MP")
			(pintype "passive")
		)
		(pad "MP2" smd roundrect
			(at 3.356 2.338 180)
			(size 1.25 1.8)
			(layers "F.Cu" "F.Mask" "F.Paste")
			(roundrect_rratio 0.25)
			(net 1 "GND")
			(pinfunction "MP2")
			(pintype "passive")
		)
	)
	(footprint "antmicro-footprints:Conn_Molex_Pico-Lock_1x2_504050-0291"
		(layer "F.Cu")
		(at 143.2 141.7 90)
		(property "Reference" "J10"
			(at 3.75 -2.95 180)
			(layer "F.SilkS")
			(effects
				(font
					(size 0.7 0.7)
					(thickness 0.15)
				)
				(justify left bottom)
			)
		)
		(property "Value" "Molex_Pico-Lock_1x2_504050-0291"
			(at -0.749 4.35 90)
			(layer "F.Fab")
			(effects
				(font
					(size 0.7 0.7)
					(thickness 0.15)
				)
				(justify left bottom)
			)
		)
		(property "Datasheet" "https://www.molex.com/en-us/products/part-detail-pdf/5040500291?display=pdf"
			(at 0 0 90)
			(layer "F.Fab")
			(hide yes)
			(effects
				(font
					(size 1.27 1.27)
					(thickness 0.15)
				)
			)
		)
		(property "Description" "Connector Header Surface Mount, Right Angle 2 position 0.059\" (1.50mm)"
			(at 0 0 90)
			(layer "F.Fab")
			(hide yes)
			(effects
				(font
					(size 1.27 1.27)
					(thickness 0.15)
				)
			)
		)
		(property "Author" "Antmicro"
			(at 284.9 -1.5 0)
			(layer "F.Fab")
			(hide yes)
			(effects
				(font
					(size 1 1)
					(thickness 0.15)
				)
			)
		)
		(property "License" "Apache-2.0"
			(at 284.9 -1.5 0)
			(layer "F.Fab")
			(hide yes)
			(effects
				(font
					(size 1 1)
					(thickness 0.15)
				)
			)
		)
		(property "MPN" "504050-0291"
			(at 284.9 -1.5 0)
			(layer "F.Fab")
			(hide yes)
			(effects
				(font
					(size 1 1)
					(thickness 0.15)
				)
			)
		)
		(property "Manufacturer" "Molex"
			(at 284.9 -1.5 0)
			(layer "F.Fab")
			(hide yes)
			(effects
				(font
					(size 1 1)
					(thickness 0.15)
				)
			)
		)
		(sheetname "/Power supply/")
		(sheetfile "power-supply.kicad_sch")
		(attr smd)
		(fp_line
			(start 3.374 -2.86)
			(end 3.374 1.088)
			(stroke
				(width 0.15)
				(type solid)
			)
			(layer "F.SilkS")
		)
		(fp_line
			(start 1.399 -2.86)
			(end 3.374 -2.86)
			(stroke
				(width 0.15)
				(type solid)
			)
			(layer "F.SilkS")
		)
		(fp_line
			(start -3.374 -2.86)
			(end -1.4 -2.86)
			(stroke
				(width 0.15)
				(type solid)
			)
			(layer "F.SilkS")
		)
		(fp_line
			(start -3.374 1.088)
			(end -3.374 -2.86)
			(stroke
				(width 0.15)
				(type solid)
			)
			(layer "F.SilkS")
		)
		(fp_line
			(start 1.649 1.289)
			(end -1.639 1.289)
			(stroke
				(width 0.15)
				(type solid)
			)
			(layer "F.SilkS")
		)
		(fp_line
			(start 1.649 1.289)
			(end 1.649 3.228)
			(stroke
				(width 0.15)
				(type solid)
			)
			(layer "F.SilkS")
		)
		(fp_line
			(start -1.639 3.239)
			(end -1.639 1.289)
			(stroke
				(width 0.15)
				(type solid)
			)
			(layer "F.SilkS")
		)
		(fp_circle
			(center -1.249 -3.15)
			(end -1.199 -3.15)
			(stroke
				(width 0.15)
				(type solid)
			)
			(fill yes)
			(layer "F.SilkS")
		)
		(fp_line
			(start 3.621 -3.61)
			(end 3.621 1.18)
			(stroke
				(width 0.05)
				(type solid)
			)
			(layer "F.CrtYd")
		)
		(fp_line
			(start -3.629 -3.61)
			(end 3.621 -3.61)
			(stroke
				(width 0.05)
				(type solid)
			)
			(layer "F.CrtYd")
		)
		(fp_line
			(start 4.231 1.18)
			(end 4.231 3.47)
			(stroke
				(width 0.05)
				(type solid)
			)
			(layer "F.CrtYd")
		)
		(fp_line
			(start 3.621 1.18)
			(end 4.231 1.18)
			(stroke
				(width 0.05)
				(type solid)
			)
			(layer "F.CrtYd")
		)
		(fp_line
			(start -3.629 1.18)
			(end -3.629 -3.61)
			(stroke
				(width 0.05)
				(type solid)
			)
			(layer "F.CrtYd")
		)
		(fp_line
			(start -4.249 1.18)
			(end -3.629 1.18)
			(stroke
				(width 0.05)
				(type solid)
			)
			(layer "F.CrtYd")
		)
		(fp_line
			(start 4.231 3.47)
			(end -4.249 3.47)
			(stroke
				(width 0.05)
				(type solid)
			)
			(layer "F.CrtYd")
		)
		(fp_line
			(start -4.249 3.47)
			(end -4.249 1.18)
			(stroke
				(width 0.05)
				(type solid)
			)
			(layer "F.CrtYd")
		)
		(fp_line
			(start 3.374 -2.86)
			(end 3.374 3.239)
			(stroke
				(width 0.15)
				(type solid)
			)
			(layer "F.Fab")
		)
		(fp_line
			(start -3.374 -2.86)
			(end 3.374 -2.86)
			(stroke
				(width 0.15)
				(type solid)
			)
			(layer "F.Fab")
		)
		(fp_line
			(start 1.75 1.188)
			(end -1.749 1.188)
			(stroke
				(width 0.15)
				(type solid)
			)
			(layer "F.Fab")
		)
		(fp_line
			(start 1.75 1.188)
			(end 1.75 3.239)
			(stroke
				(width 0.15)
				(type solid)
			)
			(layer "F.Fab")
		)
		(fp_line
			(start 1.75 3.239)
			(end 3.374 3.239)
			(stroke
				(width 0.15)
				(type solid)
			)
			(layer "F.Fab")
		)
		(fp_line
			(start -3.374 3.239)
			(end -3.374 -2.86)
			(stroke
				(width 0.15)
				(type solid)
			)
			(layer "F.Fab")
		)
		(fp_line
			(start -3.374 3.239)
			(end -1.749 3.239)
			(stroke
				(width 0.15)
				(type solid)
			)
			(layer "F.Fab")
		)
		(fp_line
			(start -1.749 3.249)
			(end -1.749 1.188)
			(stroke
				(width 0.15)
				(type solid)
			)
			(layer "F.Fab")
		)
		(fp_text user "${REFERENCE}"
			(at -3.481 10.175 90)
			(layer "F.Fab")
			(effects
				(font
					(size 0.7 0.7)
					(thickness 0.15)
				)
				(justify left bottom)
			)
		)
		(fp_text user "License: Apache-2.0"
			(at -3.481 12.573 90)
			(layer "F.Fab")
			(effects
				(font
					(size 0.7 0.7)
					(thickness 0.15)
				)
				(justify left bottom)
			)
		)
		(fp_text user "Author: Antmicro"
			(at -3.481 11.374 90)
			(layer "F.Fab")
			(effects
				(font
					(size 0.7 0.7)
					(thickness 0.15)
				)
				(justify left bottom)
			)
		)
		(pad "1" smd roundrect
			(at -0.749 -2.85 90)
			(size 0.6 1)
			(layers "F.Cu" "F.Mask" "F.Paste")
			(roundrect_rratio 0.25)
			(net 287 "3V0_BAT")
			(pinfunction "1")
			(pintype "passive")
		)
		(pad "2" smd roundrect
			(at 0.75 -2.85 90)
			(size 0.6 1)
			(layers "F.Cu" "F.Mask" "F.Paste")
			(roundrect_rratio 0.25)
			(net 1 "GND")
			(pinfunction "2")
			(pintype "passive")
		)
		(pad "MP1" smd roundrect
			(at -3.354 2.338 90)
			(size 1.25 1.8)
			(layers "F.Cu" "F.Mask" "F.Paste")
			(roundrect_rratio 0.25)
			(net 1 "GND")
			(pinfunction "MP")
			(pintype "passive")
		)
		(pad "MP2" smd roundrect
			(at 3.356 2.338 90)
			(size 1.25 1.8)
			(layers "F.Cu" "F.Mask" "F.Paste")
			(roundrect_rratio 0.25)
			(net 1 "GND")
			(pinfunction "MP2")
			(pintype "passive")
		)
	)
	(footprint "antmicro-footprints:TP_SMD_1mm"
		(layer "F.Cu")
		(at 144.54 114.4658)
		(property "Reference" "TP3"
			(at 0.56 0.4342 0)
			(layer "F.SilkS")
			(effects
				(font
					(size 0.7 0.7)
					(thickness 0.15)
				)
				(justify left bottom)
			)
		)
		(property "Value" "TP_1mm_SMD"
			(at 0 1.4 0)
			(layer "F.Fab")
			(effects
				(font
					(size 0.7 0.7)
					(thickness 0.15)
				)
				(justify left bottom)
			)
		)
		(property "Description" "Test point 1mm SMD"
			(at 0 0 0)
			(layer "F.Fab")
			(hide yes)
			(effects
				(font
					(size 1.27 1.27)
					(thickness 0.15)
				)
			)
		)
		(property "Author" "Antmicro"
			(at 0 0 0)
			(layer "F.Fab")
			(hide yes)
			(effects
				(font
					(size 1 1)
					(thickness 0.15)
				)
			)
		)
		(property "License" "Apache-2.0"
			(at 0 0 0)
			(layer "F.Fab")
			(hide yes)
			(effects
				(font
					(size 1 1)
					(thickness 0.15)
				)
			)
		)
		(property "MPN" ""
			(at 0 0 0)
			(layer "F.Fab")
			(hide yes)
			(effects
				(font
					(size 1 1)
					(thickness 0.15)
				)
			)
		)
		(property "Manufacturer" ""
			(at 0 0 0)
			(layer "F.Fab")
			(hide yes)
			(effects
				(font
					(size 1 1)
					(thickness 0.15)
				)
			)
		)
		(sheetname "/Interfaces/")
		(sheetfile "interfaces.kicad_sch")
		(attr exclude_from_pos_files exclude_from_bom)
		(fp_circle
			(center 0 0)
			(end 0.6 0)
			(stroke
				(width 0.05)
				(type default)
			)
			(fill no)
			(layer "F.CrtYd")
		)
		(pad "1" smd circle
			(at 0 0)
			(size 1 1)
			(layers "F.Cu" "F.Mask")
			(net 402 "Net-(U1-DS)")
			(pinfunction "1")
			(pintype "passive")
		)
	)
	(footprint "antmicro-footprints:C_0402_1005Metric"
		(layer "F.Cu")
		(at 82.665 163.565)
		(descr "Capacitor SMD 0402")
		(tags "capacitor SMD 0402")
		(property "Reference" "C251"
			(at 0.835 -0.065 0)
			(layer "F.SilkS")
			(effects
				(font
					(size 0.7 0.7)
					(thickness 0.15)
				)
				(justify left bottom)
			)
		)
		(property "Value" "C_100n_0402"
			(at 0 1.4 0)
			(layer "F.Fab")
			(effects
				(font
					(size 0.7 0.7)
					(thickness 0.15)
				)
				(justify left bottom)
			)
		)
		(property "Datasheet" "https://www.murata.com/products/productdetail?partno=GRM155R61H104KE14%23"
			(at 0 0 0)
			(layer "F.Fab")
			(hide yes)
			(effects
				(font
					(size 1.27 1.27)
					(thickness 0.15)
				)
			)
		)
		(property "Description" "SMD Multilayer Ceramic Capacitor, 0.1 µF, 50 V, 0402 [1005 Metric], ± 10%, X5R, GRM Series"
			(at 0 0 0)
			(layer "F.Fab")
			(hide yes)
			(effects
				(font
					(size 1.27 1.27)
					(thickness 0.15)
				)
			)
		)
		(property "Author" "Antmicro"
			(at 0 0 0)
			(layer "F.Fab")
			(hide yes)
			(effects
				(font
					(size 1 1)
					(thickness 0.15)
				)
			)
		)
		(property "Dielectric" "X5R"
			(at 0 0 0)
			(layer "F.Fab")
			(hide yes)
			(effects
				(font
					(size 1 1)
					(thickness 0.15)
				)
			)
		)
		(property "License" "Apache-2.0"
			(at 0 0 0)
			(layer "F.Fab")
			(hide yes)
			(effects
				(font
					(size 1 1)
					(thickness 0.15)
				)
			)
		)
		(property "MPN" "GRM155R61H104KE14D"
			(at 0 0 0)
			(layer "F.Fab")
			(hide yes)
			(effects
				(font
					(size 1 1)
					(thickness 0.15)
				)
			)
		)
		(property "Manufacturer" "Murata"
			(at 0 0 0)
			(layer "F.Fab")
			(hide yes)
			(effects
				(font
					(size 1 1)
					(thickness 0.15)
				)
			)
		)
		(property "Val" "100n"
			(at 0 0 0)
			(layer "F.Fab")
			(hide yes)
			(effects
				(font
					(size 1 1)
					(thickness 0.15)
				)
			)
		)
		(property "Voltage" "50V"
			(at 0 0 0)
			(layer "F.Fab")
			(hide yes)
			(effects
				(font
					(size 1 1)
					(thickness 0.15)
				)
			)
		)
		(sheetname "/Interfaces/")
		(sheetfile "interfaces.kicad_sch")
		(attr smd)
		(fp_rect
			(start -0.925 -0.47)
			(end 0.925 0.47)
			(stroke
				(width 0.05)
				(type default)
			)
			(fill no)
			(layer "F.CrtYd")
		)
		(fp_line
			(start -0.494 -0.25)
			(end 0.504 -0.25)
			(stroke
				(width 0.15)
				(type solid)
			)
			(layer "F.Fab")
		)
		(fp_line
			(start -0.494 0.248)
			(end -0.494 -0.25)
			(stroke
				(width 0.15)
				(type solid)
			)
			(layer "F.Fab")
		)
		(fp_line
			(start 0.504 -0.25)
			(end 0.504 0.248)
			(stroke
				(width 0.15)
				(type solid)
			)
			(layer "F.Fab")
		)
		(fp_line
			(start 0.504 0.248)
			(end -0.494 0.248)
			(stroke
				(width 0.15)
				(type solid)
			)
			(layer "F.Fab")
		)
		(pad "1" smd roundrect
			(at -0.48 0)
			(size 0.59 0.64)
			(layers "F.Cu" "F.Mask" "F.Paste")
			(roundrect_rratio 0.25)
			(net 1 "GND")
			(pintype "passive")
		)
		(pad "2" smd roundrect
			(at 0.48 0)
			(size 0.59 0.64)
			(layers "F.Cu" "F.Mask" "F.Paste")
			(roundrect_rratio 0.25)
			(net 2 "VCC3V3")
			(pintype "passive")
		)
	)
	(footprint "antmicro-footprints:C_0402_1005Metric"
		(layer "F.Cu")
		(at 90.59 165.415 180)
		(descr "Capacitor SMD 0402")
		(tags "capacitor SMD 0402")
		(property "Reference" "C252"
			(at -3.71 -0.91 0)
			(layer "F.SilkS")
			(effects
				(font
					(size 0.7 0.7)
					(thickness 0.15)
				)
				(justify right bottom)
			)
		)
		(property "Value" "C_100n_0402"
			(at 0 1.4 0)
			(layer "F.Fab")
			(effects
				(font
					(size 0.7 0.7)
					(thickness 0.15)
				)
				(justify right bottom)
			)
		)
		(property "Datasheet" "https://www.murata.com/products/productdetail?partno=GRM155R61H104KE14%23"
			(at 0 0 180)
			(layer "F.Fab")
			(hide yes)
			(effects
				(font
					(size 1.27 1.27)
					(thickness 0.15)
				)
			)
		)
		(property "Description" "SMD Multilayer Ceramic Capacitor, 0.1 µF, 50 V, 0402 [1005 Metric], ± 10%, X5R, GRM Series"
			(at 0 0 180)
			(layer "F.Fab")
			(hide yes)
			(effects
				(font
					(size 1.27 1.27)
					(thickness 0.15)
				)
			)
		)
		(property "Author" "Antmicro"
			(at 181.18 330.83 0)
			(layer "F.Fab")
			(hide yes)
			(effects
				(font
					(size 1 1)
					(thickness 0.15)
				)
			)
		)
		(property "Dielectric" "X5R"
			(at 181.18 330.83 0)
			(layer "F.Fab")
			(hide yes)
			(effects
				(font
					(size 1 1)
					(thickness 0.15)
				)
			)
		)
		(property "License" "Apache-2.0"
			(at 181.18 330.83 0)
			(layer "F.Fab")
			(hide yes)
			(effects
				(font
					(size 1 1)
					(thickness 0.15)
				)
			)
		)
		(property "MPN" "GRM155R61H104KE14D"
			(at 181.18 330.83 0)
			(layer "F.Fab")
			(hide yes)
			(effects
				(font
					(size 1 1)
					(thickness 0.15)
				)
			)
		)
		(property "Manufacturer" "Murata"
			(at 181.18 330.83 0)
			(layer "F.Fab")
			(hide yes)
			(effects
				(font
					(size 1 1)
					(thickness 0.15)
				)
			)
		)
		(property "Val" "100n"
			(at 181.18 330.83 0)
			(layer "F.Fab")
			(hide yes)
			(effects
				(font
					(size 1 1)
					(thickness 0.15)
				)
			)
		)
		(property "Voltage" "50V"
			(at 181.18 330.83 0)
			(layer "F.Fab")
			(hide yes)
			(effects
				(font
					(size 1 1)
					(thickness 0.15)
				)
			)
		)
		(sheetname "/Interfaces/")
		(sheetfile "interfaces.kicad_sch")
		(attr smd)
		(fp_rect
			(start -0.925 -0.47)
			(end 0.925 0.47)
			(stroke
				(width 0.05)
				(type default)
			)
			(fill no)
			(layer "F.CrtYd")
		)
		(fp_line
			(start 0.504 0.248)
			(end -0.494 0.248)
			(stroke
				(width 0.15)
				(type solid)
			)
			(layer "F.Fab")
		)
		(fp_line
			(start 0.504 -0.25)
			(end 0.504 0.248)
			(stroke
				(width 0.15)
				(type solid)
			)
			(layer "F.Fab")
		)
		(fp_line
			(start -0.494 0.248)
			(end -0.494 -0.25)
			(stroke
				(width 0.15)
				(type solid)
			)
			(layer "F.Fab")
		)
		(fp_line
			(start -0.494 -0.25)
			(end 0.504 -0.25)
			(stroke
				(width 0.15)
				(type solid)
			)
			(layer "F.Fab")
		)
		(pad "1" smd roundrect
			(at -0.48 0 180)
			(size 0.59 0.64)
			(layers "F.Cu" "F.Mask" "F.Paste")
			(roundrect_rratio 0.25)
			(net 1 "GND")
			(pintype "passive")
		)
		(pad "2" smd roundrect
			(at 0.48 0 180)
			(size 0.59 0.64)
			(layers "F.Cu" "F.Mask" "F.Paste")
			(roundrect_rratio 0.25)
			(net 2 "VCC3V3")
			(pintype "passive")
		)
	)
	(footprint "antmicro-footprints:R_0402_1005Metric"
		(layer "F.Cu")
		(at 83.09 165.065 90)
		(descr "Resistor SMD 0402")
		(tags "resistor SMD 0402")
		(property "Reference" "R12"
			(at -1.135 -0.59 90)
			(layer "F.SilkS")
			(effects
				(font
					(size 0.7 0.7)
					(thickness 0.15)
				)
				(justify left bottom)
			)
		)
		(property "Value" "R_200k_0402"
			(at 0 1.4 90)
			(layer "F.Fab")
			(effects
				(font
					(size 0.7 0.7)
					(thickness 0.15)
				)
				(justify left bottom)
			)
		)
		(property "Datasheet" "https://www.bourns.com/docs/product-datasheets/cr.pdf"
			(at 0 0 90)
			(layer "F.Fab")
			(hide yes)
			(effects
				(font
					(size 1.27 1.27)
					(thickness 0.15)
				)
			)
		)
		(property "Description" "SMD Chip Resistor, 200 kohm, ± 1%, 62.5 mW, 0402 [1005 Metric], Thick Film, General Purpose"
			(at 0 0 90)
			(layer "F.Fab")
			(hide yes)
			(effects
				(font
					(size 1.27 1.27)
					(thickness 0.15)
				)
			)
		)
		(property "Author" "Antmicro"
			(at 248.155 81.975 0)
			(layer "F.Fab")
			(hide yes)
			(effects
				(font
					(size 1 1)
					(thickness 0.15)
				)
			)
		)
		(property "License" "Apache-2.0"
			(at 248.155 81.975 0)
			(layer "F.Fab")
			(hide yes)
			(effects
				(font
					(size 1 1)
					(thickness 0.15)
				)
			)
		)
		(property "MPN" "CR0402-FX-2003GLF"
			(at 248.155 81.975 0)
			(layer "F.Fab")
			(hide yes)
			(effects
				(font
					(size 1 1)
					(thickness 0.15)
				)
			)
		)
		(property "Manufacturer" "Bourns"
			(at 248.155 81.975 0)
			(layer "F.Fab")
			(hide yes)
			(effects
				(font
					(size 1 1)
					(thickness 0.15)
				)
			)
		)
		(property "Tolerance" "1%"
			(at 248.155 81.975 0)
			(layer "F.Fab")
			(hide yes)
			(effects
				(font
					(size 1 1)
					(thickness 0.15)
				)
			)
		)
		(property "Val" "200k"
			(at 248.155 81.975 0)
			(layer "F.Fab")
			(hide yes)
			(effects
				(font
					(size 1 1)
					(thickness 0.15)
				)
			)
		)
		(sheetname "/Interfaces/")
		(sheetfile "interfaces.kicad_sch")
		(attr smd)
		(fp_rect
			(start -0.925 -0.47)
			(end 0.925 0.47)
			(stroke
				(width 0.05)
				(type default)
			)
			(fill no)
			(layer "F.CrtYd")
		)
		(fp_rect
			(start -0.5 -0.25)
			(end 0.5 0.25)
			(stroke
				(width 0.15)
				(type solid)
			)
			(fill no)
			(layer "F.Fab")
		)
		(pad "1" smd roundrect
			(at -0.48 0 90)
			(size 0.59 0.64)
			(layers "F.Cu" "F.Mask" "F.Paste")
			(roundrect_rratio 0.25)
			(net 312 "Net-(U21-EN)")
			(pintype "passive")
		)
		(pad "2" smd roundrect
			(at 0.48 0 90)
			(size 0.59 0.64)
			(layers "F.Cu" "F.Mask" "F.Paste")
			(roundrect_rratio 0.25)
			(net 2 "VCC3V3")
			(pintype "passive")
		)
	)
	(footprint "antmicro-footprints:R_0402_1005Metric"
		(layer "F.Cu")
		(at 90.59 164.39 180)
		(descr "Resistor SMD 0402")
		(tags "resistor SMD 0402")
		(property "Reference" "R62"
			(at -3.09 -0.91 0)
			(layer "F.SilkS")
			(effects
				(font
					(size 0.7 0.7)
					(thickness 0.15)
				)
				(justify right bottom)
			)
		)
		(property "Value" "R_200k_0402"
			(at 0 1.4 0)
			(layer "F.Fab")
			(effects
				(font
					(size 0.7 0.7)
					(thickness 0.15)
				)
				(justify right bottom)
			)
		)
		(property "Datasheet" "https://www.bourns.com/docs/product-datasheets/cr.pdf"
			(at 0 0 180)
			(layer "F.Fab")
			(hide yes)
			(effects
				(font
					(size 1.27 1.27)
					(thickness 0.15)
				)
			)
		)
		(property "Description" "SMD Chip Resistor, 200 kohm, ± 1%, 62.5 mW, 0402 [1005 Metric], Thick Film, General Purpose"
			(at 0 0 180)
			(layer "F.Fab")
			(hide yes)
			(effects
				(font
					(size 1.27 1.27)
					(thickness 0.15)
				)
			)
		)
		(property "Author" "Antmicro"
			(at 181.18 328.78 0)
			(layer "F.Fab")
			(hide yes)
			(effects
				(font
					(size 1 1)
					(thickness 0.15)
				)
			)
		)
		(property "License" "Apache-2.0"
			(at 181.18 328.78 0)
			(layer "F.Fab")
			(hide yes)
			(effects
				(font
					(size 1 1)
					(thickness 0.15)
				)
			)
		)
		(property "MPN" "CR0402-FX-2003GLF"
			(at 181.18 328.78 0)
			(layer "F.Fab")
			(hide yes)
			(effects
				(font
					(size 1 1)
					(thickness 0.15)
				)
			)
		)
		(property "Manufacturer" "Bourns"
			(at 181.18 328.78 0)
			(layer "F.Fab")
			(hide yes)
			(effects
				(font
					(size 1 1)
					(thickness 0.15)
				)
			)
		)
		(property "Tolerance" "1%"
			(at 181.18 328.78 0)
			(layer "F.Fab")
			(hide yes)
			(effects
				(font
					(size 1 1)
					(thickness 0.15)
				)
			)
		)
		(property "Val" "200k"
			(at 181.18 328.78 0)
			(layer "F.Fab")
			(hide yes)
			(effects
				(font
					(size 1 1)
					(thickness 0.15)
				)
			)
		)
		(sheetname "/Interfaces/")
		(sheetfile "interfaces.kicad_sch")
		(attr smd)
		(fp_rect
			(start -0.925 -0.47)
			(end 0.925 0.47)
			(stroke
				(width 0.05)
				(type default)
			)
			(fill no)
			(layer "F.CrtYd")
		)
		(fp_rect
			(start -0.5 -0.25)
			(end 0.5 0.25)
			(stroke
				(width 0.15)
				(type solid)
			)
			(fill no)
			(layer "F.Fab")
		)
		(pad "1" smd roundrect
			(at -0.48 0 180)
			(size 0.59 0.64)
			(layers "F.Cu" "F.Mask" "F.Paste")
			(roundrect_rratio 0.25)
			(net 338 "Net-(U22-EN)")
			(pintype "passive")
		)
		(pad "2" smd roundrect
			(at 0.48 0 180)
			(size 0.59 0.64)
			(layers "F.Cu" "F.Mask" "F.Paste")
			(roundrect_rratio 0.25)
			(net 2 "VCC3V3")
			(pintype "passive")
		)
	)
	(footprint "antmicro-footprints:SFF-TA-1002-4C+"
		(layer "F.Cu")
		(at 104.89 177.355)
		(property "Reference" "J9"
			(at -29.6 3.3 0)
			(layer "F.SilkS")
			(hide yes)
			(effects
				(font
					(size 0.7 0.7)
					(thickness 0.15)
				)
				(justify left bottom)
			)
		)
		(property "Value" "SFF-TA-1002-4C+"
			(at 0 4.1 0)
			(layer "F.Fab")
			(effects
				(font
					(size 0.7 0.7)
					(thickness 0.15)
				)
				(justify left bottom)
			)
		)
		(property "Datasheet" "https://cdn.amphenol-icc.com/media/wysiwyg/files/documentation/sme005.pdf?__cf_chl_jschl_tk__=4604d1306574a1ee474ea914090d3e0c57e266a6-1606907014-0-AbkYBTCTl__kMBcY3BDmgKpfUy32FqitwN2Lniuy8W-uyv2Ev04Q-Q5Mr7srIz_Wnur0_9chB4CRbxKSYcEh7IvAJYsUgJ0PWIS5YdRqqHg567uaZciEX2hQP4ss5l6M4XdNrxEjJppHvyRV3ku89t-VmUSzhgCb8oJlyHpTxST4dEmKZNXfM53TM0tmGirdVbCRt1Byrx5pkz_uMvNABIOj7B2-eDGK52J3DWRD76zEyjdxY7Iz11gPiOY5i_QGIR3uOwkR5LBPNXe8zGqAf8--AKa7RqDbIriQRt90_32C4zIuHqbGa05BXS135E65ov80PbVcb4eSiutCqcJUAacUwu3eVnXVeIumfihJxuP8Rv7_n6saeG_2IuQpEiskzovLGKZM3667Y-rm-AL1NRXTamtvBxqTk0vyMvZ60FgJ"
			(at 0 0 0)
			(layer "F.Fab")
			(hide yes)
			(effects
				(font
					(size 1.27 1.27)
					(thickness 0.15)
				)
			)
		)
		(property "Description" "PCB EDGE PCI connector"
			(at 0 0 0)
			(layer "F.Fab")
			(hide yes)
			(effects
				(font
					(size 1.27 1.27)
					(thickness 0.15)
				)
			)
		)
		(property "Author" "Antmicro"
			(at 0 0 0)
			(layer "F.Fab")
			(hide yes)
			(effects
				(font
					(size 1 1)
					(thickness 0.15)
				)
			)
		)
		(property "License" "Apache-2.0"
			(at 0 0 0)
			(layer "F.Fab")
			(hide yes)
			(effects
				(font
					(size 1 1)
					(thickness 0.15)
				)
			)
		)
		(property "MPN" ""
			(at 0 0 0)
			(layer "F.Fab")
			(hide yes)
			(effects
				(font
					(size 1 1)
					(thickness 0.15)
				)
			)
		)
		(property "Manufacturer" ""
			(at 0 0 0)
			(layer "F.Fab")
			(hide yes)
			(effects
				(font
					(size 1 1)
					(thickness 0.15)
				)
			)
		)
		(property "DNP" ""
			(at 0 0 0)
			(unlocked yes)
			(layer "F.Fab")
			(hide yes)
			(effects
				(font
					(size 1 1)
					(thickness 0.15)
				)
			)
		)
		(sheetname "/Edge connector/")
		(sheetfile "edge-connector.kicad_sch")
		(attr exclude_from_pos_files exclude_from_bom allow_missing_courtyard)
		(fp_line
			(start -35 -4.6)
			(end -31.98 -4.6)
			(stroke
				(width 0.12)
				(type solid)
			)
			(layer "B.Fab")
		)
		(fp_line
			(start -31.48 1.19)
			(end -31.48 -4.1)
			(stroke
				(width 0.12)
				(type solid)
			)
			(layer "B.Fab")
		)
		(fp_line
			(start -30.73 1.94)
			(end -31.48 1.19)
			(stroke
				(width 0.12)
				(type solid)
			)
			(layer "B.Fab")
		)
		(fp_line
			(start -30.73 1.94)
			(end -22.275 1.94)
			(stroke
				(width 0.12)
				(type solid)
			)
			(layer "B.Fab")
		)
		(fp_line
			(start -21.525 1.19)
			(end -22.275 1.94)
			(stroke
				(width 0.12)
				(type solid)
			)
			(layer "B.Fab")
		)
		(fp_line
			(start -21.525 1.19)
			(end -21.525 -4.06)
			(stroke
				(width 0.12)
				(type solid)
			)
			(layer "B.Fab")
		)
		(fp_line
			(start -19.275 1.19)
			(end -19.275 -4.06)
			(stroke
				(width 0.12)
				(type solid)
			)
			(layer "B.Fab")
		)
		(fp_line
			(start -19.275 1.19)
			(end -18.525 1.94)
			(stroke
				(width 0.12)
				(type solid)
			)
			(layer "B.Fab")
		)
		(fp_line
			(start -18.525 1.94)
			(end -1.67 1.94)
			(stroke
				(width 0.12)
				(type solid)
			)
			(layer "B.Fab")
		)
		(fp_line
			(start -0.92 1.19)
			(end -1.67 1.94)
			(stroke
				(width 0.12)
				(type solid)
			)
			(layer "B.Fab")
		)
		(fp_line
			(start -0.92 1.19)
			(end -0.92 -4.26)
			(stroke
				(width 0.12)
				(type solid)
			)
			(layer "B.Fab")
		)
		(fp_line
			(start 0.93 1.19)
			(end 0.93 -4.34)
			(stroke
				(width 0.12)
				(type solid)
			)
			(layer "B.Fab")
		)
		(fp_line
			(start 0.93 1.19)
			(end 1.68 1.94)
			(stroke
				(width 0.12)
				(type solid)
			)
			(layer "B.Fab")
		)
		(fp_line
			(start 1.68 1.94)
			(end 10.135 1.94)
			(stroke
				(width 0.12)
				(type solid)
			)
			(layer "B.Fab")
		)
		(fp_line
			(start 10.135 1.94)
			(end 10.885 1.19)
			(stroke
				(width 0.12)
				(type solid)
			)
			(layer "B.Fab")
		)
		(fp_line
			(start 10.885 1.19)
			(end 10.885 -3.81)
			(stroke
				(width 0.12)
				(type solid)
			)
			(layer "B.Fab")
		)
		(fp_line
			(start 13.635 1.19)
			(end 13.635 -3.89)
			(stroke
				(width 0.12)
				(type solid)
			)
			(layer "B.Fab")
		)
		(fp_line
			(start 14.385 1.94)
			(end 13.635 1.19)
			(stroke
				(width 0.12)
				(type solid)
			)
			(layer "B.Fab")
		)
		(fp_line
			(start 14.385 1.94)
			(end 31.2451 1.94)
			(stroke
				(width 0.12)
				(type solid)
			)
			(layer "B.Fab")
		)
		(fp_line
			(start 32 1.19)
			(end 31.2451 1.94)
			(stroke
				(width 0.12)
				(type solid)
			)
			(layer "B.Fab")
		)
		(fp_line
			(start 32 1.19)
			(end 32 -4.1)
			(stroke
				(width 0.12)
				(type solid)
			)
			(layer "B.Fab")
		)
		(fp_arc
			(start -31.98 -4.6)
			(mid -31.626447 -4.453553)
			(end -31.48 -4.1)
			(stroke
				(width 0.12)
				(type solid)
			)
			(layer "B.Fab")
		)
		(fp_arc
			(start -21.525 -4.06)
			(mid -20.4 -5.225711)
			(end -19.275 -4.06)
			(stroke
				(width 0.12)
				(type solid)
			)
			(layer "B.Fab")
		)
		(fp_arc
			(start -0.92 -4.26)
			(mid -0.015005 -5.225648)
			(end 0.930864 -4.3)
			(stroke
				(width 0.12)
				(type solid)
			)
			(layer "B.Fab")
		)
		(fp_arc
			(start 10.885 -3.81)
			(mid 12.264997 -5.225573)
			(end 13.634673 -3.800012)
			(stroke
				(width 0.12)
				(type solid)
			)
			(layer "B.Fab")
		)
		(fp_arc
			(start 32 -4.1)
			(mid 32.146447 -4.453553)
			(end 32.5 -4.6)
			(stroke
				(width 0.12)
				(type solid)
			)
			(layer "B.Fab")
		)
		(fp_text user "License: Apache-2.0"
			(at 0 7.8 0)
			(layer "F.Fab")
			(effects
				(font
					(size 0.7 0.7)
					(thickness 0.15)
				)
				(justify left bottom)
			)
		)
		(fp_text user "${REFERENCE}"
			(at 0 5.4 0)
			(layer "F.Fab")
			(effects
				(font
					(size 0.7 0.7)
					(thickness 0.15)
				)
				(justify left bottom)
			)
		)
		(fp_text user "Author: Antmicro"
			(at 0 6.6 0)
			(layer "F.Fab")
			(effects
				(font
					(size 0.7 0.7)
					(thickness 0.15)
				)
				(justify left bottom)
			)
		)
		(pad "A1" smd rect
			(at -18.205 -0.2)
			(size 0.38 1.72)
			(layers "B.Cu" "B.Mask")
			(net 31 "I2C[0]_SCL")
			(pinfunction "A1")
			(pintype "passive")
		)
		(pad "A2" smd rect
			(at -17.6 -0.2)
			(size 0.38 1.72)
			(layers "B.Cu" "B.Mask")
			(net 32 "I2C[0]_SDA")
			(pinfunction "A2")
			(pintype "passive")
		)
		(pad "A3" smd rect
			(at -17 -0.2)
			(size 0.38 1.72)
			(layers "B.Cu" "B.Mask")
			(net 22 "I2C[1]_SCL")
			(pinfunction "A3")
			(pintype "passive")
		)
		(pad "A4" smd rect
			(at -16.4 -0.2)
			(size 0.38 1.72)
			(layers "B.Cu" "B.Mask")
			(net 23 "I2C[1]_SDA")
			(pinfunction "A4")
			(pintype "passive")
		)
		(pad "A5" smd rect
			(at -15.8 -0.2)
			(size 0.38 1.72)
			(layers "B.Cu" "B.Mask")
			(net 26 "I2C[2]_SCL")
			(pinfunction "A5")
			(pintype "passive")
		)
		(pad "A6" smd rect
			(at -15.2 -0.2)
			(size 0.38 1.72)
			(layers "B.Cu" "B.Mask")
			(net 25 "I2C[2]_SDA")
			(pinfunction "A6")
			(pintype "passive")
		)
		(pad "A7" smd rect
			(at -14.6 -0.2)
			(size 0.38 1.72)
			(layers "B.Cu" "B.Mask")
			(net 19 "I2C[3]_SCL")
			(pinfunction "A7")
			(pintype "passive")
		)
		(pad "A8" smd rect
			(at -14 -0.2)
			(size 0.38 1.72)
			(layers "B.Cu" "B.Mask")
			(net 21 "I2C[3]_SDA")
			(pinfunction "A8")
			(pintype "passive")
		)
		(pad "A9" smd rect
			(at -13.4 -0.2)
			(size 0.38 1.72)
			(layers "B.Cu" "B.Mask")
			(net 30 "I2C[4]_SCL")
			(pinfunction "A9")
			(pintype "passive")
		)
		(pad "A10" smd rect
			(at -12.8 -0.2)
			(size 0.38 1.72)
			(layers "B.Cu" "B.Mask")
			(net 27 "I2C[4]_SDA")
			(pinfunction "A10")
			(pintype "passive")
		)
		(pad "A11" smd rect
			(at -12.2 0)
			(size 0.38 2.12)
			(layers "B.Cu" "B.Mask")
			(net 18 "I2C[5]_SCL")
			(pinfunction "A11")
			(pintype "passive")
		)
		(pad "A12" smd rect
			(at -11.6 -0.2)
			(size 0.38 1.72)
			(layers "B.Cu" "B.Mask")
			(net 17 "I2C[5]_SDA")
			(pinfunction "A12")
			(pintype "passive")
		)
		(pad "A13" smd rect
			(at -11 -0.2)
			(size 0.38 1.72)
			(layers "B.Cu" "B.Mask")
			(net 1 "GND")
			(pinfunction "A13")
			(pintype "passive")
		)
		(pad "A14" smd rect
			(at -10.4 0)
			(size 0.38 2.12)
			(layers "B.Cu" "B.Mask")
			(net 379 "PCIE_BMC_CLK_100_P")
			(pinfunction "A14")
			(pintype "passive")
		)
		(pad "A15" smd rect
			(at -9.8 -0.2)
			(size 0.38 1.72)
			(layers "B.Cu" "B.Mask")
			(net 380 "PCIE_BMC_CLK_100_N")
			(pinfunction "A15")
			(pintype "passive")
		)
		(pad "A16" smd rect
			(at -9.2 -0.2)
			(size 0.38 1.72)
			(layers "B.Cu" "B.Mask")
			(net 1 "GND")
			(pinfunction "A16")
			(pintype "passive")
		)
		(pad "A17" smd rect
			(at -8.6 0)
			(size 0.38 2.12)
			(layers "B.Cu" "B.Mask")
			(net 378 "PCIE_BMC_TX_P")
			(pinfunction "A17")
			(pintype "passive")
		)
		(pad "A18" smd rect
			(at -8 -0.2)
			(size 0.38 1.72)
			(layers "B.Cu" "B.Mask")
			(net 377 "PCIE_BMC_TX_N")
			(pinfunction "A18")
			(pintype "passive")
		)
		(pad "A19" smd rect
			(at -7.4 -0.2)
			(size 0.38 1.72)
			(layers "B.Cu" "B.Mask")
			(net 1 "GND")
			(pinfunction "A19")
			(pintype "passive")
		)
		(pad "A20" smd rect
			(at -6.8 0)
			(size 0.38 2.12)
			(layers "B.Cu" "B.Mask")
			(net 381 "PCIE_BMC_RX_P")
			(pinfunction "A20")
			(pintype "passive")
		)
		(pad "A21" smd rect
			(at -6.2 -0.2)
			(size 0.38 1.72)
			(layers "B.Cu" "B.Mask")
			(net 382 "PCIE_BMC_RX_N")
			(pinfunction "A21")
			(pintype "passive")
		)
		(pad "A22" smd rect
			(at -5.6 -0.2)
			(size 0.38 1.72)
			(layers "B.Cu" "B.Mask")
			(net 1 "GND")
			(pinfunction "A22")
			(pintype "passive")
		)
		(pad "A23" smd rect
			(at -5 -0.2)
			(size 0.38 1.72)
			(layers "B.Cu" "B.Mask")
			(net 28 "I2C[6]_SCL")
			(pinfunction "A23")
			(pintype "passive")
		)
		(pad "A24" smd rect
			(at -4.4 -0.2)
			(size 0.38 1.72)
			(layers "B.Cu" "B.Mask")
			(net 29 "I2C[6]_SDA")
			(pinfunction "A24")
			(pintype "passive")
		)
		(pad "A25" smd rect
			(at -3.8 -0.2)
			(size 0.38 1.72)
			(layers "B.Cu" "B.Mask")
			(net 20 "I2C[7]_SCL")
			(pinfunction "A25")
			(pintype "passive")
		)
		(pad "A26" smd rect
			(at -3.2 -0.2)
			(size 0.38 1.72)
			(layers "B.Cu" "B.Mask")
			(net 24 "I2C[7]_SDA")
			(pinfunction "A26")
			(pintype "passive")
		)
		(pad "A27" smd rect
			(at -2.6 -0.2)
			(size 0.38 1.72)
			(layers "B.Cu" "B.Mask")
			(net 45 "I2C[8]_SCL")
			(pinfunction "A27")
			(pintype "passive")
		)
		(pad "A28" smd rect
			(at -2 -0.2)
			(size 0.38 1.72)
			(layers "B.Cu" "B.Mask")
			(net 46 "I2C[8]_SDA")
			(pinfunction "A28")
			(pintype "passive")
		)
		(pad "A29" smd rect
			(at 2.01 -0.2)
			(size 0.38 1.72)
			(layers "B.Cu" "B.Mask")
			(net 37 "I2C[9]_SCL")
			(pinfunction "A29")
			(pintype "passive")
		)
		(pad "A30" smd rect
			(at 2.6 -0.2)
			(size 0.38 1.72)
			(layers "B.Cu" "B.Mask")
			(net 38 "I2C[9]_SDA")
			(pinfunction "A30")
			(pintype "passive")
		)
		(pad "A31" smd rect
			(at 3.2 -0.2)
			(size 0.38 1.72)
			(layers "B.Cu" "B.Mask")
			(net 42 "I2C[10]_SCL")
			(pinfunction "A31")
			(pintype "passive")
		)
		(pad "A32" smd rect
			(at 3.8 -0.2)
			(size 0.38 1.72)
			(layers "B.Cu" "B.Mask")
			(net 41 "I2C[10]_SDA")
			(pinfunction "A32")
			(pintype "passive")
		)
		(pad "A33" smd rect
			(at 4.4 0)
			(size 0.38 2.12)
			(layers "B.Cu" "B.Mask")
			(net 1 "GND")
			(pinfunction "A33")
			(pintype "passive")
		)
		(pad "A34" smd rect
			(at 5 -0.2)
			(size 0.38 1.72)
			(layers "B.Cu" "B.Mask")
			(net 15 "JTAG_TCK")
			(pinfunction "A34")
			(pintype "passive")
		)
		(pad "A35" smd rect
			(at 5.6 -0.2)
			(size 0.38 1.72)
			(layers "B.Cu" "B.Mask")
			(net 16 "JTAG_TMS")
			(pinfunction "A35")
			(pintype "passive")
		)
		(pad "A36" smd rect
			(at 6.2 -0.2)
			(size 0.38 1.72)
			(layers "B.Cu" "B.Mask")
			(net 13 "JTAG_TDI")
			(pinfunction "A36")
			(pintype "passive")
		)
		(pad "A37" smd rect
			(at 6.8 -0.2)
			(size 0.38 1.72)
			(layers "B.Cu" "B.Mask")
			(net 14 "JTAG_TDO")
			(pinfunction "A37")
			(pintype "passive")
		)
		(pad "A38" smd rect
			(at 7.4 -0.2)
			(size 0.38 1.72)
			(layers "B.Cu" "B.Mask")
			(net 34 "I2C[11]_SCL")
			(pinfunction "A38")
			(pintype "passive")
		)
		(pad "A39" smd rect
			(at 8 -0.2)
			(size 0.38 1.72)
			(layers "B.Cu" "B.Mask")
			(net 36 "I2C[11]_SDA")
			(pinfunction "A39")
			(pintype "passive")
		)
		(pad "A40" smd rect
			(at 8.6 -0.2)
			(size 0.38 1.72)
			(layers "B.Cu" "B.Mask")
			(net 44 "I2C[12]_SCL")
			(pinfunction "A40")
			(pintype "passive")
		)
		(pad "A41" smd rect
			(at 9.2 -0.2)
			(size 0.38 1.72)
			(layers "B.Cu" "B.Mask")
			(net 43 "I2C[12]_SDA")
			(pinfunction "A41")
			(pintype "passive")
		)
		(pad "A42" smd rect
			(at 9.8 0)
			(size 0.38 2.12)
			(layers "B.Cu" "B.Mask")
			(net 1 "GND")
			(pinfunction "A42")
			(pintype "passive")
		)
		(pad "A43" smd rect
			(at 14.715 -0.2)
			(size 0.38 1.72)
			(layers "B.Cu" "B.Mask")
			(net 258 "/Edge connector/HPM_FW_RECOVERY")
			(pinfunction "A43")
			(pintype "passive")
		)
		(pad "A44" smd rect
			(at 15.3 -0.2)
			(size 0.38 1.72)
			(layers "B.Cu" "B.Mask")
			(net 257 "/Edge connector/HPM_STBY_RDY")
			(pinfunction "A44")
			(pintype "passive")
		)
		(pad "A45" smd rect
			(at 15.9 -0.2)
			(size 0.38 1.72)
			(layers "B.Cu" "B.Mask")
			(net 256 "/Edge connector/HPM_STBY_EN")
			(pinfunction "A45")
			(pintype "passive")
		)
		(pad "A46" smd rect
			(at 16.5 -0.2)
			(size 0.38 1.72)
			(layers "B.Cu" "B.Mask")
			(net 255 "/Edge connector/HPM_STBY_RST_N")
			(pinfunction "A46")
			(pintype "passive")
		)
		(pad "A47" smd rect
			(at 17.1 -0.2)
			(size 0.38 1.72)
			(layers "B.Cu" "B.Mask")
			(net 254 "/Edge connector/SYS_PWRBTN_N")
			(pinfunction "A47")
			(pintype "passive")
		)
		(pad "A48" smd rect
			(at 17.7 -0.2)
			(size 0.38 1.72)
			(layers "B.Cu" "B.Mask")
			(net 253 "/Edge connector/SYS_PWROK")
			(pinfunction "A48")
			(pintype "passive")
		)
		(pad "A49" smd rect
			(at 18.3 -0.2)
			(size 0.38 1.72)
			(layers "B.Cu" "B.Mask")
			(net 252 "/Edge connector/DBP_PREQ_N")
			(pinfunction "A49")
			(pintype "passive")
		)
		(pad "A50" smd rect
			(at 18.9 -0.2)
			(size 0.38 1.72)
			(layers "B.Cu" "B.Mask")
			(net 251 "/Edge connector/DBP_PRDY_N")
			(pinfunction "A50")
			(pintype "passive")
		)
		(pad "A51" smd rect
			(at 19.5 -0.2)
			(size 0.38 1.72)
			(layers "B.Cu" "B.Mask")
			(net 248 "/Edge connector/RST_PLTRST_BUF_N")
			(pinfunction "A51")
			(pintype "passive")
		)
		(pad "A52" smd rect
			(at 20.1 -0.2)
			(size 0.38 1.72)
			(layers "B.Cu" "B.Mask")
			(net 249 "/Edge connector/SPARE1")
			(pinfunction "A52")
			(pintype "passive")
		)
		(pad "A53" smd rect
			(at 20.7 -0.2)
			(size 0.38 1.72)
			(layers "B.Cu" "B.Mask")
			(net 250 "/Edge connector/RoT_CPU_RST_N")
			(pinfunction "A53")
			(pintype "passive")
		)
		(pad "A54" smd rect
			(at 21.3 -0.2)
			(size 0.38 1.72)
			(layers "B.Cu" "B.Mask")
			(net 247 "/Edge connector/CHASI#")
			(pinfunction "A54")
			(pintype "passive")
		)
		(pad "A55" smd rect
			(at 21.9 -0.2)
			(size 0.38 1.72)
			(layers "B.Cu" "B.Mask")
			(net 246 "/Edge connector/SPARE0")
			(pinfunction "A55")
			(pintype "passive")
		)
		(pad "A56" smd rect
			(at 22.5 -0.2)
			(size 0.38 1.72)
			(layers "B.Cu" "B.Mask")
			(net 245 "/Edge connector/IRQ_N")
			(pinfunction "A56")
			(pintype "passive")
		)
		(pad "A57" smd rect
			(at 23.1 -0.2)
			(size 0.38 1.72)
			(layers "B.Cu" "B.Mask")
			(net 118 "PRSNT1_N")
			(pinfunction "A57")
			(pintype "passive")
		)
		(pad "A58" smd rect
			(at 23.7 0)
			(size 0.38 2.12)
			(layers "B.Cu" "B.Mask")
			(net 1 "GND")
			(pinfunction "A58")
			(pintype "passive")
		)
		(pad "A59" smd rect
			(at 24.3 -0.2)
			(size 0.38 1.72)
			(layers "B.Cu" "B.Mask")
			(net 361 "PCIE_HPM_RX[0]_P")
			(pinfunction "A59")
			(pintype "passive")
		)
		(pad "A60" smd rect
			(at 24.9 -0.2)
			(size 0.38 1.72)
			(layers "B.Cu" "B.Mask")
			(net 362 "PCIE_HPM_RX[0]_N")
			(pinfunction "A60")
			(pintype "passive")
		)
		(pad "A61" smd rect
			(at 25.5 0)
			(size 0.38 2.12)
			(layers "B.Cu" "B.Mask")
			(net 1 "GND")
			(pinfunction "A61")
			(pintype "passive")
		)
		(pad "A62" smd rect
			(at 26.1 -0.2)
			(size 0.38 1.72)
			(layers "B.Cu" "B.Mask")
			(net 363 "PCIE_HPM_RX[1]_P")
			(pinfunction "A62")
			(pintype "passive")
		)
		(pad "A63" smd rect
			(at 26.7 -0.2)
			(size 0.38 1.72)
			(layers "B.Cu" "B.Mask")
			(net 364 "PCIE_HPM_RX[1]_N")
			(pinfunction "A63")
			(pintype "passive")
		)
		(pad "A64" smd rect
			(at 27.3 0)
			(size 0.38 2.12)
			(layers "B.Cu" "B.Mask")
			(net 1 "GND")
			(pinfunction "A64")
			(pintype "passive")
		)
		(pad "A65" smd rect
			(at 27.9 -0.2)
			(size 0.38 1.72)
			(layers "B.Cu" "B.Mask")
			(net 365 "PCIE_HPM_RX[2]_P")
			(pinfunction "A65")
			(pintype "passive")
		)
		(pad "A66" smd rect
			(at 28.5 -0.2)
			(size 0.38 1.72)
			(layers "B.Cu" "B.Mask")
			(net 366 "PCIE_HPM_RX[2]_N")
			(pinfunction "A66")
			(pintype "passive")
		)
		(pad "A67" smd rect
			(at 29.1 0)
			(size 0.38 2.12)
			(layers "B.Cu" "B.Mask")
			(net 1 "GND")
			(pinfunction "A67")
			(pintype "passive")
		)
		(pad "A68" smd rect
			(at 29.7 -0.2)
			(size 0.38 1.72)
			(layers "B.Cu" "B.Mask")
			(net 367 "PCIE_HPM_RX[3]_P")
			(pinfunction "A68")
			(pintype "passive")
		)
		(pad "A69" smd rect
			(at 30.3 -0.2)
			(size 0.38 1.72)
			(layers "B.Cu" "B.Mask")
			(net 368 "PCIE_HPM_RX[3]_N")
			(pinfunction "A69")
			(pintype "passive")
		)
		(pad "A70" smd rect
			(at 30.9 0)
			(size 0.38 2.12)
			(layers "B.Cu" "B.Mask")
			(net 1 "GND")
			(pinfunction "A70")
			(pintype "passive")
		)
		(pad "B1" smd rect
			(at -18.205 -0.2)
			(size 0.38 1.72)
			(layers "F.Cu" "F.Mask")
			(net 584 "ESPI_CLK_1V8")
			(pinfunction "B1")
			(pintype "passive")
		)
		(pad "B2" smd rect
			(at -17.6 -0.2)
			(size 0.38 1.72)
			(layers "F.Cu" "F.Mask")
			(net 583 "ESPI_CS0_N_1V8")
			(pinfunction "B2")
			(pintype "passive")
		)
		(pad "B3" smd rect
			(at -17 -0.2)
			(size 0.38 1.72)
			(layers "F.Cu" "F.Mask")
			(net 582 "ESPI_ALERT_N_1V8")
			(pinfunction "B3")
			(pintype "passive")
		)
		(pad "B4" smd rect
			(at -16.4 -0.2)
			(size 0.38 1.72)
			(layers "F.Cu" "F.Mask")
			(net 581 "ESPI_RESET_N_1V8")
			(pinfunction "B4")
			(pintype "passive")
		)
		(pad "B5" smd rect
			(at -15.8 -0.2)
			(size 0.38 1.72)
			(layers "F.Cu" "F.Mask")
			(net 580 "ESPI_IO0_1V8")
			(pinfunction "B5")
			(pintype "passive")
		)
		(pad "B6" smd rect
			(at -15.2 -0.2)
			(size 0.38 1.72)
			(layers "F.Cu" "F.Mask")
			(net 579 "ESPI_IO1_1V8")
			(pinfunction "B6")
			(pintype "passive")
		)
		(pad "B7" smd rect
			(at -14.6 -0.2)
			(size 0.38 1.72)
			(layers "F.Cu" "F.Mask")
			(net 578 "ESPI_IO2_1V8")
			(pinfunction "B7")
			(pintype "passive")
		)
		(pad "B8" smd rect
			(at -14 -0.2)
			(size 0.38 1.72)
			(layers "F.Cu" "F.Mask")
			(net 577 "ESPI_IO3_1V8")
			(pinfunction "B8")
			(pintype "passive")
		)
		(pad "B9" smd rect
			(at -13.4 -0.2)
			(size 0.38 1.72)
			(layers "F.Cu" "F.Mask")
			(net 576 "ESPI_CS1_N_1V8")
			(pinfunction "B9")
			(pintype "passive")
		)
		(pad "B10" smd rect
			(at -12.8 0)
			(size 0.38 2.12)
			(layers "F.Cu" "F.Mask")
			(net 1 "GND")
			(pinfunction "B10")
			(pintype "passive")
		)
		(pad "B11" smd rect
			(at -12.2 -0.2)
			(size 0.38 1.72)
			(layers "F.Cu" "F.Mask")
			(net 70 "QSPI0_CLK")
			(pinfunction "B11")
			(pintype "passive")
		)
		(pad "B12" smd rect
			(at -11.6 -0.2)
			(size 0.38 1.72)
			(layers "F.Cu" "F.Mask")
			(net 71 "QSPI0_CS0_N")
			(pinfunction "B12")
			(pintype "passive")
		)
		(pad "B13" smd rect
			(at -11 -0.2)
			(size 0.38 1.72)
			(layers "F.Cu" "F.Mask")
			(net 72 "QSPI0_D0")
			(pinfunction "B13")
			(pintype "passive")
		)
		(pad "B14" smd rect
			(at -10.4 -0.2)
			(size 0.38 1.72)
			(layers "F.Cu" "F.Mask")
			(net 73 "QSPI0_D1")
			(pinfunction "B14")
			(pintype "passive")
		)
		(pad "B15" smd rect
			(at -9.8 -0.2)
			(size 0.38 1.72)
			(layers "F.Cu" "F.Mask")
			(net 74 "QSPI0_D2")
			(pinfunction "B15")
			(pintype "passive")
		)
		(pad "B16" smd rect
			(at -9.2 -0.2)
			(size 0.38 1.72)
			(layers "F.Cu" "F.Mask")
			(net 75 "QSPI0_D3")
			(pinfunction "B16")
			(pintype "passive")
		)
		(pad "B17" smd rect
			(at -8.6 0)
			(size 0.38 2.12)
			(layers "F.Cu" "F.Mask")
			(net 1 "GND")
			(pinfunction "B17")
			(pintype "passive")
		)
		(pad "B18" smd rect
			(at -8 -0.2)
			(size 0.38 1.72)
			(layers "F.Cu" "F.Mask")
			(net 76 "NCSI_CLK")
			(pinfunction "B18")
			(pintype "passive")
		)
		(pad "B19" smd rect
			(at -7.4 -0.2)
			(size 0.38 1.72)
			(layers "F.Cu" "F.Mask")
			(net 77 "NCSI_CRS_DV")
			(pinfunction "B19")
			(pintype "passive")
		)
		(pad "B20" smd rect
			(at -6.8 -0.2)
			(size 0.38 1.72)
			(layers "F.Cu" "F.Mask")
			(net 78 "NCSI_TXEN")
			(pinfunction "B20")
			(pintype "passive")
		)
		(pad "B21" smd rect
			(at -6.2 -0.2)
			(size 0.38 1.72)
			(layers "F.Cu" "F.Mask")
			(net 79 "NCSI_TXD0")
			(pinfunction "B21")
			(pintype "passive")
		)
		(pad "B22" smd rect
			(at -5.6 -0.2)
			(size 0.38 1.72)
			(layers "F.Cu" "F.Mask")
			(net 80 "NCSI_TXD1")
			(pinfunction "B22")
			(pintype "passive")
		)
		(pad "B23" smd rect
			(at -5 -0.2)
			(size 0.38 1.72)
			(layers "F.Cu" "F.Mask")
			(net 81 "NCSI_RXER")
			(pinfunction "B23")
			(pintype "passive")
		)
		(pad "B24" smd rect
			(at -4.4 -0.2)
			(size 0.38 1.72)
			(layers "F.Cu" "F.Mask")
			(net 82 "NCSI_RXD0")
			(pinfunction "B24")
			(pintype "passive")
		)
		(pad "B25" smd rect
			(at -3.8 -0.2)
			(size 0.38 1.72)
			(layers "F.Cu" "F.Mask")
			(net 83 "NCSI_RXD1")
			(pinfunction "B25")
			(pintype "passive")
		)
		(pad "B26" smd rect
			(at -3.2 0)
			(size 0.38 2.12)
			(layers "F.Cu" "F.Mask")
			(net 1 "GND")
			(pinfunction "B26")
			(pintype "passive")
		)
		(pad "B27" smd rect
			(at -2.6 -0.2)
			(size 0.38 1.72)
			(layers "F.Cu" "F.Mask")
			(net 84 "PECI_BMC")
			(pinfunction "B27")
			(pintype "passive")
		)
		(pad "B28" smd rect
			(at -2 -0.2)
			(size 0.38 1.72)
			(layers "F.Cu" "F.Mask")
			(net 85 "PVCCIO_PECI")
			(pinfunction "B28")
			(pintype "passive")
		)
		(pad "B29" smd rect
			(at 2.01 -0.2)
			(size 0.38 1.72)
			(layers "F.Cu" "F.Mask")
			(net 86 "SGPIO0_DO")
			(pinfunction "B29")
			(pintype "passive")
		)
		(pad "B30" smd rect
			(at 2.6 -0.2)
			(size 0.38 1.72)
			(layers "F.Cu" "F.Mask")
			(net 87 "SGPIO0_CLK")
			(pinfunction "B30")
			(pintype "passive")
		)
		(pad "B31" smd rect
			(at 3.2 -0.2)
			(size 0.38 1.72)
			(layers "F.Cu" "F.Mask")
			(net 88 "SGPIO0_DI")
			(pinfunction "B31")
			(pintype "passive")
		)
		(pad "B32" smd rect
			(at 3.8 -0.2)
			(size 0.38 1.72)
			(layers "F.Cu" "F.Mask")
			(net 89 "SGPIO0_LD")
			(pinfunction "B32")
			(pintype "passive")
		)
		(pad "B33" smd rect
			(at 4.4 0)
			(size 0.38 2.12)
			(layers "F.Cu" "F.Mask")
			(net 1 "GND")
			(pinfunction "B33")
			(pintype "passive")
		)
		(pad "B34" smd rect
			(at 5 -0.2)
			(size 0.38 1.72)
			(layers "F.Cu" "F.Mask")
			(net 90 "SGPIO1_DO")
			(pinfunction "B34")
			(pintype "passive")
		)
		(pad "B35" smd rect
			(at 5.6 -0.2)
			(size 0.38 1.72)
			(layers "F.Cu" "F.Mask")
			(net 694 "Net-(J9-PadB35)")
			(pinfunction "B35")
			(pintype "passive")
		)
		(pad "B36" smd rect
			(at 6.2 -0.2)
			(size 0.38 1.72)
			(layers "F.Cu" "F.Mask")
			(net 92 "SGPIO1_DI")
			(pinfunction "B36")
			(pintype "passive")
		)
		(pad "B37" smd rect
			(at 6.8 -0.2)
			(size 0.38 1.72)
			(layers "F.Cu" "F.Mask")
			(net 93 "SGPIO1_LD")
			(pinfunction "B37")
			(pintype "passive")
		)
		(pad "B38" smd rect
			(at 7.4 0)
			(size 0.38 2.12)
			(layers "F.Cu" "F.Mask")
			(net 1 "GND")
			(pinfunction "B38")
			(pintype "passive")
		)
		(pad "B39" smd rect
			(at 8 -0.2)
			(size 0.38 1.72)
			(layers "F.Cu" "F.Mask")
			(net 94 "SGPIO_RESET_N")
			(pinfunction "B39")
			(pintype "passive")
		)
		(pad "B40" smd rect
			(at 8.6 -0.2)
			(size 0.38 1.72)
			(layers "F.Cu" "F.Mask")
			(net 95 "SGPIO_INTR_N")
			(pinfunction "B40")
			(pintype "passive")
		)
		(pad "B41" smd rect
			(at 9.2 -0.2)
			(size 0.38 1.72)
			(layers "F.Cu" "F.Mask")
			(net 287 "3V0_BAT")
			(pinfunction "B41")
			(pintype "passive")
		)
		(pad "B42" smd rect
			(at 9.8 -0.2)
			(size 0.38 1.72)
			(layers "F.Cu" "F.Mask")
			(net 96 "QSPI0_CS1_N")
			(pinfunction "B42")
			(pintype "passive")
		)
		(pad "B43" smd rect
			(at 14.715 -0.2)
			(size 0.38 1.72)
			(layers "F.Cu" "F.Mask")
			(net 97 "QSPI1_CLK")
			(pinfunction "B43")
			(pintype "passive")
		)
		(pad "B44" smd rect
			(at 15.3 -0.2)
			(size 0.38 1.72)
			(layers "F.Cu" "F.Mask")
			(net 98 "QSPI1_CS0_N")
			(pinfunction "B44")
			(pintype "passive")
		)
		(pad "B45" smd rect
			(at 15.9 -0.2)
			(size 0.38 1.72)
			(layers "F.Cu" "F.Mask")
			(net 99 "QSPI1_D0")
			(pinfunction "B45")
			(pintype "passive")
		)
		(pad "B46" smd rect
			(at 16.5 -0.2)
			(size 0.38 1.72)
			(layers "F.Cu" "F.Mask")
			(net 100 "QSPI1_D1")
			(pinfunction "B46")
			(pintype "passive")
		)
		(pad "B47" smd rect
			(at 17.1 -0.2)
			(size 0.38 1.72)
			(layers "F.Cu" "F.Mask")
			(net 101 "QSPI1_D2")
			(pinfunction "B47")
			(pintype "passive")
		)
		(pad "B48" smd rect
			(at 17.7 -0.2)
			(size 0.38 1.72)
			(layers "F.Cu" "F.Mask")
			(net 102 "QSPI1_D3")
			(pinfunction "B48")
			(pintype "passive")
		)
		(pad "B49" smd rect
			(at 18.3 0)
			(size 0.38 2.12)
			(layers "F.Cu" "F.Mask")
			(net 1 "GND")
			(pinfunction "B49")
			(pintype "passive")
		)
		(pad "B50" smd rect
			(at 18.9 -0.2)
			(size 0.38 1.72)
			(layers "F.Cu" "F.Mask")
			(net 383 "USB2_D_P")
			(pinfunction "B50")
			(pintype "passive")
		)
		(pad "B51" smd rect
			(at 19.5 -0.2)
			(size 0.38 1.72)
			(layers "F.Cu" "F.Mask")
			(net 384 "USB2_D_N")
			(pinfunction "B51")
			(pintype "passive")
		)
		(pad "B52" smd rect
			(at 20.1 0)
			(size 0.38 2.12)
			(layers "F.Cu" "F.Mask")
			(net 1 "GND")
			(pinfunction "B52")
			(pintype "passive")
		)
		(pad "B53" smd rect
			(at 20.7 -0.2)
			(size 0.38 1.72)
			(layers "F.Cu" "F.Mask")
			(net 385 "USB1_D_P")
			(pinfunction "B53")
			(pintype "passive")
		)
		(pad "B54" smd rect
			(at 21.3 -0.2)
			(size 0.38 1.72)
			(layers "F.Cu" "F.Mask")
			(net 386 "USB1_D_N")
			(pinfunction "B54")
			(pintype "passive")
		)
		(pad "B55" smd rect
			(at 21.9 0)
			(size 0.38 2.12)
			(layers "F.Cu" "F.Mask")
			(net 1 "GND")
			(pinfunction "B55")
			(pintype "passive")
		)
		(pad "B56" smd rect
			(at 22.5 -0.2)
			(size 0.38 1.72)
			(layers "F.Cu" "F.Mask")
			(net 359 "PCIE_HPM_CLK_P")
			(pinfunction "B56")
			(pintype "passive")
		)
		(pad "B57" smd rect
			(at 23.1 -0.2)
			(size 0.38 1.72)
			(layers "F.Cu" "F.Mask")
			(net 360 "PCIE_HPM_CLK_N")
			(pinfunction "B57")
			(pintype "passive")
		)
		(pad "B58" smd rect
			(at 23.7 0)
			(size 0.38 2.12)
			(layers "F.Cu" "F.Mask")
			(net 1 "GND")
			(pinfunction "B58")
			(pintype "passive")
		)
		(pad "B59" smd rect
			(at 24.3 -0.2)
			(size 0.38 1.72)
			(layers "F.Cu" "F.Mask")
			(net 351 "PCIE_HPM_TX[0]_P")
			(pinfunction "B59")
			(pintype "passive")
		)
		(pad "B60" smd rect
			(at 24.9 -0.2)
			(size 0.38 1.72)
			(layers "F.Cu" "F.Mask")
			(net 353 "PCIE_HPM_TX[0]_N")
			(pinfunction "B60")
			(pintype "passive")
		)
		(pad "B61" smd rect
			(at 25.5 0)
			(size 0.38 2.12)
			(layers "F.Cu" "F.Mask")
			(net 1 "GND")
			(pinfunction "B61")
			(pintype "passive")
		)
		(pad "B62" smd rect
			(at 26.1 -0.2)
			(size 0.38 1.72)
			(layers "F.Cu" "F.Mask")
			(net 352 "PCIE_HPM_TX[1]_P")
			(pinfunction "B62")
			(pintype "passive")
		)
		(pad "B63" smd rect
			(at 26.7 -0.2)
			(size 0.38 1.72)
			(layers "F.Cu" "F.Mask")
			(net 354 "PCIE_HPM_TX[1]_N")
			(pinfunction "B63")
			(pintype "passive")
		)
		(pad "B64" smd rect
			(at 27.3 0)
			(size 0.38 2.12)
			(layers "F.Cu" "F.Mask")
			(net 1 "GND")
			(pinfunction "B64")
			(pintype "passive")
		)
		(pad "B65" smd rect
			(at 27.9 -0.2)
			(size 0.38 1.72)
			(layers "F.Cu" "F.Mask")
			(net 355 "PCIE_HPM_TX[2]_P")
			(pinfunction "B65")
			(pintype "passive")
		)
		(pad "B66" smd rect
			(at 28.5 -0.2)
			(size 0.38 1.72)
			(layers "F.Cu" "F.Mask")
			(net 357 "PCIE_HPM_TX[2]_N")
			(pinfunction "B66")
			(pintype "passive")
		)
		(pad "B67" smd rect
			(at 29.1 0)
			(size 0.38 2.12)
			(layers "F.Cu" "F.Mask")
			(net 1 "GND")
			(pinfunction "B67")
			(pintype "passive")
		)
		(pad "B68" smd rect
			(at 29.7 -0.2)
			(size 0.38 1.72)
			(layers "F.Cu" "F.Mask")
			(net 356 "PCIE_HPM_TX[3]_P")
			(pinfunction "B68")
			(pintype "passive")
		)
		(pad "B69" smd rect
			(at 30.3 -0.2)
			(size 0.38 1.72)
			(layers "F.Cu" "F.Mask")
			(net 358 "PCIE_HPM_TX[3]_N")
			(pinfunction "B69")
			(pintype "passive")
		)
		(pad "B70" smd rect
			(at 30.9 0)
			(size 0.38 2.12)
			(layers "F.Cu" "F.Mask")
			(net 1 "GND")
			(pinfunction "B70")
			(pintype "passive")
		)
		(pad "OA1" smd rect
			(at -30.4 -0.2)
			(size 0.38 1.72)
			(layers "B.Cu" "B.Mask")
			(net 59 "P12V_AUX")
			(pinfunction "OA1")
			(pintype "passive")
		)
		(pad "OA2" smd rect
			(at -29.8 -0.2)
			(size 0.38 1.72)
			(layers "B.Cu" "B.Mask")
			(net 59 "P12V_AUX")
			(pinfunction "OA2")
			(pintype "passive")
		)
		(pad "OA3" smd rect
			(at -29.2 0)
			(size 0.38 2.12)
			(layers "B.Cu" "B.Mask")
			(net 1 "GND")
			(pinfunction "OA3")
			(pintype "passive")
		)
		(pad "OA4" smd rect
			(at -28.6 0)
			(size 0.38 2.12)
			(layers "B.Cu" "B.Mask")
			(net 1 "GND")
			(pinfunction "OA4")
			(pintype "passive")
		)
		(pad "OA5" smd rect
			(at -28 -0.2)
			(size 0.38 1.72)
			(layers "B.Cu" "B.Mask")
			(net 49 "I3C[0]_SCL")
			(pinfunction "OA5")
			(pintype "passive")
		)
		(pad "OA6" smd rect
			(at -27.4 -0.2)
			(size 0.38 1.72)
			(layers "B.Cu" "B.Mask")
			(net 48 "I3C[0]_SDA")
			(pinfunction "OA6")
			(pintype "passive")
		)
		(pad "OA7" smd rect
			(at -26.8 -0.2)
			(size 0.38 1.72)
			(layers "B.Cu" "B.Mask")
			(net 52 "I3C[1]_SCL")
			(pinfunction "OA7")
			(pintype "passive")
		)
		(pad "OA8" smd rect
			(at -26.2 -0.2)
			(size 0.38 1.72)
			(layers "B.Cu" "B.Mask")
			(net 51 "I3C[1]_SDA")
			(pinfunction "OA8")
			(pintype "passive")
		)
		(pad "OA9" smd rect
			(at -25.6 -0.2)
			(size 0.38 1.72)
			(layers "B.Cu" "B.Mask")
			(net 47 "I3C[2]_SCL")
			(pinfunction "OA9")
			(pintype "passive")
		)
		(pad "OA10" smd rect
			(at -25 -0.2)
			(size 0.38 1.72)
			(layers "B.Cu" "B.Mask")
			(net 50 "I3C[2]_SDA")
			(pinfunction "OA10")
			(pintype "passive")
		)
		(pad "OA11" smd rect
			(at -24.4 -0.2)
			(size 0.38 1.72)
			(layers "B.Cu" "B.Mask")
			(net 54 "I3C[3]_SCL")
			(pinfunction "OA11")
			(pintype "passive")
		)
		(pad "OA12" smd rect
			(at -23.8 -0.2)
			(size 0.38 1.72)
			(layers "B.Cu" "B.Mask")
			(net 53 "I3C[3]_SDA")
			(pinfunction "OA12")
			(pintype "passive")
		)
		(pad "OA13" smd rect
			(at -23.2 0)
			(size 0.38 2.12)
			(layers "B.Cu" "B.Mask")
			(net 1 "GND")
			(pinfunction "OA13")
			(pintype "passive")
		)
		(pad "OA14" smd rect
			(at -22.6 -0.2)
			(size 0.38 1.72)
			(layers "B.Cu" "B.Mask")
			(net 244 "/Edge connector/VIRTUAL_RESEAT")
			(pinfunction "OA14")
			(pintype "passive")
		)
		(pad "OB1" smd rect
			(at -30.4 -0.2)
			(size 0.38 1.72)
			(layers "F.Cu" "F.Mask")
			(net 59 "P12V_AUX")
			(pinfunction "OB1")
			(pintype "passive")
		)
		(pad "OB2" smd rect
			(at -29.8 -0.2)
			(size 0.38 1.72)
			(layers "F.Cu" "F.Mask")
			(net 59 "P12V_AUX")
			(pinfunction "OB2")
			(pintype "passive")
		)
		(pad "OB3" smd rect
			(at -29.2 -0.2)
			(size 0.38 1.72)
			(layers "F.Cu" "F.Mask")
			(net 243 "/Edge connector/PRSNT0_N")
			(pinfunction "OB3")
			(pintype "passive")
		)
		(pad "OB4" smd rect
			(at -28.6 0)
			(size 0.38 2.12)
			(layers "F.Cu" "F.Mask")
			(net 1 "GND")
			(pinfunction "OB4")
			(pintype "passive")
		)
		(pad "OB5" smd rect
			(at -28 -0.2)
			(size 0.38 1.72)
			(layers "F.Cu" "F.Mask")
			(net 40 "UART1_SCM_TX")
			(pinfunction "OB5")
			(pintype "passive")
		)
		(pad "OB6" smd rect
			(at -27.4 -0.2)
			(size 0.38 1.72)
			(layers "F.Cu" "F.Mask")
			(net 33 "UART1_SCM_RX")
			(pinfunction "OB6")
			(pintype "passive")
		)
		(pad "OB7" smd rect
			(at -26.8 0)
			(size 0.38 2.12)
			(layers "F.Cu" "F.Mask")
			(net 1 "GND")
			(pinfunction "OB7")
			(pintype "passive")
		)
		(pad "OB8" smd rect
			(at -26.2 -0.2)
			(size 0.38 1.72)
			(layers "F.Cu" "F.Mask")
			(net 35 "UART0_SCM_TX")
			(pinfunction "OB8")
			(pintype "passive")
		)
		(pad "OB9" smd rect
			(at -25.6 -0.2)
			(size 0.38 1.72)
			(layers "F.Cu" "F.Mask")
			(net 39 "UART0_SCM_RX")
			(pinfunction "OB9")
			(pintype "passive")
		)
		(pad "OB10" smd rect
			(at -25 0)
			(size 0.38 2.12)
			(layers "F.Cu" "F.Mask")
			(net 1 "GND")
			(pinfunction "OB10")
			(pintype "passive")
		)
		(pad "OB11" smd rect
			(at -24.4 -0.2)
			(size 0.38 1.72)
			(layers "F.Cu" "F.Mask")
			(net 56 "SPI0_CLK")
			(pinfunction "OB11")
			(pintype "passive")
		)
		(pad "OB12" smd rect
			(at -23.8 -0.2)
			(size 0.38 1.72)
			(layers "F.Cu" "F.Mask")
			(net 55 "SPI0_CS_N")
			(pinfunction "OB12")
			(pintype "passive")
		)
		(pad "OB13" smd rect
			(at -23.2 -0.2)
			(size 0.38 1.72)
			(layers "F.Cu" "F.Mask")
			(net 57 "SPI0_MOSI")
			(pinfunction "OB13")
			(pintype "passive")
		)
		(pad "OB14" smd rect
			(at -22.6 -0.2)
			(size 0.38 1.72)
			(layers "F.Cu" "F.Mask")
			(net 58 "SPI0_MISO")
			(pinfunction "OB14")
			(pintype "passive")
		)
	)
	(footprint "antmicro-footprints:VQFN-20_1EP_4.5x2.5mm_P0.5mm"
		(layer "F.Cu")
		(at 86.64 166.015)
		(property "Reference" "U21"
			(at 0.66 -1.815 0)
			(layer "F.SilkS")
			(effects
				(font
					(size 0.7 0.7)
					(thickness 0.15)
				)
				(justify left bottom)
			)
		)
		(property "Value" "LSF0108RKSR"
			(at 0.689 2.959 0)
			(layer "F.Fab")
			(effects
				(font
					(size 0.7 0.7)
					(thickness 0.15)
				)
				(justify left bottom)
			)
		)
		(property "Datasheet" "https://www.ti.com/lit/ds/symlink/lsf0108.pdf?ts=1686550470995&ref_url=https%253A%252F%252Fwww.ti.com%252Fproduct%252FLSF0108%252Fpart-details%252FLSF0108RKSR"
			(at 0 0 0)
			(layer "F.Fab")
			(hide yes)
			(effects
				(font
					(size 1.27 1.27)
					(thickness 0.15)
				)
			)
		)
		(property "Description" "Voltage Level Translator, 8 Input, 1.5 ns, 0 V to 5 V, VQFN-20"
			(at 0 0 0)
			(layer "F.Fab")
			(hide yes)
			(effects
				(font
					(size 1.27 1.27)
					(thickness 0.15)
				)
			)
		)
		(property "Author" "Antmicro"
			(at 0 0 0)
			(layer "F.Fab")
			(hide yes)
			(effects
				(font
					(size 1 1)
					(thickness 0.15)
				)
			)
		)
		(property "License" "Apache-2.0"
			(at 0 0 0)
			(layer "F.Fab")
			(hide yes)
			(effects
				(font
					(size 1 1)
					(thickness 0.15)
				)
			)
		)
		(property "MPN" "LSF0108RKSR"
			(at 0 0 0)
			(layer "F.Fab")
			(hide yes)
			(effects
				(font
					(size 1 1)
					(thickness 0.15)
				)
			)
		)
		(property "Manufacturer" "Texas Instruments"
			(at 0 0 0)
			(layer "F.Fab")
			(hide yes)
			(effects
				(font
					(size 1 1)
					(thickness 0.15)
				)
			)
		)
		(sheetname "/Interfaces/")
		(sheetfile "interfaces.kicad_sch")
		(attr smd exclude_from_pos_files exclude_from_bom dnp)
		(fp_line
			(start -2.25 -1.25)
			(end -2.25 -0.5)
			(stroke
				(width 0.15)
				(type solid)
			)
			(layer "F.SilkS")
		)
		(fp_line
			(start -2.249 1.25)
			(end -2 1.25)
			(stroke
				(width 0.15)
				(type solid)
			)
			(layer "F.SilkS")
		)
		(fp_line
			(start -2.001 -1.25)
			(end -2.25 -1.25)
			(stroke
				(width 0.15)
				(type solid)
			)
			(layer "F.SilkS")
		)
		(fp_line
			(start 2.249 -1.25)
			(end 2 -1.25)
			(stroke
				(width 0.15)
				(type solid)
			)
			(layer "F.SilkS")
		)
		(fp_line
			(start 2.249 -1.25)
			(end 2.249 -0.5)
			(stroke
				(width 0.15)
				(type solid)
			)
			(layer "F.SilkS")
		)
		(fp_line
			(start 2.249 1.249)
			(end 2 1.249)
			(stroke
				(width 0.15)
				(type solid)
			)
			(layer "F.SilkS")
		)
		(fp_line
			(start 2.249 1.249)
			(end 2.249 0.5)
			(stroke
				(width 0.15)
				(type solid)
			)
			(layer "F.SilkS")
		)
		(fp_rect
			(start -2.711 -1.71)
			(end 2.708 1.709)
			(stroke
				(width 0.05)
				(type solid)
			)
			(fill no)
			(layer "F.CrtYd")
		)
		(fp_line
			(start -2.25 1.249)
			(end -2.25 -1.25)
			(stroke
				(width 0.15)
				(type solid)
			)
			(layer "F.Fab")
		)
		(fp_line
			(start 2.249 -1.25)
			(end -2.25 -1.25)
			(stroke
				(width 0.15)
				(type solid)
			)
			(layer "F.Fab")
		)
		(fp_line
			(start 2.249 1.249)
			(end -2.25 1.249)
			(stroke
				(width 0.15)
				(type solid)
			)
			(layer "F.Fab")
		)
		(fp_line
			(start 2.249 1.249)
			(end 2.249 -1.25)
			(stroke
				(width 0.15)
				(type solid)
			)
			(layer "F.Fab")
		)
		(pad "" smd roundrect
			(at -0.76 0)
			(size 1.31 0.95)
			(layers "F.Paste")
			(roundrect_rratio 0.05)
		)
		(pad "" smd roundrect
			(at 0.76 0)
			(size 1.31 0.95)
			(layers "F.Paste")
			(roundrect_rratio 0.05)
		)
		(pad "1" smd roundrect
			(at -2.15 0.25 90)
			(size 0.25 0.8)
			(layers "F.Cu" "F.Mask" "F.Paste")
			(roundrect_rratio 0.2)
			(net 1 "GND")
			(pinfunction "GND")
			(pintype "power_in")
		)
		(pad "2" smd roundrect
			(at -1.75 1.15)
			(size 0.25 0.8)
			(layers "F.Cu" "F.Mask" "F.Paste")
			(roundrect_rratio 0.2)
			(net 5 "VCC1V8")
			(pinfunction "VREF_{A}")
			(pintype "power_in")
		)
		(pad "3" smd roundrect
			(at -1.25 1.15)
			(size 0.25 0.8)
			(layers "F.Cu" "F.Mask" "F.Paste")
			(roundrect_rratio 0.2)
			(net 584 "ESPI_CLK_1V8")
			(pinfunction "A1")
			(pintype "bidirectional")
		)
		(pad "4" smd roundrect
			(at -0.75 1.15)
			(size 0.25 0.8)
			(layers "F.Cu" "F.Mask" "F.Paste")
			(roundrect_rratio 0.2)
			(net 583 "ESPI_CS0_N_1V8")
			(pinfunction "A2")
			(pintype "bidirectional")
		)
		(pad "5" smd roundrect
			(at -0.25 1.15)
			(size 0.25 0.8)
			(layers "F.Cu" "F.Mask" "F.Paste")
			(roundrect_rratio 0.2)
			(net 582 "ESPI_ALERT_N_1V8")
			(pinfunction "A3")
			(pintype "bidirectional")
		)
		(pad "6" smd roundrect
			(at 0.25 1.15)
			(size 0.25 0.8)
			(layers "F.Cu" "F.Mask" "F.Paste")
			(roundrect_rratio 0.2)
			(net 581 "ESPI_RESET_N_1V8")
			(pinfunction "A4")
			(pintype "bidirectional")
		)
		(pad "7" smd roundrect
			(at 0.75 1.15)
			(size 0.25 0.8)
			(layers "F.Cu" "F.Mask" "F.Paste")
			(roundrect_rratio 0.2)
			(net 580 "ESPI_IO0_1V8")
			(pinfunction "A5")
			(pintype "bidirectional")
		)
		(pad "8" smd roundrect
			(at 1.25 1.15)
			(size 0.25 0.8)
			(layers "F.Cu" "F.Mask" "F.Paste")
			(roundrect_rratio 0.2)
			(net 579 "ESPI_IO1_1V8")
			(pinfunction "A6")
			(pintype "bidirectional")
		)
		(pad "9" smd roundrect
			(at 1.75 1.15)
			(size 0.25 0.8)
			(layers "F.Cu" "F.Mask" "F.Paste")
			(roundrect_rratio 0.2)
			(net 578 "ESPI_IO2_1V8")
			(pinfunction "A7")
			(pintype "bidirectional")
		)
		(pad "10" smd roundrect
			(at 2.15 0.25 90)
			(size 0.25 0.8)
			(layers "F.Cu" "F.Mask" "F.Paste")
			(roundrect_rratio 0.2)
			(net 577 "ESPI_IO3_1V8")
			(pinfunction "A8")
			(pintype "bidirectional")
		)
		(pad "11" smd roundrect
			(at 2.15 -0.25 90)
			(size 0.25 0.8)
			(layers "F.Cu" "F.Mask" "F.Paste")
			(roundrect_rratio 0.2)
			(net 68 "ESPI_IO3")
			(pinfunction "B8")
			(pintype "bidirectional")
		)
		(pad "12" smd roundrect
			(at 1.75 -1.15)
			(size 0.25 0.8)
			(layers "F.Cu" "F.Mask" "F.Paste")
			(roundrect_rratio 0.2)
			(net 67 "ESPI_IO2")
			(pinfunction "B7")
			(pintype "bidirectional")
		)
		(pad "13" smd roundrect
			(at 1.25 -1.15)
			(size 0.25 0.8)
			(layers "F.Cu" "F.Mask" "F.Paste")
			(roundrect_rratio 0.2)
			(net 66 "ESPI_IO1")
			(pinfunction "B6")
			(pintype "bidirectional")
		)
		(pad "14" smd roundrect
			(at 0.75 -1.15)
			(size 0.25 0.8)
			(layers "F.Cu" "F.Mask" "F.Paste")
			(roundrect_rratio 0.2)
			(net 65 "ESPI_IO0")
			(pinfunction "B5")
			(pintype "bidirectional")
		)
		(pad "15" smd roundrect
			(at 0.25 -1.15)
			(size 0.25 0.8)
			(layers "F.Cu" "F.Mask" "F.Paste")
			(roundrect_rratio 0.2)
			(net 64 "ESPI_RESET_N")
			(pinfunction "B4")
			(pintype "bidirectional")
		)
		(pad "16" smd roundrect
			(at -0.25 -1.15)
			(size 0.25 0.8)
			(layers "F.Cu" "F.Mask" "F.Paste")
			(roundrect_rratio 0.2)
			(net 63 "ESPI_ALERT_N")
			(pinfunction "B3")
			(pintype "bidirectional")
		)
		(pad "17" smd roundrect
			(at -0.75 -1.15)
			(size 0.25 0.8)
			(layers "F.Cu" "F.Mask" "F.Paste")
			(roundrect_rratio 0.2)
			(net 62 "ESPI_CS0_N")
			(pinfunction "B2")
			(pintype "bidirectional")
		)
		(pad "18" smd roundrect
			(at -1.25 -1.15)
			(size 0.25 0.8)
			(layers "F.Cu" "F.Mask" "F.Paste")
			(roundrect_rratio 0.2)
			(net 61 "ESPI_CLK")
			(pinfunction "B1")
			(pintype "bidirectional")
		)
		(pad "19" smd roundrect
			(at -1.75 -1.15)
			(size 0.25 0.8)
			(layers "F.Cu" "F.Mask" "F.Paste")
			(roundrect_rratio 0.2)
			(net 2 "VCC3V3")
			(pinfunction "VREF_{B}")
			(pintype "power_in")
		)
		(pad "20" smd roundrect
			(at -2.15 -0.25 90)
			(size 0.25 0.8)
			(layers "F.Cu" "F.Mask" "F.Paste")
			(roundrect_rratio 0.2)
			(net 312 "Net-(U21-EN)")
			(pinfunction "EN")
			(pintype "input")
		)
		(pad "21" smd roundrect
			(at 0 0)
			(size 3 1)
			(layers "F.Cu" "F.Mask")
			(roundrect_rratio 0.05)
			(net 1 "GND")
			(pinfunction "EP")
			(pintype "power_in")
		)
	)
	(footprint "antmicro-footprints:USON-6_1.45x1.0mm_P0.5mm_Texas_DRY6"
		(layer "F.Cu")
		(at 91.059 163.363 180)
		(property "Reference" "U22"
			(at 1.359 1.463 0)
			(layer "F.SilkS")
			(effects
				(font
					(size 0.7 0.7)
					(thickness 0.15)
				)
				(justify left bottom)
			)
		)
		(property "Value" "LSF0101DRYR"
			(at 7.416 2.156 180)
			(layer "F.Fab")
			(effects
				(font
					(size 0.7 0.7)
					(thickness 0.15)
				)
				(justify left bottom)
			)
		)
		(property "Datasheet" "https://www.ti.com/lit/ds/symlink/lsf0101.pdf?ts=1686656250822&ref_url=https%253A%252F%252Fwww.ti.com%252Fproduct%252FLSF0101%252Fpart-details%252FLSF0101DRYR"
			(at 0 0 180)
			(layer "F.Fab")
			(hide yes)
			(effects
				(font
					(size 1.27 1.27)
					(thickness 0.15)
				)
			)
		)
		(property "Description" "Voltage Level Translator, 1 Input, 1.5 ns, 0 V to 5 V, SON-6"
			(at 0 0 180)
			(layer "F.Fab")
			(hide yes)
			(effects
				(font
					(size 1.27 1.27)
					(thickness 0.15)
				)
			)
		)
		(property "Author" "Antmicro"
			(at 182.118 326.726 0)
			(layer "F.Fab")
			(hide yes)
			(effects
				(font
					(size 1 1)
					(thickness 0.15)
				)
			)
		)
		(property "License" "Apache-2.0"
			(at 182.118 326.726 0)
			(layer "F.Fab")
			(hide yes)
			(effects
				(font
					(size 1 1)
					(thickness 0.15)
				)
			)
		)
		(property "MPN" "LSF0101DRYR"
			(at 182.118 326.726 0)
			(layer "F.Fab")
			(hide yes)
			(effects
				(font
					(size 1 1)
					(thickness 0.15)
				)
			)
		)
		(property "Manufacturer" "Texas Instruments"
			(at 182.118 326.726 0)
			(layer "F.Fab")
			(hide yes)
			(effects
				(font
					(size 1 1)
					(thickness 0.15)
				)
			)
		)
		(sheetname "/Interfaces/")
		(sheetfile "interfaces.kicad_sch")
		(attr smd)
		(fp_line
			(start -0.211 1.275)
			(end 0.79 1.275)
			(stroke
				(width 0.15)
				(type solid)
			)
			(layer "F.SilkS")
		)
		(fp_line
			(start -0.211 -0.275)
			(end 0.79 -0.275)
			(stroke
				(width 0.15)
				(type solid)
			)
			(layer "F.SilkS")
		)
		(fp_rect
			(start -0.411 -0.326)
			(end 0.99 1.325)
			(stroke
				(width 0.05)
				(type solid)
			)
			(fill no)
			(layer "F.CrtYd")
		)
		(fp_line
			(start 0.79 1.225)
			(end 0.79 -0.226)
			(stroke
				(width 0.15)
				(type solid)
			)
			(layer "F.Fab")
		)
		(fp_line
			(start -0.211 1.225)
			(end 0.79 1.225)
			(stroke
				(width 0.15)
				(type solid)
			)
			(layer "F.Fab")
		)
		(fp_line
			(start -0.211 -0.226)
			(end 0.79 -0.226)
			(stroke
				(width 0.15)
				(type solid)
			)
			(layer "F.Fab")
		)
		(fp_line
			(start -0.211 -0.226)
			(end -0.211 1.225)
			(stroke
				(width 0.15)
				(type solid)
			)
			(layer "F.Fab")
		)
		(fp_text user "."
			(at -0.5 -0.6 180)
			(layer "F.SilkS")
			(effects
				(font
					(size 1 1)
					(thickness 0.15)
				)
			)
		)
		(pad "1" smd roundrect
			(at 0 0 180)
			(size 0.42 0.3)
			(layers "F.Cu" "F.Mask" "F.Paste")
			(roundrect_rratio 0)
			(chamfer_ratio 0.3)
			(chamfer top_left)
			(net 1 "GND")
			(pinfunction "GND")
			(pintype "power_in")
		)
		(pad "2" smd rect
			(at -0.006 0.498 180)
			(size 0.41 0.3)
			(layers "F.Cu" "F.Mask" "F.Paste")
			(net 5 "VCC1V8")
			(pinfunction "VREF_{A}")
			(pintype "input")
		)
		(pad "3" smd rect
			(at -0.006 0.998 180)
			(size 0.41 0.3)
			(layers "F.Cu" "F.Mask" "F.Paste")
			(net 576 "ESPI_CS1_N_1V8")
			(pinfunction "A1")
			(pintype "bidirectional")
		)
		(pad "4" smd rect
			(at 0.583 0.998 180)
			(size 0.41 0.3)
			(layers "F.Cu" "F.Mask" "F.Paste")
			(net 69 "ESPI_CS1_N")
			(pinfunction "B1")
			(pintype "bidirectional")
		)
		(pad "5" smd rect
			(at 0.583 0.498 180)
			(size 0.41 0.3)
			(layers "F.Cu" "F.Mask" "F.Paste")
			(net 2 "VCC3V3")
			(pinfunction "VREF_{B}")
			(pintype "input")
		)
		(pad "6" smd rect
			(at 0.583 0 180)
			(size 0.41 0.3)
			(layers "F.Cu" "F.Mask" "F.Paste")
			(net 338 "Net-(U22-EN)")
			(pinfunction "EN")
			(pintype "input")
		)
	)
	(footprint "antmicro-footprints:C_0402_1005Metric"
		(layer "F.Cu")
		(at 78.265 67.7 90)
		(descr "Capacitor SMD 0402")
		(tags "capacitor SMD 0402")
		(property "Reference" "C250"
			(at -1.3 -16.165 90)
			(layer "F.SilkS")
			(effects
				(font
					(size 0.7 0.7)
					(thickness 0.15)
				)
				(justify left bottom)
			)
		)
		(property "Value" "C_10u_0402"
			(at 0 1.4 90)
			(layer "F.Fab")
			(effects
				(font
					(size 0.7 0.7)
					(thickness 0.15)
				)
				(justify left bottom)
			)
		)
		(property "Datasheet" "https://www.yageo.com/en/Chart/Download/pdf/CC0402MRX5R5BB106"
			(at 0 0 90)
			(layer "F.Fab")
			(hide yes)
			(effects
				(font
					(size 1.27 1.27)
					(thickness 0.15)
				)
			)
		)
		(property "Description" "SMD Multilayer Ceramic Capacitor, 10 µF, 6.3 V, 0402 [1005 Metric], ± 20%, X5R, CC Series"
			(at 0 0 90)
			(layer "F.Fab")
			(hide yes)
			(effects
				(font
					(size 1.27 1.27)
					(thickness 0.15)
				)
			)
		)
		(property "Author" "Antmicro"
			(at 145.965 -10.565 0)
			(layer "F.Fab")
			(hide yes)
			(effects
				(font
					(size 1 1)
					(thickness 0.15)
				)
			)
		)
		(property "Dielectric" ""
			(at 145.965 -10.565 0)
			(layer "F.Fab")
			(hide yes)
			(effects
				(font
					(size 1 1)
					(thickness 0.15)
				)
			)
		)
		(property "License" "Apache-2.0"
			(at 145.965 -10.565 0)
			(layer "F.Fab")
			(hide yes)
			(effects
				(font
					(size 1 1)
					(thickness 0.15)
				)
			)
		)
		(property "MPN" "CC0402MRX5R5BB106"
			(at 145.965 -10.565 0)
			(layer "F.Fab")
			(hide yes)
			(effects
				(font
					(size 1 1)
					(thickness 0.15)
				)
			)
		)
		(property "Manufacturer" "YAGEO"
			(at 145.965 -10.565 0)
			(layer "F.Fab")
			(hide yes)
			(effects
				(font
					(size 1 1)
					(thickness 0.15)
				)
			)
		)
		(property "Val" "10u"
			(at 145.965 -10.565 0)
			(layer "F.Fab")
			(hide yes)
			(effects
				(font
					(size 1 1)
					(thickness 0.15)
				)
			)
		)
		(property "Voltage" ""
			(at 145.965 -10.565 0)
			(layer "F.Fab")
			(hide yes)
			(effects
				(font
					(size 1 1)
					(thickness 0.15)
				)
			)
		)
		(sheetname "/Power supply/")
		(sheetfile "power-supply.kicad_sch")
		(attr smd)
		(fp_rect
			(start -0.925 -0.47)
			(end 0.925 0.47)
			(stroke
				(width 0.05)
				(type default)
			)
			(fill no)
			(layer "F.CrtYd")
		)
		(fp_line
			(start 0.504 -0.25)
			(end 0.504 0.248)
			(stroke
				(width 0.15)
				(type solid)
			)
			(layer "F.Fab")
		)
		(fp_line
			(start -0.494 -0.25)
			(end 0.504 -0.25)
			(stroke
				(width 0.15)
				(type solid)
			)
			(layer "F.Fab")
		)
		(fp_line
			(start 0.504 0.248)
			(end -0.494 0.248)
			(stroke
				(width 0.15)
				(type solid)
			)
			(layer "F.Fab")
		)
		(fp_line
			(start -0.494 0.248)
			(end -0.494 -0.25)
			(stroke
				(width 0.15)
				(type solid)
			)
			(layer "F.Fab")
		)
		(pad "1" smd roundrect
			(at -0.48 0 90)
			(size 0.59 0.64)
			(layers "F.Cu" "F.Mask" "F.Paste")
			(roundrect_rratio 0.25)
			(net 1 "GND")
			(pintype "passive")
		)
		(pad "2" smd roundrect
			(at 0.48 0 90)
			(size 0.59 0.64)
			(layers "F.Cu" "F.Mask" "F.Paste")
			(roundrect_rratio 0.25)
			(net 573 "/Power supply/5V0_PG")
			(pintype "passive")
		)
	)
	(footprint "antmicro-footprints:TP_SMD_1mm"
		(layer "F.Cu")
		(at 69.175 88.35 -90)
		(property "Reference" "TP4"
			(at 0.25 0.675 180)
			(layer "F.SilkS")
			(effects
				(font
					(size 0.7 0.7)
					(thickness 0.15)
				)
				(justify right bottom)
			)
		)
		(property "Value" "TP_1mm_SMD"
			(at 0 1.4 90)
			(layer "F.Fab")
			(effects
				(font
					(size 0.7 0.7)
					(thickness 0.15)
				)
				(justify right bottom)
			)
		)
		(property "Description" "Test point 1mm SMD"
			(at 0 0 270)
			(layer "F.Fab")
			(hide yes)
			(effects
				(font
					(size 1.27 1.27)
					(thickness 0.15)
				)
			)
		)
		(property "Author" "Antmicro"
			(at -19.175 157.525 0)
			(layer "F.Fab")
			(hide yes)
			(effects
				(font
					(size 1 1)
					(thickness 0.15)
				)
			)
		)
		(property "License" "Apache-2.0"
			(at -19.175 157.525 0)
			(layer "F.Fab")
			(hide yes)
			(effects
				(font
					(size 1 1)
					(thickness 0.15)
				)
			)
		)
		(property "MPN" ""
			(at -19.175 157.525 0)
			(layer "F.Fab")
			(hide yes)
			(effects
				(font
					(size 1 1)
					(thickness 0.15)
				)
			)
		)
		(property "Manufacturer" ""
			(at -19.175 157.525 0)
			(layer "F.Fab")
			(hide yes)
			(effects
				(font
					(size 1 1)
					(thickness 0.15)
				)
			)
		)
		(sheetname "/Power supply/")
		(sheetfile "power-supply.kicad_sch")
		(attr exclude_from_pos_files exclude_from_bom)
		(fp_circle
			(center 0 0)
			(end 0.6 0)
			(stroke
				(width 0.05)
				(type default)
			)
			(fill no)
			(layer "F.CrtYd")
		)
		(pad "1" smd circle
			(at 0 0 270)
			(size 1 1)
			(layers "F.Cu" "F.Mask")
			(net 573 "/Power supply/5V0_PG")
			(pinfunction "1")
			(pintype "passive")
		)
	)
	(footprint "antmicro-footprints:C_0402_1005Metric"
		(layer "F.Cu")
		(at 133.005 168.181 -90)
		(descr "Capacitor SMD 0402")
		(tags "capacitor SMD 0402")
		(property "Reference" "C182"
			(at 0.819 -0.404 90)
			(layer "F.SilkS")
			(effects
				(font
					(size 0.7 0.7)
					(thickness 0.15)
				)
				(justify right bottom)
			)
		)
		(property "Value" "C_100n_6V3_0402"
			(at 0 1.4 90)
			(layer "F.Fab")
			(effects
				(font
					(size 0.7 0.7)
					(thickness 0.15)
				)
				(justify right bottom)
			)
		)
		(property "Datasheet" "https://www.passivecomponent.com/wp-content/uploads/datasheet/WTC_MLCC_General_Purpose.pdf"
			(at 0 0 270)
			(layer "F.Fab")
			(hide yes)
			(effects
				(font
					(size 1.27 1.27)
					(thickness 0.15)
				)
			)
		)
		(property "Description" "SMT Multilayer Ceramic Capacitor, 0.1 µF, 6.3 V, 0402 [1005 Metric], ± 10%, X5R, Walsin MLCC"
			(at 0 0 270)
			(layer "F.Fab")
			(hide yes)
			(effects
				(font
					(size 1.27 1.27)
					(thickness 0.15)
				)
			)
		)
		(property "Author" "Antmicro"
			(at -35.176 301.186 0)
			(layer "F.Fab")
			(hide yes)
			(effects
				(font
					(size 1 1)
					(thickness 0.15)
				)
			)
		)
		(property "Dielectric" ""
			(at -35.176 301.186 0)
			(layer "F.Fab")
			(hide yes)
			(effects
				(font
					(size 1 1)
					(thickness 0.15)
				)
			)
		)
		(property "License" "Apache-2.0"
			(at -35.176 301.186 0)
			(layer "F.Fab")
			(hide yes)
			(effects
				(font
					(size 1 1)
					(thickness 0.15)
				)
			)
		)
		(property "MPN" "0402X104K6R3CT"
			(at -35.176 301.186 0)
			(layer "F.Fab")
			(hide yes)
			(effects
				(font
					(size 1 1)
					(thickness 0.15)
				)
			)
		)
		(property "Manufacturer" "Walsin"
			(at -35.176 301.186 0)
			(layer "F.Fab")
			(hide yes)
			(effects
				(font
					(size 1 1)
					(thickness 0.15)
				)
			)
		)
		(property "Public" "False"
			(at -35.176 301.186 0)
			(layer "F.Fab")
			(hide yes)
			(effects
				(font
					(size 1 1)
					(thickness 0.15)
				)
			)
		)
		(property "Val" "100n"
			(at -35.176 301.186 0)
			(layer "F.Fab")
			(hide yes)
			(effects
				(font
					(size 1 1)
					(thickness 0.15)
				)
			)
		)
		(property "Voltage" ""
			(at -35.176 301.186 0)
			(layer "F.Fab")
			(hide yes)
			(effects
				(font
					(size 1 1)
					(thickness 0.15)
				)
			)
		)
		(sheetname "/PCIe-connector/")
		(sheetfile "pcie-conn.kicad_sch")
		(attr smd)
		(fp_rect
			(start -0.925 -0.47)
			(end 0.925 0.47)
			(stroke
				(width 0.05)
				(type default)
			)
			(fill no)
			(layer "F.CrtYd")
		)
		(fp_line
			(start -0.494 0.248)
			(end -0.494 -0.25)
			(stroke
				(width 0.15)
				(type solid)
			)
			(layer "F.Fab")
		)
		(fp_line
			(start 0.504 0.248)
			(end -0.494 0.248)
			(stroke
				(width 0.15)
				(type solid)
			)
			(layer "F.Fab")
		)
		(fp_line
			(start -0.494 -0.25)
			(end 0.504 -0.25)
			(stroke
				(width 0.15)
				(type solid)
			)
			(layer "F.Fab")
		)
		(fp_line
			(start 0.504 -0.25)
			(end 0.504 0.248)
			(stroke
				(width 0.15)
				(type solid)
			)
			(layer "F.Fab")
		)
		(pad "1" smd roundrect
			(at -0.48 0 270)
			(size 0.59 0.64)
			(layers "F.Cu" "F.Mask" "F.Paste")
			(roundrect_rratio 0.25)
			(net 376 "/PCIe-connector/PCIE_HPM_TX3_C_N")
			(pintype "passive")
		)
		(pad "2" smd roundrect
			(at 0.48 0 270)
			(size 0.59 0.64)
			(layers "F.Cu" "F.Mask" "F.Paste")
			(roundrect_rratio 0.25)
			(net 358 "PCIE_HPM_TX[3]_N")
			(pintype "passive")
		)
	)
	(footprint "antmicro-footprints:C_0402_1005Metric"
		(layer "F.Cu")
		(at 131.995 168.181 -90)
		(descr "Capacitor SMD 0402")
		(tags "capacitor SMD 0402")
		(property "Reference" "C180"
			(at 0.819 -0.404 90)
			(layer "F.SilkS")
			(effects
				(font
					(size 0.7 0.7)
					(thickness 0.15)
				)
				(justify right bottom)
			)
		)
		(property "Value" "C_100n_6V3_0402"
			(at 0 1.4 90)
			(layer "F.Fab")
			(effects
				(font
					(size 0.7 0.7)
					(thickness 0.15)
				)
				(justify right bottom)
			)
		)
		(property "Datasheet" "https://www.passivecomponent.com/wp-content/uploads/datasheet/WTC_MLCC_General_Purpose.pdf"
			(at 0 0 270)
			(layer "F.Fab")
			(hide yes)
			(effects
				(font
					(size 1.27 1.27)
					(thickness 0.15)
				)
			)
		)
		(property "Description" "SMT Multilayer Ceramic Capacitor, 0.1 µF, 6.3 V, 0402 [1005 Metric], ± 10%, X5R, Walsin MLCC"
			(at 0 0 270)
			(layer "F.Fab")
			(hide yes)
			(effects
				(font
					(size 1.27 1.27)
					(thickness 0.15)
				)
			)
		)
		(property "Author" "Antmicro"
			(at -36.186 300.176 0)
			(layer "F.Fab")
			(hide yes)
			(effects
				(font
					(size 1 1)
					(thickness 0.15)
				)
			)
		)
		(property "Dielectric" ""
			(at -36.186 300.176 0)
			(layer "F.Fab")
			(hide yes)
			(effects
				(font
					(size 1 1)
					(thickness 0.15)
				)
			)
		)
		(property "License" "Apache-2.0"
			(at -36.186 300.176 0)
			(layer "F.Fab")
			(hide yes)
			(effects
				(font
					(size 1 1)
					(thickness 0.15)
				)
			)
		)
		(property "MPN" "0402X104K6R3CT"
			(at -36.186 300.176 0)
			(layer "F.Fab")
			(hide yes)
			(effects
				(font
					(size 1 1)
					(thickness 0.15)
				)
			)
		)
		(property "Manufacturer" "Walsin"
			(at -36.186 300.176 0)
			(layer "F.Fab")
			(hide yes)
			(effects
				(font
					(size 1 1)
					(thickness 0.15)
				)
			)
		)
		(property "Public" "False"
			(at -36.186 300.176 0)
			(layer "F.Fab")
			(hide yes)
			(effects
				(font
					(size 1 1)
					(thickness 0.15)
				)
			)
		)
		(property "Val" "100n"
			(at -36.186 300.176 0)
			(layer "F.Fab")
			(hide yes)
			(effects
				(font
					(size 1 1)
					(thickness 0.15)
				)
			)
		)
		(property "Voltage" ""
			(at -36.186 300.176 0)
			(layer "F.Fab")
			(hide yes)
			(effects
				(font
					(size 1 1)
					(thickness 0.15)
				)
			)
		)
		(sheetname "/PCIe-connector/")
		(sheetfile "pcie-conn.kicad_sch")
		(attr smd)
		(fp_rect
			(start -0.925 -0.47)
			(end 0.925 0.47)
			(stroke
				(width 0.05)
				(type default)
			)
			(fill no)
			(layer "F.CrtYd")
		)
		(fp_line
			(start -0.494 0.248)
			(end -0.494 -0.25)
			(stroke
				(width 0.15)
				(type solid)
			)
			(layer "F.Fab")
		)
		(fp_line
			(start 0.504 0.248)
			(end -0.494 0.248)
			(stroke
				(width 0.15)
				(type solid)
			)
			(layer "F.Fab")
		)
		(fp_line
			(start -0.494 -0.25)
			(end 0.504 -0.25)
			(stroke
				(width 0.15)
				(type solid)
			)
			(layer "F.Fab")
		)
		(fp_line
			(start 0.504 -0.25)
			(end 0.504 0.248)
			(stroke
				(width 0.15)
				(type solid)
			)
			(layer "F.Fab")
		)
		(pad "1" smd roundrect
			(at -0.48 0 270)
			(size 0.59 0.64)
			(layers "F.Cu" "F.Mask" "F.Paste")
			(roundrect_rratio 0.25)
			(net 374 "/PCIe-connector/PCIE_HPM_TX3_C_P")
			(pintype "passive")
		)
		(pad "2" smd roundrect
			(at 0.48 0 270)
			(size 0.59 0.64)
			(layers "F.Cu" "F.Mask" "F.Paste")
			(roundrect_rratio 0.25)
			(net 356 "PCIE_HPM_TX[3]_P")
			(pintype "passive")
		)
	)
	(footprint "antmicro-footprints:VQFN-20_1EP_4.5x2.5mm_P0.5mm"
		(layer "F.Cu")
		(at 78.015 166.115)
		(property "Reference" "U6"
			(at 1.285 -1.915 0)
			(layer "F.SilkS")
			(effects
				(font
					(size 0.7 0.7)
					(thickness 0.15)
				)
				(justify left bottom)
			)
		)
		(property "Value" "NVT2008BQ,115"
			(at 0.689 2.959 0)
			(layer "F.Fab")
			(effects
				(font
					(size 0.7 0.7)
					(thickness 0.15)
				)
				(justify left bottom)
			)
		)
		(property "Datasheet" "https://www.nxp.com/docs/en/data-sheet/NVT2008_NVT2010.pdf"
			(at 0 0 0)
			(layer "F.Fab")
			(hide yes)
			(effects
				(font
					(size 1.27 1.27)
					(thickness 0.15)
				)
			)
		)
		(property "Description" "Bidirectional Voltage Level Translator, 8 Inputs, 1.5ns, 1.8V to 5.5V, DHVQFN-20"
			(at 0 0 0)
			(layer "F.Fab")
			(hide yes)
			(effects
				(font
					(size 1.27 1.27)
					(thickness 0.15)
				)
			)
		)
		(property "Author" "Antmicro"
			(at 0 0 0)
			(layer "F.Fab")
			(hide yes)
			(effects
				(font
					(size 1 1)
					(thickness 0.15)
				)
			)
		)
		(property "License" "Apache-2.0"
			(at 0 0 0)
			(layer "F.Fab")
			(hide yes)
			(effects
				(font
					(size 1 1)
					(thickness 0.15)
				)
			)
		)
		(property "MPN" "NVT2008BQ,115"
			(at 0 0 0)
			(layer "F.Fab")
			(hide yes)
			(effects
				(font
					(size 1 1)
					(thickness 0.15)
				)
			)
		)
		(property "Manufacturer" "NXP"
			(at 0 0 0)
			(layer "F.Fab")
			(hide yes)
			(effects
				(font
					(size 1 1)
					(thickness 0.15)
				)
			)
		)
		(sheetname "/Interfaces/")
		(sheetfile "interfaces.kicad_sch")
		(attr smd)
		(fp_line
			(start -2.25 -1.25)
			(end -2.25 -0.5)
			(stroke
				(width 0.15)
				(type solid)
			)
			(layer "F.SilkS")
		)
		(fp_line
			(start -2.249 1.25)
			(end -2 1.25)
			(stroke
				(width 0.15)
				(type solid)
			)
			(layer "F.SilkS")
		)
		(fp_line
			(start -2.001 -1.25)
			(end -2.25 -1.25)
			(stroke
				(width 0.15)
				(type solid)
			)
			(layer "F.SilkS")
		)
		(fp_line
			(start 2.249 -1.25)
			(end 2 -1.25)
			(stroke
				(width 0.15)
				(type solid)
			)
			(layer "F.SilkS")
		)
		(fp_line
			(start 2.249 -1.25)
			(end 2.249 -0.5)
			(stroke
				(width 0.15)
				(type solid)
			)
			(layer "F.SilkS")
		)
		(fp_line
			(start 2.249 1.249)
			(end 2 1.249)
			(stroke
				(width 0.15)
				(type solid)
			)
			(layer "F.SilkS")
		)
		(fp_line
			(start 2.249 1.249)
			(end 2.249 0.5)
			(stroke
				(width 0.15)
				(type solid)
			)
			(layer "F.SilkS")
		)
		(fp_rect
			(start -2.711 -1.71)
			(end 2.708 1.709)
			(stroke
				(width 0.05)
				(type solid)
			)
			(fill no)
			(layer "F.CrtYd")
		)
		(fp_line
			(start -2.25 1.249)
			(end -2.25 -1.25)
			(stroke
				(width 0.15)
				(type solid)
			)
			(layer "F.Fab")
		)
		(fp_line
			(start 2.249 -1.25)
			(end -2.25 -1.25)
			(stroke
				(width 0.15)
				(type solid)
			)
			(layer "F.Fab")
		)
		(fp_line
			(start 2.249 1.249)
			(end -2.25 1.249)
			(stroke
				(width 0.15)
				(type solid)
			)
			(layer "F.Fab")
		)
		(fp_line
			(start 2.249 1.249)
			(end 2.249 -1.25)
			(stroke
				(width 0.15)
				(type solid)
			)
			(layer "F.Fab")
		)
		(pad "" smd roundrect
			(at -0.76 0)
			(size 1.31 0.95)
			(layers "F.Paste")
			(roundrect_rratio 0.05)
		)
		(pad "" smd roundrect
			(at 0.76 0)
			(size 1.31 0.95)
			(layers "F.Paste")
			(roundrect_rratio 0.05)
		)
		(pad "1" smd roundrect
			(at -2.15 0.25 90)
			(size 0.25 0.8)
			(layers "F.Cu" "F.Mask" "F.Paste")
			(roundrect_rratio 0.2)
			(net 1 "GND")
			(pinfunction "GND")
			(pintype "power_in")
		)
		(pad "2" smd roundrect
			(at -1.75 1.15)
			(size 0.25 0.8)
			(layers "F.Cu" "F.Mask" "F.Paste")
			(roundrect_rratio 0.2)
			(net 6 "VCC1V0")
			(pinfunction "VREFA")
			(pintype "power_in")
		)
		(pad "3" smd roundrect
			(at -1.25 1.15)
			(size 0.25 0.8)
			(layers "F.Cu" "F.Mask" "F.Paste")
			(roundrect_rratio 0.2)
			(net 49 "I3C[0]_SCL")
			(pinfunction "A1")
			(pintype "bidirectional")
		)
		(pad "4" smd roundrect
			(at -0.75 1.15)
			(size 0.25 0.8)
			(layers "F.Cu" "F.Mask" "F.Paste")
			(roundrect_rratio 0.2)
			(net 48 "I3C[0]_SDA")
			(pinfunction "A2")
			(pintype "bidirectional")
		)
		(pad "5" smd roundrect
			(at -0.25 1.15)
			(size 0.25 0.8)
			(layers "F.Cu" "F.Mask" "F.Paste")
			(roundrect_rratio 0.2)
			(net 52 "I3C[1]_SCL")
			(pinfunction "A3")
			(pintype "bidirectional")
		)
		(pad "6" smd roundrect
			(at 0.25 1.15)
			(size 0.25 0.8)
			(layers "F.Cu" "F.Mask" "F.Paste")
			(roundrect_rratio 0.2)
			(net 51 "I3C[1]_SDA")
			(pinfunction "A4")
			(pintype "bidirectional")
		)
		(pad "7" smd roundrect
			(at 0.75 1.15)
			(size 0.25 0.8)
			(layers "F.Cu" "F.Mask" "F.Paste")
			(roundrect_rratio 0.2)
			(net 47 "I3C[2]_SCL")
			(pinfunction "A5")
			(pintype "bidirectional")
		)
		(pad "8" smd roundrect
			(at 1.25 1.15)
			(size 0.25 0.8)
			(layers "F.Cu" "F.Mask" "F.Paste")
			(roundrect_rratio 0.2)
			(net 50 "I3C[2]_SDA")
			(pinfunction "A6")
			(pintype "bidirectional")
		)
		(pad "9" smd roundrect
			(at 1.75 1.15)
			(size 0.25 0.8)
			(layers "F.Cu" "F.Mask" "F.Paste")
			(roundrect_rratio 0.2)
			(net 54 "I3C[3]_SCL")
			(pinfunction "A7")
			(pintype "bidirectional")
		)
		(pad "10" smd roundrect
			(at 2.15 0.25 90)
			(size 0.25 0.8)
			(layers "F.Cu" "F.Mask" "F.Paste")
			(roundrect_rratio 0.2)
			(net 53 "I3C[3]_SDA")
			(pinfunction "A8")
			(pintype "bidirectional")
		)
		(pad "11" smd roundrect
			(at 2.15 -0.25 90)
			(size 0.25 0.8)
			(layers "F.Cu" "F.Mask" "F.Paste")
			(roundrect_rratio 0.2)
			(net 174 "I3C[3]_SDA_3V3")
			(pinfunction "B8")
			(pintype "bidirectional")
		)
		(pad "12" smd roundrect
			(at 1.75 -1.15)
			(size 0.25 0.8)
			(layers "F.Cu" "F.Mask" "F.Paste")
			(roundrect_rratio 0.2)
			(net 175 "I3C[3]_SCL_3V3")
			(pinfunction "B7")
			(pintype "bidirectional")
		)
		(pad "13" smd roundrect
			(at 1.25 -1.15)
			(size 0.25 0.8)
			(layers "F.Cu" "F.Mask" "F.Paste")
			(roundrect_rratio 0.2)
			(net 172 "I3C[2]_SDA_3V3")
			(pinfunction "B6")
			(pintype "bidirectional")
		)
		(pad "14" smd roundrect
			(at 0.75 -1.15)
			(size 0.25 0.8)
			(layers "F.Cu" "F.Mask" "F.Paste")
			(roundrect_rratio 0.2)
			(net 173 "I3C[2]_SCL_3V3")
			(pinfunction "B5")
			(pintype "bidirectional")
		)
		(pad "15" smd roundrect
			(at 0.25 -1.15)
			(size 0.25 0.8)
			(layers "F.Cu" "F.Mask" "F.Paste")
			(roundrect_rratio 0.2)
			(net 170 "I3C[1]_SDA_3V3")
			(pinfunction "B4")
			(pintype "bidirectional")
		)
		(pad "16" smd roundrect
			(at -0.25 -1.15)
			(size 0.25 0.8)
			(layers "F.Cu" "F.Mask" "F.Paste")
			(roundrect_rratio 0.2)
			(net 171 "I3C[1]_SCL_3V3")
			(pinfunction "B3")
			(pintype "bidirectional")
		)
		(pad "17" smd roundrect
			(at -0.75 -1.15)
			(size 0.25 0.8)
			(layers "F.Cu" "F.Mask" "F.Paste")
			(roundrect_rratio 0.2)
			(net 168 "I3C[0]_SDA_3V3")
			(pinfunction "B2")
			(pintype "bidirectional")
		)
		(pad "18" smd roundrect
			(at -1.25 -1.15)
			(size 0.25 0.8)
			(layers "F.Cu" "F.Mask" "F.Paste")
			(roundrect_rratio 0.2)
			(net 169 "I3C[0]_SCL_3V3")
			(pinfunction "B1")
			(pintype "bidirectional")
		)
		(pad "19" smd roundrect
			(at -1.75 -1.15)
			(size 0.25 0.8)
			(layers "F.Cu" "F.Mask" "F.Paste")
			(roundrect_rratio 0.2)
			(net 7 "/Interfaces/1V0_EN")
			(pinfunction "VREFB")
			(pintype "power_in")
		)
		(pad "20" smd roundrect
			(at -2.15 -0.25 90)
			(size 0.25 0.8)
			(layers "F.Cu" "F.Mask" "F.Paste")
			(roundrect_rratio 0.2)
			(net 7 "/Interfaces/1V0_EN")
			(pinfunction "EN")
			(pintype "input")
		)
		(pad "21" smd roundrect
			(at 0 0)
			(size 3 1)
			(layers "F.Cu" "F.Mask")
			(roundrect_rratio 0.05)
			(net 1 "GND")
			(pinfunction "EP")
			(pintype "power_in")
		)
	)
	(footprint "antmicro-footprints:R_0402_1005Metric"
		(layer "F.Cu")
		(at 77.2 67.7 -90)
		(descr "Resistor SMD 0402")
		(tags "resistor SMD 0402")
		(property "Reference" "R68"
			(at -0.9 16.03 90)
			(layer "F.SilkS")
			(effects
				(font
					(size 0.7 0.7)
					(thickness 0.15)
				)
				(justify right bottom)
			)
		)
		(property "Value" "R_100k_0402"
			(at 0 1.4 90)
			(layer "F.Fab")
			(effects
				(font
					(size 0.7 0.7)
					(thickness 0.15)
				)
				(justify right bottom)
			)
		)
		(property "Datasheet" "https://www.bourns.com/docs/product-datasheets/cr.pdf"
			(at 0 0 270)
			(layer "F.Fab")
			(hide yes)
			(effects
				(font
					(size 1.27 1.27)
					(thickness 0.15)
				)
			)
		)
		(property "Description" "SMD Chip Resistor, 100 kohm, ± 1%, 62.5 mW, 0402 [1005 Metric], Thick Film, General Purpose"
			(at 0 0 270)
			(layer "F.Fab")
			(hide yes)
			(effects
				(font
					(size 1.27 1.27)
					(thickness 0.15)
				)
			)
		)
		(property "Author" "Antmicro"
			(at 9.5 144.9 0)
			(layer "F.Fab")
			(hide yes)
			(effects
				(font
					(size 1 1)
					(thickness 0.15)
				)
			)
		)
		(property "License" "Apache-2.0"
			(at 9.5 144.9 0)
			(layer "F.Fab")
			(hide yes)
			(effects
				(font
					(size 1 1)
					(thickness 0.15)
				)
			)
		)
		(property "MPN" "CR0402-FX-1003GLF"
			(at 9.5 144.9 0)
			(layer "F.Fab")
			(hide yes)
			(effects
				(font
					(size 1 1)
					(thickness 0.15)
				)
			)
		)
		(property "Manufacturer" "Bourns"
			(at 9.5 144.9 0)
			(layer "F.Fab")
			(hide yes)
			(effects
				(font
					(size 1 1)
					(thickness 0.15)
				)
			)
		)
		(property "Tolerance" "1%"
			(at 9.5 144.9 0)
			(layer "F.Fab")
			(hide yes)
			(effects
				(font
					(size 1 1)
					(thickness 0.15)
				)
			)
		)
		(property "Val" "100k"
			(at 9.5 144.9 0)
			(layer "F.Fab")
			(hide yes)
			(effects
				(font
					(size 1 1)
					(thickness 0.15)
				)
			)
		)
		(sheetname "/Power supply/")
		(sheetfile "power-supply.kicad_sch")
		(attr smd)
		(fp_rect
			(start -0.925 -0.47)
			(end 0.925 0.47)
			(stroke
				(width 0.05)
				(type default)
			)
			(fill no)
			(layer "F.CrtYd")
		)
		(fp_rect
			(start -0.5 -0.25)
			(end 0.5 0.25)
			(stroke
				(width 0.15)
				(type solid)
			)
			(fill no)
			(layer "F.Fab")
		)
		(pad "1" smd roundrect
			(at -0.48 0 270)
			(size 0.59 0.64)
			(layers "F.Cu" "F.Mask" "F.Paste")
			(roundrect_rratio 0.25)
			(net 4 "VCC5V0")
			(pintype "passive")
		)
		(pad "2" smd roundrect
			(at 0.48 0 270)
			(size 0.59 0.64)
			(layers "F.Cu" "F.Mask" "F.Paste")
			(roundrect_rratio 0.25)
			(net 573 "/Power supply/5V0_PG")
			(pintype "passive")
		)
	)
	(footprint "antmicro-footprints:USON-14_3.5x1.35_P0.5mm"
		(layer "F.Cu")
		(at 137.515 75.265 -90)
		(descr "JEDEC MO-229")
		(property "Reference" "D2"
			(at -1.065 0.815 0)
			(layer "F.SilkS")
			(effects
				(font
					(size 0.7 0.7)
					(thickness 0.15)
				)
				(justify left bottom)
			)
		)
		(property "Value" "SP3011-06UTG"
			(at -1.3 3 270)
			(layer "F.Fab")
			(effects
				(font
					(size 0.7 0.7)
					(thickness 0.15)
				)
				(justify left bottom)
			)
		)
		(property "Datasheet" "https://www.littelfuse.com/media?resourcetype=datasheets&itemid=c9002a97-9994-449b-b722-f45ab5538c7f&filename=littelfuse-tvs-diode-array-sp3011-datasheet"
			(at 0 0 270)
			(layer "F.Fab")
			(hide yes)
			(effects
				(font
					(size 1.27 1.27)
					(thickness 0.15)
				)
			)
		)
		(property "Description" "TVS diode array, 8 kV, USON-14, 6 V, 0.4 pF"
			(at 0 0 270)
			(layer "F.Fab")
			(hide yes)
			(effects
				(font
					(size 1.27 1.27)
					(thickness 0.15)
				)
			)
		)
		(property "Author" "Antmicro"
			(at 62.25 212.78 0)
			(layer "F.Fab")
			(hide yes)
			(effects
				(font
					(size 1 1)
					(thickness 0.15)
				)
			)
		)
		(property "License" "Apache-2.0"
			(at 62.25 212.78 0)
			(layer "F.Fab")
			(hide yes)
			(effects
				(font
					(size 1 1)
					(thickness 0.15)
				)
			)
		)
		(property "MPN" "SP3011-06UTG"
			(at 62.25 212.78 0)
			(layer "F.Fab")
			(hide yes)
			(effects
				(font
					(size 1 1)
					(thickness 0.15)
				)
			)
		)
		(property "Manufacturer" "Littelfuse"
			(at 62.25 212.78 0)
			(layer "F.Fab")
			(hide yes)
			(effects
				(font
					(size 1 1)
					(thickness 0.15)
				)
			)
		)
		(sheetname "/Interfaces/")
		(sheetfile "interfaces.kicad_sch")
		(attr smd)
		(fp_line
			(start -0.8 1.75)
			(end 0.8 1.75)
			(stroke
				(width 0.12)
				(type solid)
			)
			(layer "F.SilkS")
		)
		(fp_line
			(start -0.4 -1.75)
			(end 0.8 -1.75)
			(stroke
				(width 0.12)
				(type solid)
			)
			(layer "F.SilkS")
		)
		(fp_rect
			(start 1 -1.9)
			(end -0.95 1.9)
			(stroke
				(width 0.05)
				(type solid)
			)
			(fill no)
			(layer "F.CrtYd")
		)
		(fp_line
			(start -0.7 1.75)
			(end -0.7 -1.55)
			(stroke
				(width 0.1)
				(type solid)
			)
			(layer "F.Fab")
		)
		(fp_line
			(start 0.65 1.75)
			(end -0.7 1.75)
			(stroke
				(width 0.1)
				(type solid)
			)
			(layer "F.Fab")
		)
		(fp_line
			(start -0.7 -1.55)
			(end -0.5 -1.75)
			(stroke
				(width 0.1)
				(type solid)
			)
			(layer "F.Fab")
		)
		(fp_line
			(start -0.5 -1.75)
			(end 0.65 -1.75)
			(stroke
				(width 0.1)
				(type solid)
			)
			(layer "F.Fab")
		)
		(fp_line
			(start 0.65 -1.75)
			(end 0.65 1.75)
			(stroke
				(width 0.1)
				(type solid)
			)
			(layer "F.Fab")
		)
		(fp_text user "."
			(at -0.9 -2.25 270)
			(layer "F.SilkS")
			(effects
				(font
					(size 1 1)
					(thickness 0.15)
				)
			)
		)
		(pad "1" smd roundrect
			(at -0.623 -1.5 180)
			(size 0.2 0.5)
			(layers "F.Cu" "F.Mask" "F.Paste")
			(roundrect_rratio 0.25)
			(chamfer_ratio 0.2)
			(chamfer bottom_left)
			(net 16 "JTAG_TMS")
			(pintype "passive")
		)
		(pad "2" smd roundrect
			(at -0.623 -1 180)
			(size 0.2 0.5)
			(layers "F.Cu" "F.Mask" "F.Paste")
			(roundrect_rratio 0.25)
			(net 15 "JTAG_TCK")
			(pintype "passive")
		)
		(pad "3" smd roundrect
			(at -0.623 -0.5 180)
			(size 0.2 0.5)
			(layers "F.Cu" "F.Mask" "F.Paste")
			(roundrect_rratio 0.25)
			(net 695 "unconnected-(D2-Pad12)_1")
			(pintype "passive+no_connect")
		)
		(pad "4" smd roundrect
			(at -0.623 0 180)
			(size 0.2 0.5)
			(layers "F.Cu" "F.Mask" "F.Paste")
			(roundrect_rratio 0.25)
			(net 696 "unconnected-(D2-Pad11)_1")
			(pintype "passive+no_connect")
		)
		(pad "5" smd roundrect
			(at -0.623 0.498 180)
			(size 0.2 0.5)
			(layers "F.Cu" "F.Mask" "F.Paste")
			(roundrect_rratio 0.25)
			(net 1 "GND")
			(pintype "passive")
		)
		(pad "6" smd roundrect
			(at -0.623 0.998 180)
			(size 0.2 0.5)
			(layers "F.Cu" "F.Mask" "F.Paste")
			(roundrect_rratio 0.25)
			(net 14 "JTAG_TDO")
			(pintype "passive")
		)
		(pad "7" smd roundrect
			(at -0.623 1.499 180)
			(size 0.2 0.5)
			(layers "F.Cu" "F.Mask" "F.Paste")
			(roundrect_rratio 0.25)
			(net 13 "JTAG_TDI")
			(pintype "passive")
		)
		(pad "8" smd roundrect
			(at 0.625 1.499 180)
			(size 0.2 0.5)
			(layers "F.Cu" "F.Mask" "F.Paste")
			(roundrect_rratio 0.25)
			(net 13 "JTAG_TDI")
			(pintype "passive")
		)
		(pad "9" smd roundrect
			(at 0.625 0.998 180)
			(size 0.2 0.5)
			(layers "F.Cu" "F.Mask" "F.Paste")
			(roundrect_rratio 0.25)
			(net 14 "JTAG_TDO")
			(pintype "passive")
		)
		(pad "10" smd roundrect
			(at 0.625 0.498 180)
			(size 0.2 0.5)
			(layers "F.Cu" "F.Mask" "F.Paste")
			(roundrect_rratio 0.25)
			(net 1 "GND")
			(pintype "passive")
		)
		(pad "11" smd roundrect
			(at 0.625 0 180)
			(size 0.2 0.5)
			(layers "F.Cu" "F.Mask" "F.Paste")
			(roundrect_rratio 0.25)
			(net 210 "unconnected-(D2-Pad11)")
			(pintype "passive+no_connect")
		)
		(pad "12" smd roundrect
			(at 0.625 -0.5 180)
			(size 0.2 0.5)
			(layers "F.Cu" "F.Mask" "F.Paste")
			(roundrect_rratio 0.25)
			(net 209 "unconnected-(D2-Pad12)")
			(pintype "passive+no_connect")
		)
		(pad "13" smd roundrect
			(at 0.625 -1 180)
			(size 0.2 0.5)
			(layers "F.Cu" "F.Mask" "F.Paste")
			(roundrect_rratio 0.25)
			(net 15 "JTAG_TCK")
			(pintype "passive")
		)
		(pad "14" smd roundrect
			(at 0.625 -1.5 180)
			(size 0.2 0.5)
			(layers "F.Cu" "F.Mask" "F.Paste")
			(roundrect_rratio 0.25)
			(net 16 "JTAG_TMS")
			(pintype "passive")
		)
	)
	(footprint "antmicro-footprints:C_0402_1005Metric"
		(layer "F.Cu")
		(at 83.09 167.05 -90)
		(descr "Capacitor SMD 0402")
		(tags "capacitor SMD 0402")
		(property "Reference" "C253"
			(at -0.65 0.49 90)
			(layer "F.SilkS")
			(effects
				(font
					(size 0.7 0.7)
					(thickness 0.15)
				)
				(justify right bottom)
			)
		)
		(property "Value" "C_100n_0402"
			(at 0 1.4 90)
			(layer "F.Fab")
			(effects
				(font
					(size 0.7 0.7)
					(thickness 0.15)
				)
				(justify right bottom)
			)
		)
		(property "Datasheet" "https://www.murata.com/products/productdetail?partno=GRM155R61H104KE14%23"
			(at 0 0 270)
			(layer "F.Fab")
			(hide yes)
			(effects
				(font
					(size 1.27 1.27)
					(thickness 0.15)
				)
			)
		)
		(property "Description" "SMD Multilayer Ceramic Capacitor, 0.1 µF, 50 V, 0402 [1005 Metric], ± 10%, X5R, GRM Series"
			(at 0 0 270)
			(layer "F.Fab")
			(hide yes)
			(effects
				(font
					(size 1.27 1.27)
					(thickness 0.15)
				)
			)
		)
		(property "Author" "Antmicro"
			(at -83.96 250.14 0)
			(layer "F.Fab")
			(hide yes)
			(effects
				(font
					(size 1 1)
					(thickness 0.15)
				)
			)
		)
		(property "Dielectric" "X5R"
			(at -83.96 250.14 0)
			(layer "F.Fab")
			(hide yes)
			(effects
				(font
					(size 1 1)
					(thickness 0.15)
				)
			)
		)
		(property "License" "Apache-2.0"
			(at -83.96 250.14 0)
			(layer "F.Fab")
			(hide yes)
			(effects
				(font
					(size 1 1)
					(thickness 0.15)
				)
			)
		)
		(property "MPN" "GRM155R61H104KE14D"
			(at -83.96 250.14 0)
			(layer "F.Fab")
			(hide yes)
			(effects
				(font
					(size 1 1)
					(thickness 0.15)
				)
			)
		)
		(property "Manufacturer" "Murata"
			(at -83.96 250.14 0)
			(layer "F.Fab")
			(hide yes)
			(effects
				(font
					(size 1 1)
					(thickness 0.15)
				)
			)
		)
		(property "Val" "100n"
			(at -83.96 250.14 0)
			(layer "F.Fab")
			(hide yes)
			(effects
				(font
					(size 1 1)
					(thickness 0.15)
				)
			)
		)
		(property "Voltage" "50V"
			(at -83.96 250.14 0)
			(layer "F.Fab")
			(hide yes)
			(effects
				(font
					(size 1 1)
					(thickness 0.15)
				)
			)
		)
		(sheetname "/Interfaces/")
		(sheetfile "interfaces.kicad_sch")
		(attr smd)
		(fp_rect
			(start -0.925 -0.47)
			(end 0.925 0.47)
			(stroke
				(width 0.05)
				(type default)
			)
			(fill no)
			(layer "F.CrtYd")
		)
		(fp_line
			(start -0.494 0.248)
			(end -0.494 -0.25)
			(stroke
				(width 0.15)
				(type solid)
			)
			(layer "F.Fab")
		)
		(fp_line
			(start 0.504 0.248)
			(end -0.494 0.248)
			(stroke
				(width 0.15)
				(type solid)
			)
			(layer "F.Fab")
		)
		(fp_line
			(start -0.494 -0.25)
			(end 0.504 -0.25)
			(stroke
				(width 0.15)
				(type solid)
			)
			(layer "F.Fab")
		)
		(fp_line
			(start 0.504 -0.25)
			(end 0.504 0.248)
			(stroke
				(width 0.15)
				(type solid)
			)
			(layer "F.Fab")
		)
		(pad "1" smd roundrect
			(at -0.48 0 270)
			(size 0.59 0.64)
			(layers "F.Cu" "F.Mask" "F.Paste")
			(roundrect_rratio 0.25)
			(net 1 "GND")
			(pintype "passive")
		)
		(pad "2" smd roundrect
			(at 0.48 0 270)
			(size 0.59 0.64)
			(layers "F.Cu" "F.Mask" "F.Paste")
			(roundrect_rratio 0.25)
			(net 5 "VCC1V8")
			(pintype "passive")
		)
	)
	(footprint "antmicro-footprints:C_0402_1005Metric"
		(layer "F.Cu")
		(at 92.065 163.425 90)
		(descr "Capacitor SMD 0402")
		(tags "capacitor SMD 0402")
		(property "Reference" "C254"
			(at -0.975 1.335 90)
			(layer "F.SilkS")
			(effects
				(font
					(size 0.7 0.7)
					(thickness 0.15)
				)
				(justify left bottom)
			)
		)
		(property "Value" "C_100n_0402"
			(at 0 1.4 90)
			(layer "F.Fab")
			(effects
				(font
					(size 0.7 0.7)
					(thickness 0.15)
				)
				(justify left bottom)
			)
		)
		(property "Datasheet" "https://www.murata.com/products/productdetail?partno=GRM155R61H104KE14%23"
			(at 0 0 90)
			(layer "F.Fab")
			(hide yes)
			(effects
				(font
					(size 1.27 1.27)
					(thickness 0.15)
				)
			)
		)
		(property "Description" "SMD Multilayer Ceramic Capacitor, 0.1 µF, 50 V, 0402 [1005 Metric], ± 10%, X5R, GRM Series"
			(at 0 0 90)
			(layer "F.Fab")
			(hide yes)
			(effects
				(font
					(size 1.27 1.27)
					(thickness 0.15)
				)
			)
		)
		(property "Author" "Antmicro"
			(at 255.49 71.36 0)
			(layer "F.Fab")
			(hide yes)
			(effects
				(font
					(size 1 1)
					(thickness 0.15)
				)
			)
		)
		(property "Dielectric" "X5R"
			(at 255.49 71.36 0)
			(layer "F.Fab")
			(hide yes)
			(effects
				(font
					(size 1 1)
					(thickness 0.15)
				)
			)
		)
		(property "License" "Apache-2.0"
			(at 255.49 71.36 0)
			(layer "F.Fab")
			(hide yes)
			(effects
				(font
					(size 1 1)
					(thickness 0.15)
				)
			)
		)
		(property "MPN" "GRM155R61H104KE14D"
			(at 255.49 71.36 0)
			(layer "F.Fab")
			(hide yes)
			(effects
				(font
					(size 1 1)
					(thickness 0.15)
				)
			)
		)
		(property "Manufacturer" "Murata"
			(at 255.49 71.36 0)
			(layer "F.Fab")
			(hide yes)
			(effects
				(font
					(size 1 1)
					(thickness 0.15)
				)
			)
		)
		(property "Val" "100n"
			(at 255.49 71.36 0)
			(layer "F.Fab")
			(hide yes)
			(effects
				(font
					(size 1 1)
					(thickness 0.15)
				)
			)
		)
		(property "Voltage" "50V"
			(at 255.49 71.36 0)
			(layer "F.Fab")
			(hide yes)
			(effects
				(font
					(size 1 1)
					(thickness 0.15)
				)
			)
		)
		(sheetname "/Interfaces/")
		(sheetfile "interfaces.kicad_sch")
		(attr smd)
		(fp_rect
			(start -0.925 -0.47)
			(end 0.925 0.47)
			(stroke
				(width 0.05)
				(type default)
			)
			(fill no)
			(layer "F.CrtYd")
		)
		(fp_line
			(start 0.504 -0.25)
			(end 0.504 0.248)
			(stroke
				(width 0.15)
				(type solid)
			)
			(layer "F.Fab")
		)
		(fp_line
			(start -0.494 -0.25)
			(end 0.504 -0.25)
			(stroke
				(width 0.15)
				(type solid)
			)
			(layer "F.Fab")
		)
		(fp_line
			(start 0.504 0.248)
			(end -0.494 0.248)
			(stroke
				(width 0.15)
				(type solid)
			)
			(layer "F.Fab")
		)
		(fp_line
			(start -0.494 0.248)
			(end -0.494 -0.25)
			(stroke
				(width 0.15)
				(type solid)
			)
			(layer "F.Fab")
		)
		(pad "1" smd roundrect
			(at -0.48 0 90)
			(size 0.59 0.64)
			(layers "F.Cu" "F.Mask" "F.Paste")
			(roundrect_rratio 0.25)
			(net 1 "GND")
			(pintype "passive")
		)
		(pad "2" smd roundrect
			(at 0.48 0 90)
			(size 0.59 0.64)
			(layers "F.Cu" "F.Mask" "F.Paste")
			(roundrect_rratio 0.25)
			(net 5 "VCC1V8")
			(pintype "passive")
		)
	)
	(footprint "antmicro-footprints:C_0402_1005Metric"
		(layer "F.Cu")
		(at 120.965 133.125 90)
		(descr "Capacitor SMD 0402")
		(tags "capacitor SMD 0402")
		(property "Reference" "C4"
			(at -0.775 -0.465 90)
			(layer "F.SilkS")
			(effects
				(font
					(size 0.7 0.7)
					(thickness 0.15)
				)
				(justify left bottom)
			)
		)
		(property "Value" "C_100n_0402"
			(at 0 1.4 90)
			(layer "F.Fab")
			(effects
				(font
					(size 0.7 0.7)
					(thickness 0.15)
				)
				(justify left bottom)
			)
		)
		(property "Datasheet" "https://www.murata.com/products/productdetail?partno=GRM155R61H104KE14%23"
			(at 0 0 90)
			(layer "F.Fab")
			(hide yes)
			(effects
				(font
					(size 1.27 1.27)
					(thickness 0.15)
				)
			)
		)
		(property "Description" "SMD Multilayer Ceramic Capacitor, 0.1 µF, 50 V, 0402 [1005 Metric], ± 10%, X5R, GRM Series"
			(at 0 0 90)
			(layer "F.Fab")
			(hide yes)
			(effects
				(font
					(size 1.27 1.27)
					(thickness 0.15)
				)
			)
		)
		(property "Author" "Antmicro"
			(at 254.09 12.16 0)
			(layer "F.Fab")
			(hide yes)
			(effects
				(font
					(size 1 1)
					(thickness 0.15)
				)
			)
		)
		(property "Dielectric" "X5R"
			(at 254.09 12.16 0)
			(layer "F.Fab")
			(hide yes)
			(effects
				(font
					(size 1 1)
					(thickness 0.15)
				)
			)
		)
		(property "License" "Apache-2.0"
			(at 254.09 12.16 0)
			(layer "F.Fab")
			(hide yes)
			(effects
				(font
					(size 1 1)
					(thickness 0.15)
				)
			)
		)
		(property "MPN" "GRM155R61H104KE14D"
			(at 254.09 12.16 0)
			(layer "F.Fab")
			(hide yes)
			(effects
				(font
					(size 1 1)
					(thickness 0.15)
				)
			)
		)
		(property "Manufacturer" "Murata"
			(at 254.09 12.16 0)
			(layer "F.Fab")
			(hide yes)
			(effects
				(font
					(size 1 1)
					(thickness 0.15)
				)
			)
		)
		(property "Val" "100n"
			(at 254.09 12.16 0)
			(layer "F.Fab")
			(hide yes)
			(effects
				(font
					(size 1 1)
					(thickness 0.15)
				)
			)
		)
		(property "Voltage" "50V"
			(at 254.09 12.16 0)
			(layer "F.Fab")
			(hide yes)
			(effects
				(font
					(size 1 1)
					(thickness 0.15)
				)
			)
		)
		(sheetname "/Interfaces/")
		(sheetfile "interfaces.kicad_sch")
		(attr smd)
		(fp_rect
			(start -0.925 -0.47)
			(end 0.925 0.47)
			(stroke
				(width 0.05)
				(type default)
			)
			(fill no)
			(layer "F.CrtYd")
		)
		(fp_line
			(start 0.504 -0.25)
			(end 0.504 0.248)
			(stroke
				(width 0.15)
				(type solid)
			)
			(layer "F.Fab")
		)
		(fp_line
			(start -0.494 -0.25)
			(end 0.504 -0.25)
			(stroke
				(width 0.15)
				(type solid)
			)
			(layer "F.Fab")
		)
		(fp_line
			(start 0.504 0.248)
			(end -0.494 0.248)
			(stroke
				(width 0.15)
				(type solid)
			)
			(layer "F.Fab")
		)
		(fp_line
			(start -0.494 0.248)
			(end -0.494 -0.25)
			(stroke
				(width 0.15)
				(type solid)
			)
			(layer "F.Fab")
		)
		(pad "1" smd roundrect
			(at -0.48 0 90)
			(size 0.59 0.64)
			(layers "F.Cu" "F.Mask" "F.Paste")
			(roundrect_rratio 0.25)
			(net 1 "GND")
			(pintype "passive")
		)
		(pad "2" smd roundrect
			(at 0.48 0 90)
			(size 0.59 0.64)
			(layers "F.Cu" "F.Mask" "F.Paste")
			(roundrect_rratio 0.25)
			(net 2 "VCC3V3")
			(pintype "passive")
		)
	)
	(footprint "antmicro-footprints:C_0402_1005Metric"
		(layer "F.Cu")
		(at 121.305 116.415 -90)
		(descr "Capacitor SMD 0402")
		(tags "capacitor SMD 0402")
		(property "Reference" "C5"
			(at 0.985 -0.295 90)
			(layer "F.SilkS")
			(effects
				(font
					(size 0.7 0.7)
					(thickness 0.15)
				)
				(justify right bottom)
			)
		)
		(property "Value" "C_100n_0402"
			(at 0 1.4 90)
			(layer "F.Fab")
			(effects
				(font
					(size 0.7 0.7)
					(thickness 0.15)
				)
				(justify right bottom)
			)
		)
		(property "Datasheet" "https://www.murata.com/products/productdetail?partno=GRM155R61H104KE14%23"
			(at 0 0 270)
			(layer "F.Fab")
			(hide yes)
			(effects
				(font
					(size 1.27 1.27)
					(thickness 0.15)
				)
			)
		)
		(property "Description" "SMD Multilayer Ceramic Capacitor, 0.1 µF, 50 V, 0402 [1005 Metric], ± 10%, X5R, GRM Series"
			(at 0 0 270)
			(layer "F.Fab")
			(hide yes)
			(effects
				(font
					(size 1.27 1.27)
					(thickness 0.15)
				)
			)
		)
		(property "Author" "Antmicro"
			(at 4.89 237.72 0)
			(layer "F.Fab")
			(hide yes)
			(effects
				(font
					(size 1 1)
					(thickness 0.15)
				)
			)
		)
		(property "Dielectric" "X5R"
			(at 4.89 237.72 0)
			(layer "F.Fab")
			(hide yes)
			(effects
				(font
					(size 1 1)
					(thickness 0.15)
				)
			)
		)
		(property "License" "Apache-2.0"
			(at 4.89 237.72 0)
			(layer "F.Fab")
			(hide yes)
			(effects
				(font
					(size 1 1)
					(thickness 0.15)
				)
			)
		)
		(property "MPN" "GRM155R61H104KE14D"
			(at 4.89 237.72 0)
			(layer "F.Fab")
			(hide yes)
			(effects
				(font
					(size 1 1)
					(thickness 0.15)
				)
			)
		)
		(property "Manufacturer" "Murata"
			(at 4.89 237.72 0)
			(layer "F.Fab")
			(hide yes)
			(effects
				(font
					(size 1 1)
					(thickness 0.15)
				)
			)
		)
		(property "Val" "100n"
			(at 4.89 237.72 0)
			(layer "F.Fab")
			(hide yes)
			(effects
				(font
					(size 1 1)
					(thickness 0.15)
				)
			)
		)
		(property "Voltage" "50V"
			(at 4.89 237.72 0)
			(layer "F.Fab")
			(hide yes)
			(effects
				(font
					(size 1 1)
					(thickness 0.15)
				)
			)
		)
		(sheetname "/Interfaces/")
		(sheetfile "interfaces.kicad_sch")
		(attr smd)
		(fp_rect
			(start -0.925 -0.47)
			(end 0.925 0.47)
			(stroke
				(width 0.05)
				(type default)
			)
			(fill no)
			(layer "F.CrtYd")
		)
		(fp_line
			(start -0.494 0.248)
			(end -0.494 -0.25)
			(stroke
				(width 0.15)
				(type solid)
			)
			(layer "F.Fab")
		)
		(fp_line
			(start 0.504 0.248)
			(end -0.494 0.248)
			(stroke
				(width 0.15)
				(type solid)
			)
			(layer "F.Fab")
		)
		(fp_line
			(start -0.494 -0.25)
			(end 0.504 -0.25)
			(stroke
				(width 0.15)
				(type solid)
			)
			(layer "F.Fab")
		)
		(fp_line
			(start 0.504 -0.25)
			(end 0.504 0.248)
			(stroke
				(width 0.15)
				(type solid)
			)
			(layer "F.Fab")
		)
		(pad "1" smd roundrect
			(at -0.48 0 270)
			(size 0.59 0.64)
			(layers "F.Cu" "F.Mask" "F.Paste")
			(roundrect_rratio 0.25)
			(net 2 "VCC3V3")
			(pintype "passive")
		)
		(pad "2" smd roundrect
			(at 0.48 0 270)
			(size 0.59 0.64)
			(layers "F.Cu" "F.Mask" "F.Paste")
			(roundrect_rratio 0.25)
			(net 1 "GND")
			(pintype "passive")
		)
	)
	(footprint "antmicro-footprints:Oscillator_SMD_Abracon_ASEMB_3.2x2.5mm"
		(layer "F.Cu")
		(at 123.735 133.633 90)
		(property "Reference" "U23"
			(at -2.867 -0.985 180)
			(layer "F.SilkS")
			(effects
				(font
					(size 0.7 0.7)
					(thickness 0.15)
				)
				(justify left bottom)
			)
		)
		(property "Value" "Oscillator_24MHz_ASEMB"
			(at 20.284 4.161 90)
			(layer "F.Fab")
			(effects
				(font
					(size 0.7 0.7)
					(thickness 0.15)
				)
				(justify left bottom)
			)
		)
		(property "Datasheet" "https://abracon.com/Oscillators/ASEMB.pdf"
			(at 0 0 90)
			(layer "F.Fab")
			(hide yes)
			(effects
				(font
					(size 1.27 1.27)
					(thickness 0.15)
				)
			)
		)
		(property "Description" "MEMS Oscillator, Clock, Pure Silicon&trade;, 24 MHz, SMD, 3.2mm x 2.5mm, 50 ppm, 3.3 V, ASEMB, LVCMOS"
			(at 0 0 90)
			(layer "F.Fab")
			(hide yes)
			(effects
				(font
					(size 1.27 1.27)
					(thickness 0.15)
				)
			)
		)
		(property "Author" "Antmicro"
			(at 257.368 9.898 0)
			(layer "F.Fab")
			(hide yes)
			(effects
				(font
					(size 1 1)
					(thickness 0.15)
				)
			)
		)
		(property "License" "Apache-2.0"
			(at 257.368 9.898 0)
			(layer "F.Fab")
			(hide yes)
			(effects
				(font
					(size 1 1)
					(thickness 0.15)
				)
			)
		)
		(property "MPN" "ASEMB-24.000MHZ-LC-T"
			(at 257.368 9.898 0)
			(layer "F.Fab")
			(hide yes)
			(effects
				(font
					(size 1 1)
					(thickness 0.15)
				)
			)
		)
		(property "Manufacturer" "Abracon"
			(at 257.368 9.898 0)
			(layer "F.Fab")
			(hide yes)
			(effects
				(font
					(size 1 1)
					(thickness 0.15)
				)
			)
		)
		(property "Val" "24 MHz"
			(at 257.368 9.898 0)
			(layer "F.Fab")
			(hide yes)
			(effects
				(font
					(size 1 1)
					(thickness 0.15)
				)
			)
		)
		(sheetname "/Interfaces/")
		(sheetfile "interfaces.kicad_sch")
		(attr smd)
		(fp_circle
			(center -1.5748 -1.8034)
			(end -1.5248 -1.8034)
			(stroke
				(width 0.15)
				(type solid)
			)
			(fill yes)
			(layer "F.SilkS")
		)
		(fp_rect
			(start -1.752 -2.101)
			(end 1.749 2.1)
			(stroke
				(width 0.05)
				(type solid)
			)
			(fill no)
			(layer "F.CrtYd")
		)
		(fp_line
			(start -1.2192 -1.4224)
			(end -1.0668 -1.5748)
			(stroke
				(width 0.15)
				(type solid)
			)
			(layer "F.Fab")
		)
		(fp_rect
			(start -1.252 -1.601)
			(end 1.249 1.6)
			(stroke
				(width 0.15)
				(type solid)
			)
			(fill no)
			(layer "F.Fab")
		)
		(pad "1" smd rect
			(at -0.951 -1.049 90)
			(size 1 0.9)
			(layers "F.Cu" "F.Mask" "F.Paste")
			(net 2 "VCC3V3")
			(pinfunction "EN")
			(pintype "input")
		)
		(pad "2" smd rect
			(at -0.951 1.05 90)
			(size 1 0.9)
			(layers "F.Cu" "F.Mask" "F.Paste")
			(net 1 "GND")
			(pinfunction "GND")
			(pintype "power_in")
		)
		(pad "3" smd rect
			(at 0.948 1.05 90)
			(size 1 0.9)
			(layers "F.Cu" "F.Mask" "F.Paste")
			(net 656 "Net-(U18-XI)")
			(pinfunction "OUT")
			(pintype "output")
		)
		(pad "4" smd rect
			(at 0.948 -1.049 90)
			(size 1 0.9)
			(layers "F.Cu" "F.Mask" "F.Paste")
			(net 2 "VCC3V3")
			(pinfunction "VDD")
			(pintype "power_in")
		)
	)
	(footprint "antmicro-footprints:Oscillator_SMD_Abracon_ASEMB_3.2x2.5mm"
		(layer "F.Cu")
		(at 123.905 116.883 90)
		(property "Reference" "U24"
			(at -2.917 -0.905 180)
			(layer "F.SilkS")
			(effects
				(font
					(size 0.7 0.7)
					(thickness 0.15)
				)
				(justify left bottom)
			)
		)
		(property "Value" "Oscillator_24MHz_ASEMB"
			(at 20.284 4.161 90)
			(layer "F.Fab")
			(effects
				(font
					(size 0.7 0.7)
					(thickness 0.15)
				)
				(justify left bottom)
			)
		)
		(property "Datasheet" "https://abracon.com/Oscillators/ASEMB.pdf"
			(at 0 0 90)
			(layer "F.Fab")
			(hide yes)
			(effects
				(font
					(size 1.27 1.27)
					(thickness 0.15)
				)
			)
		)
		(property "Description" "MEMS Oscillator, Clock, Pure Silicon&trade;, 24 MHz, SMD, 3.2mm x 2.5mm, 50 ppm, 3.3 V, ASEMB, LVCMOS"
			(at 0 0 90)
			(layer "F.Fab")
			(hide yes)
			(effects
				(font
					(size 1.27 1.27)
					(thickness 0.15)
				)
			)
		)
		(property "Author" "Antmicro"
			(at 240.788 -7.022 0)
			(layer "F.Fab")
			(hide yes)
			(effects
				(font
					(size 1 1)
					(thickness 0.15)
				)
			)
		)
		(property "License" "Apache-2.0"
			(at 240.788 -7.022 0)
			(layer "F.Fab")
			(hide yes)
			(effects
				(font
					(size 1 1)
					(thickness 0.15)
				)
			)
		)
		(property "MPN" "ASEMB-24.000MHZ-LC-T"
			(at 240.788 -7.022 0)
			(layer "F.Fab")
			(hide yes)
			(effects
				(font
					(size 1 1)
					(thickness 0.15)
				)
			)
		)
		(property "Manufacturer" "Abracon"
			(at 240.788 -7.022 0)
			(layer "F.Fab")
			(hide yes)
			(effects
				(font
					(size 1 1)
					(thickness 0.15)
				)
			)
		)
		(property "Val" "24 MHz"
			(at 240.788 -7.022 0)
			(layer "F.Fab")
			(hide yes)
			(effects
				(font
					(size 1 1)
					(thickness 0.15)
				)
			)
		)
		(sheetname "/Interfaces/")
		(sheetfile "interfaces.kicad_sch")
		(attr smd)
		(fp_circle
			(center -1.5748 -1.8034)
			(end -1.5248 -1.8034)
			(stroke
				(width 0.15)
				(type solid)
			)
			(fill yes)
			(layer "F.SilkS")
		)
		(fp_rect
			(start -1.752 -2.101)
			(end 1.749 2.1)
			(stroke
				(width 0.05)
				(type solid)
			)
			(fill no)
			(layer "F.CrtYd")
		)
		(fp_line
			(start -1.2192 -1.4224)
			(end -1.0668 -1.5748)
			(stroke
				(width 0.15)
				(type solid)
			)
			(layer "F.Fab")
		)
		(fp_rect
			(start -1.252 -1.601)
			(end 1.249 1.6)
			(stroke
				(width 0.15)
				(type solid)
			)
			(fill no)
			(layer "F.Fab")
		)
		(pad "1" smd rect
			(at -0.951 -1.049 90)
			(size 1 0.9)
			(layers "F.Cu" "F.Mask" "F.Paste")
			(net 2 "VCC3V3")
			(pinfunction "EN")
			(pintype "input")
		)
		(pad "2" smd rect
			(at -0.951 1.05 90)
			(size 1 0.9)
			(layers "F.Cu" "F.Mask" "F.Paste")
			(net 1 "GND")
			(pinfunction "GND")
			(pintype "power_in")
		)
		(pad "3" smd rect
			(at 0.948 1.05 90)
			(size 1 0.9)
			(layers "F.Cu" "F.Mask" "F.Paste")
			(net 651 "Net-(U17-XI)")
			(pinfunction "OUT")
			(pintype "output")
		)
		(pad "4" smd rect
			(at 0.948 -1.049 90)
			(size 1 0.9)
			(layers "F.Cu" "F.Mask" "F.Paste")
			(net 2 "VCC3V3")
			(pinfunction "VDD")
			(pintype "power_in")
		)
	)
	(footprint "antmicro-footprints:TP_SMD_1mm"
		(layer "F.Cu")
		(at 104.055 164.1058)
		(property "Reference" "TP10"
			(at -2.055 1.5842 0)
			(layer "F.SilkS")
			(effects
				(font
					(size 0.7 0.7)
					(thickness 0.15)
				)
				(justify left bottom)
			)
		)
		(property "Value" "TP_1mm_SMD"
			(at 0 1.4 0)
			(layer "F.Fab")
			(effects
				(font
					(size 0.7 0.7)
					(thickness 0.15)
				)
				(justify left bottom)
			)
		)
		(property "Description" "Test point 1mm SMD"
			(at 0 0 0)
			(layer "F.Fab")
			(hide yes)
			(effects
				(font
					(size 1.27 1.27)
					(thickness 0.15)
				)
			)
		)
		(property "Author" "Antmicro"
			(at 0 0 0)
			(layer "F.Fab")
			(hide yes)
			(effects
				(font
					(size 1 1)
					(thickness 0.15)
				)
			)
		)
		(property "License" "Apache-2.0"
			(at 0 0 0)
			(layer "F.Fab")
			(hide yes)
			(effects
				(font
					(size 1 1)
					(thickness 0.15)
				)
			)
		)
		(property "MPN" ""
			(at 0 0 0)
			(layer "F.Fab")
			(hide yes)
			(effects
				(font
					(size 1 1)
					(thickness 0.15)
				)
			)
		)
		(property "Manufacturer" ""
			(at 0 0 0)
			(layer "F.Fab")
			(hide yes)
			(effects
				(font
					(size 1 1)
					(thickness 0.15)
				)
			)
		)
		(sheetname "/Edge connector/")
		(sheetfile "edge-connector.kicad_sch")
		(attr exclude_from_pos_files exclude_from_bom)
		(fp_circle
			(center 0 0)
			(end 0.6 0)
			(stroke
				(width 0.05)
				(type default)
			)
			(fill no)
			(layer "F.CrtYd")
		)
		(pad "1" smd circle
			(at 0 0)
			(size 1 1)
			(layers "F.Cu" "F.Mask")
			(net 84 "PECI_BMC")
			(pinfunction "1")
			(pintype "passive")
		)
	)
	(footprint "antmicro-footprints:TP_SMD_1mm"
		(layer "F.Cu")
		(at 105.705 164.1158)
		(property "Reference" "TP11"
			(at -0.405 1.5842 0)
			(layer "F.SilkS")
			(effects
				(font
					(size 0.7 0.7)
					(thickness 0.15)
				)
				(justify left bottom)
			)
		)
		(property "Value" "TP_1mm_SMD"
			(at 0 1.4 0)
			(layer "F.Fab")
			(effects
				(font
					(size 0.7 0.7)
					(thickness 0.15)
				)
				(justify left bottom)
			)
		)
		(property "Description" "Test point 1mm SMD"
			(at 0 0 0)
			(layer "F.Fab")
			(hide yes)
			(effects
				(font
					(size 1.27 1.27)
					(thickness 0.15)
				)
			)
		)
		(property "Author" "Antmicro"
			(at 0 0 0)
			(layer "F.Fab")
			(hide yes)
			(effects
				(font
					(size 1 1)
					(thickness 0.15)
				)
			)
		)
		(property "License" "Apache-2.0"
			(at 0 0 0)
			(layer "F.Fab")
			(hide yes)
			(effects
				(font
					(size 1 1)
					(thickness 0.15)
				)
			)
		)
		(property "MPN" ""
			(at 0 0 0)
			(layer "F.Fab")
			(hide yes)
			(effects
				(font
					(size 1 1)
					(thickness 0.15)
				)
			)
		)
		(property "Manufacturer" ""
			(at 0 0 0)
			(layer "F.Fab")
			(hide yes)
			(effects
				(font
					(size 1 1)
					(thickness 0.15)
				)
			)
		)
		(sheetname "/Edge connector/")
		(sheetfile "edge-connector.kicad_sch")
		(attr exclude_from_pos_files exclude_from_bom)
		(fp_circle
			(center 0 0)
			(end 0.6 0)
			(stroke
				(width 0.05)
				(type default)
			)
			(fill no)
			(layer "F.CrtYd")
		)
		(pad "1" smd circle
			(at 0 0)
			(size 1 1)
			(layers "F.Cu" "F.Mask")
			(net 85 "PVCCIO_PECI")
			(pinfunction "1")
			(pintype "passive")
		)
	)
	(footprint "antmicro-footprints:C_0402_1005Metric"
		(layer "F.Cu")
		(at 108.66 95.73 90)
		(descr "Capacitor SMD 0402")
		(tags "capacitor SMD 0402")
		(property "Reference" "C176"
			(at -3.67 0.44 90)
			(layer "F.SilkS")
			(effects
				(font
					(size 0.7 0.7)
					(thickness 0.15)
				)
				(justify left bottom)
			)
		)
		(property "Value" "C_22p_0402"
			(at 0 1.4 90)
			(layer "F.Fab")
			(effects
				(font
					(size 0.7 0.7)
					(thickness 0.15)
				)
				(justify left bottom)
			)
		)
		(property "Datasheet" "https://www.yageo.com/en/Chart/Download/pdf/CC0402JRNPO9BN220"
			(at 0 0 90)
			(layer "F.Fab")
			(hide yes)
			(effects
				(font
					(size 1.27 1.27)
					(thickness 0.15)
				)
			)
		)
		(property "Description" "SMD Multilayer Ceramic Capacitor, 22 pF, 50 V, 0402 [1005 Metric], ± 5%, C0G / NP0, CC Series"
			(at 0 0 90)
			(layer "F.Fab")
			(hide yes)
			(effects
				(font
					(size 1.27 1.27)
					(thickness 0.15)
				)
			)
		)
		(property "Author" "Antmicro"
			(at 204.39 -12.93 0)
			(layer "F.Fab")
			(hide yes)
			(effects
				(font
					(size 1 1)
					(thickness 0.15)
				)
			)
		)
		(property "Dielectric" ""
			(at 204.39 -12.93 0)
			(layer "F.Fab")
			(hide yes)
			(effects
				(font
					(size 1 1)
					(thickness 0.15)
				)
			)
		)
		(property "License" "Apache-2.0"
			(at 204.39 -12.93 0)
			(layer "F.Fab")
			(hide yes)
			(effects
				(font
					(size 1 1)
					(thickness 0.15)
				)
			)
		)
		(property "MPN" "CC0402JRNPO9BN220"
			(at 204.39 -12.93 0)
			(layer "F.Fab")
			(hide yes)
			(effects
				(font
					(size 1 1)
					(thickness 0.15)
				)
			)
		)
		(property "Manufacturer" "YAGEO"
			(at 204.39 -12.93 0)
			(layer "F.Fab")
			(hide yes)
			(effects
				(font
					(size 1 1)
					(thickness 0.15)
				)
			)
		)
		(property "Val" "22p"
			(at 204.39 -12.93 0)
			(layer "F.Fab")
			(hide yes)
			(effects
				(font
					(size 1 1)
					(thickness 0.15)
				)
			)
		)
		(property "Voltage" ""
			(at 204.39 -12.93 0)
			(layer "F.Fab")
			(hide yes)
			(effects
				(font
					(size 1 1)
					(thickness 0.15)
				)
			)
		)
		(sheetname "/Ethernet/")
		(sheetfile "ethernet.kicad_sch")
		(attr smd)
		(fp_rect
			(start -0.925 -0.47)
			(end 0.925 0.47)
			(stroke
				(width 0.05)
				(type default)
			)
			(fill no)
			(layer "F.CrtYd")
		)
		(fp_line
			(start 0.504 -0.25)
			(end 0.504 0.248)
			(stroke
				(width 0.15)
				(type solid)
			)
			(layer "F.Fab")
		)
		(fp_line
			(start -0.494 -0.25)
			(end 0.504 -0.25)
			(stroke
				(width 0.15)
				(type solid)
			)
			(layer "F.Fab")
		)
		(fp_line
			(start 0.504 0.248)
			(end -0.494 0.248)
			(stroke
				(width 0.15)
				(type solid)
			)
			(layer "F.Fab")
		)
		(fp_line
			(start -0.494 0.248)
			(end -0.494 -0.25)
			(stroke
				(width 0.15)
				(type solid)
			)
			(layer "F.Fab")
		)
		(pad "1" smd roundrect
			(at -0.48 0 90)
			(size 0.59 0.64)
			(layers "F.Cu" "F.Mask" "F.Paste")
			(roundrect_rratio 0.25)
			(net 1 "GND")
			(pintype "passive")
		)
		(pad "2" smd roundrect
			(at 0.48 0 90)
			(size 0.59 0.64)
			(layers "F.Cu" "F.Mask" "F.Paste")
			(roundrect_rratio 0.25)
			(net 199 "Net-(U20-XO)")
			(pintype "passive")
		)
	)
	(footprint "antmicro-footprints:C_0402_1005Metric"
		(layer "F.Cu")
		(at 108.65 93.21 -90)
		(descr "Capacitor SMD 0402")
		(tags "capacitor SMD 0402")
		(property "Reference" "C220"
			(at -3.61 -0.45 90)
			(layer "F.SilkS")
			(effects
				(font
					(size 0.7 0.7)
					(thickness 0.15)
				)
				(justify right bottom)
			)
		)
		(property "Value" "C_22p_0402"
			(at 0 1.4 90)
			(layer "F.Fab")
			(effects
				(font
					(size 0.7 0.7)
					(thickness 0.15)
				)
				(justify right bottom)
			)
		)
		(property "Datasheet" "https://www.yageo.com/en/Chart/Download/pdf/CC0402JRNPO9BN220"
			(at 0 0 270)
			(layer "F.Fab")
			(hide yes)
			(effects
				(font
					(size 1.27 1.27)
					(thickness 0.15)
				)
			)
		)
		(property "Description" "SMD Multilayer Ceramic Capacitor, 22 pF, 50 V, 0402 [1005 Metric], ± 5%, C0G / NP0, CC Series"
			(at 0 0 270)
			(layer "F.Fab")
			(hide yes)
			(effects
				(font
					(size 1.27 1.27)
					(thickness 0.15)
				)
			)
		)
		(property "Author" "Antmicro"
			(at 15.44 201.86 0)
			(layer "F.Fab")
			(hide yes)
			(effects
				(font
					(size 1 1)
					(thickness 0.15)
				)
			)
		)
		(property "Dielectric" ""
			(at 15.44 201.86 0)
			(layer "F.Fab")
			(hide yes)
			(effects
				(font
					(size 1 1)
					(thickness 0.15)
				)
			)
		)
		(property "License" "Apache-2.0"
			(at 15.44 201.86 0)
			(layer "F.Fab")
			(hide yes)
			(effects
				(font
					(size 1 1)
					(thickness 0.15)
				)
			)
		)
		(property "MPN" "CC0402JRNPO9BN220"
			(at 15.44 201.86 0)
			(layer "F.Fab")
			(hide yes)
			(effects
				(font
					(size 1 1)
					(thickness 0.15)
				)
			)
		)
		(property "Manufacturer" "YAGEO"
			(at 15.44 201.86 0)
			(layer "F.Fab")
			(hide yes)
			(effects
				(font
					(size 1 1)
					(thickness 0.15)
				)
			)
		)
		(property "Val" "22p"
			(at 15.44 201.86 0)
			(layer "F.Fab")
			(hide yes)
			(effects
				(font
					(size 1 1)
					(thickness 0.15)
				)
			)
		)
		(property "Voltage" ""
			(at 15.44 201.86 0)
			(layer "F.Fab")
			(hide yes)
			(effects
				(font
					(size 1 1)
					(thickness 0.15)
				)
			)
		)
		(sheetname "/Ethernet/")
		(sheetfile "ethernet.kicad_sch")
		(attr smd)
		(fp_rect
			(start -0.925 -0.47)
			(end 0.925 0.47)
			(stroke
				(width 0.05)
				(type default)
			)
			(fill no)
			(layer "F.CrtYd")
		)
		(fp_line
			(start -0.494 0.248)
			(end -0.494 -0.25)
			(stroke
				(width 0.15)
				(type solid)
			)
			(layer "F.Fab")
		)
		(fp_line
			(start 0.504 0.248)
			(end -0.494 0.248)
			(stroke
				(width 0.15)
				(type solid)
			)
			(layer "F.Fab")
		)
		(fp_line
			(start -0.494 -0.25)
			(end 0.504 -0.25)
			(stroke
				(width 0.15)
				(type solid)
			)
			(layer "F.Fab")
		)
		(fp_line
			(start 0.504 -0.25)
			(end 0.504 0.248)
			(stroke
				(width 0.15)
				(type solid)
			)
			(layer "F.Fab")
		)
		(pad "1" smd roundrect
			(at -0.48 0 270)
			(size 0.59 0.64)
			(layers "F.Cu" "F.Mask" "F.Paste")
			(roundrect_rratio 0.25)
			(net 1 "GND")
			(pintype "passive")
		)
		(pad "2" smd roundrect
			(at 0.48 0 270)
			(size 0.59 0.64)
			(layers "F.Cu" "F.Mask" "F.Paste")
			(roundrect_rratio 0.25)
			(net 201 "Net-(U20-XI)")
			(pintype "passive")
		)
	)
	(footprint "antmicro-footprints:R_0402_1005Metric"
		(layer "F.Cu")
		(at 107.64 94.73 90)
		(descr "Resistor SMD 0402")
		(tags "resistor SMD 0402")
		(property "Reference" "R194"
			(at 0.73 0.36 90)
			(layer "F.SilkS")
			(effects
				(font
					(size 0.7 0.7)
					(thickness 0.15)
				)
				(justify left bottom)
			)
		)
		(property "Value" "R_1M8_0402"
			(at 0 1.4 90)
			(layer "F.Fab")
			(effects
				(font
					(size 0.7 0.7)
					(thickness 0.15)
				)
				(justify left bottom)
			)
		)
		(property "Datasheet" "https://www.bourns.com/docs/product-datasheets/cr.pdf"
			(at 0 0 90)
			(layer "F.Fab")
			(hide yes)
			(effects
				(font
					(size 1.27 1.27)
					(thickness 0.15)
				)
			)
		)
		(property "Description" "SMD Chip Resistor"
			(at 0 0 90)
			(layer "F.Fab")
			(hide yes)
			(effects
				(font
					(size 1.27 1.27)
					(thickness 0.15)
				)
			)
		)
		(property "Author" "Antmicro"
			(at 202.37 -12.91 0)
			(layer "F.Fab")
			(hide yes)
			(effects
				(font
					(size 1 1)
					(thickness 0.15)
				)
			)
		)
		(property "License" "Apache-2.0"
			(at 202.37 -12.91 0)
			(layer "F.Fab")
			(hide yes)
			(effects
				(font
					(size 1 1)
					(thickness 0.15)
				)
			)
		)
		(property "MPN" "CR0402-FX-1804GLF"
			(at 202.37 -12.91 0)
			(layer "F.Fab")
			(hide yes)
			(effects
				(font
					(size 1 1)
					(thickness 0.15)
				)
			)
		)
		(property "Manufacturer" "Bourns"
			(at 202.37 -12.91 0)
			(layer "F.Fab")
			(hide yes)
			(effects
				(font
					(size 1 1)
					(thickness 0.15)
				)
			)
		)
		(property "Tolerance" "1%"
			(at 202.37 -12.91 0)
			(layer "F.Fab")
			(hide yes)
			(effects
				(font
					(size 1 1)
					(thickness 0.15)
				)
			)
		)
		(property "Val" "1M8"
			(at 202.37 -12.91 0)
			(layer "F.Fab")
			(hide yes)
			(effects
				(font
					(size 1 1)
					(thickness 0.15)
				)
			)
		)
		(sheetname "/Ethernet/")
		(sheetfile "ethernet.kicad_sch")
		(attr smd)
		(fp_rect
			(start -0.925 -0.47)
			(end 0.925 0.47)
			(stroke
				(width 0.05)
				(type default)
			)
			(fill no)
			(layer "F.CrtYd")
		)
		(fp_rect
			(start -0.5 -0.25)
			(end 0.5 0.25)
			(stroke
				(width 0.15)
				(type solid)
			)
			(fill no)
			(layer "F.Fab")
		)
		(pad "1" smd roundrect
			(at -0.48 0 90)
			(size 0.59 0.64)
			(layers "F.Cu" "F.Mask" "F.Paste")
			(roundrect_rratio 0.25)
			(net 199 "Net-(U20-XO)")
			(pintype "passive")
		)
		(pad "2" smd roundrect
			(at 0.48 0 90)
			(size 0.59 0.64)
			(layers "F.Cu" "F.Mask" "F.Paste")
			(roundrect_rratio 0.25)
			(net 201 "Net-(U20-XI)")
			(pintype "passive")
		)
	)
	(footprint "antmicro-footprints:Resonator_SMD_Abracon_ABM8G_3.2x2.5mm"
		(layer "F.Cu")
		(at 110.91 95.18 90)
		(property "Reference" "Y2"
			(at 2.08 1.69 180)
			(layer "F.SilkS")
			(effects
				(font
					(size 0.7 0.7)
					(thickness 0.15)
				)
				(justify right bottom)
			)
		)
		(property "Value" "Resonator_25MHz_ABM8G"
			(at -1.75 2.548 90)
			(layer "F.Fab")
			(effects
				(font
					(size 0.7 0.7)
					(thickness 0.15)
				)
				(justify left bottom)
			)
		)
		(property "Datasheet" "https://abracon.com/Resonators/ABM8G.pdf"
			(at 0 0 90)
			(layer "F.Fab")
			(hide yes)
			(effects
				(font
					(size 1.27 1.27)
					(thickness 0.15)
				)
			)
		)
		(property "Description" "Crystal, 25 MHz, SMD, 3.2mm x 2.5mm, 30 ppm, 18 pF, 20 ppm, ABM8G"
			(at 0 0 90)
			(layer "F.Fab")
			(hide yes)
			(effects
				(font
					(size 1.27 1.27)
					(thickness 0.15)
				)
			)
		)
		(property "Author" "Antmicro"
			(at 206.09 -15.73 0)
			(layer "F.Fab")
			(hide yes)
			(effects
				(font
					(size 1 1)
					(thickness 0.15)
				)
			)
		)
		(property "License" "Apache-2.0"
			(at 206.09 -15.73 0)
			(layer "F.Fab")
			(hide yes)
			(effects
				(font
					(size 1 1)
					(thickness 0.15)
				)
			)
		)
		(property "MPN" "ABM8G-25.000MHZ-18-D2Y-T3"
			(at 206.09 -15.73 0)
			(layer "F.Fab")
			(hide yes)
			(effects
				(font
					(size 1 1)
					(thickness 0.15)
				)
			)
		)
		(property "Manufacturer" "Abracon"
			(at 206.09 -15.73 0)
			(layer "F.Fab")
			(hide yes)
			(effects
				(font
					(size 1 1)
					(thickness 0.15)
				)
			)
		)
		(property "Val" "25 MHz"
			(at 206.09 -15.73 0)
			(layer "F.Fab")
			(hide yes)
			(effects
				(font
					(size 1 1)
					(thickness 0.15)
				)
			)
		)
		(sheetname "/Ethernet/")
		(sheetfile "ethernet.kicad_sch")
		(attr smd)
		(fp_line
			(start -0.35 -1.25)
			(end 0.45 -1.25)
			(stroke
				(width 0.15)
				(type solid)
			)
			(layer "F.SilkS")
		)
		(fp_line
			(start 1.6 0.3)
			(end 1.6 -0.2)
			(stroke
				(width 0.15)
				(type solid)
			)
			(layer "F.SilkS")
		)
		(fp_line
			(start -1.6 0.3)
			(end -1.6 -0.2)
			(stroke
				(width 0.15)
				(type solid)
			)
			(layer "F.SilkS")
		)
		(fp_line
			(start -0.35 1.25)
			(end 0.45 1.25)
			(stroke
				(width 0.15)
				(type solid)
			)
			(layer "F.SilkS")
		)
		(fp_circle
			(center -1.75 1.5)
			(end -1.7 1.5)
			(stroke
				(width 0.15)
				(type solid)
			)
			(fill no)
			(layer "F.SilkS")
		)
		(fp_rect
			(start -1.907 -1.55)
			(end 2.006 1.649)
			(stroke
				(width 0.05)
				(type solid)
			)
			(fill no)
			(layer "F.CrtYd")
		)
		(pad "1" smd roundrect
			(at -1.101 0.949 90)
			(size 1.3 1.1)
			(layers "F.Cu" "F.Mask" "F.Paste")
			(roundrect_rratio 0)
			(chamfer_ratio 0.2)
			(chamfer bottom_left)
			(net 199 "Net-(U20-XO)")
			(pintype "passive")
		)
		(pad "2" smd rect
			(at 1.199 0.949 90)
			(size 1.3 1.1)
			(layers "F.Cu" "F.Mask" "F.Paste")
			(net 1 "GND")
			(pinfunction "SH")
			(pintype "passive")
		)
		(pad "3" smd rect
			(at 1.199 -0.85 90)
			(size 1.3 1.1)
			(layers "F.Cu" "F.Mask" "F.Paste")
			(net 201 "Net-(U20-XI)")
			(pintype "passive")
		)
		(pad "4" smd rect
			(at -1.101 -0.85 90)
			(size 1.3 1.1)
			(layers "F.Cu" "F.Mask" "F.Paste")
			(net 1 "GND")
			(pinfunction "SH")
			(pintype "passive")
		)
	)
	(footprint "antmicro-footprints:C_0402_1005Metric"
		(layer "F.Cu")
		(at 141.35 91.7125 180)
		(descr "Capacitor SMD 0402")
		(tags "capacitor SMD 0402")
		(property "Reference" "C6"
			(at -2.25 -0.2875 0)
			(layer "F.SilkS")
			(effects
				(font
					(size 0.7 0.7)
					(thickness 0.15)
				)
				(justify right bottom)
			)
		)
		(property "Value" "C_100n_0402"
			(at 0 1.4 0)
			(layer "F.Fab")
			(effects
				(font
					(size 0.7 0.7)
					(thickness 0.15)
				)
				(justify right bottom)
			)
		)
		(property "Datasheet" "https://www.murata.com/products/productdetail?partno=GRM155R61H104KE14%23"
			(at 0 0 180)
			(layer "F.Fab")
			(hide yes)
			(effects
				(font
					(size 1.27 1.27)
					(thickness 0.15)
				)
			)
		)
		(property "Description" "SMD Multilayer Ceramic Capacitor, 0.1 µF, 50 V, 0402 [1005 Metric], ± 10%, X5R, GRM Series"
			(at 0 0 180)
			(layer "F.Fab")
			(hide yes)
			(effects
				(font
					(size 1.27 1.27)
					(thickness 0.15)
				)
			)
		)
		(property "Author" "Antmicro"
			(at 282.7 183.425 0)
			(layer "F.Fab")
			(hide yes)
			(effects
				(font
					(size 1 1)
					(thickness 0.15)
				)
			)
		)
		(property "Dielectric" "X5R"
			(at 282.7 183.425 0)
			(layer "F.Fab")
			(hide yes)
			(effects
				(font
					(size 1 1)
					(thickness 0.15)
				)
			)
		)
		(property "License" "Apache-2.0"
			(at 282.7 183.425 0)
			(layer "F.Fab")
			(hide yes)
			(effects
				(font
					(size 1 1)
					(thickness 0.15)
				)
			)
		)
		(property "MPN" "GRM155R61H104KE14D"
			(at 282.7 183.425 0)
			(layer "F.Fab")
			(hide yes)
			(effects
				(font
					(size 1 1)
					(thickness 0.15)
				)
			)
		)
		(property "Manufacturer" "Murata"
			(at 282.7 183.425 0)
			(layer "F.Fab")
			(hide yes)
			(effects
				(font
					(size 1 1)
					(thickness 0.15)
				)
			)
		)
		(property "Val" "100n"
			(at 282.7 183.425 0)
			(layer "F.Fab")
			(hide yes)
			(effects
				(font
					(size 1 1)
					(thickness 0.15)
				)
			)
		)
		(property "Voltage" "50V"
			(at 282.7 183.425 0)
			(layer "F.Fab")
			(hide yes)
			(effects
				(font
					(size 1 1)
					(thickness 0.15)
				)
			)
		)
		(sheetname "/Interfaces/")
		(sheetfile "interfaces.kicad_sch")
		(attr smd)
		(fp_rect
			(start -0.925 -0.47)
			(end 0.925 0.47)
			(stroke
				(width 0.05)
				(type default)
			)
			(fill no)
			(layer "F.CrtYd")
		)
		(fp_line
			(start 0.504 0.248)
			(end -0.494 0.248)
			(stroke
				(width 0.15)
				(type solid)
			)
			(layer "F.Fab")
		)
		(fp_line
			(start 0.504 -0.25)
			(end 0.504 0.248)
			(stroke
				(width 0.15)
				(type solid)
			)
			(layer "F.Fab")
		)
		(fp_line
			(start -0.494 0.248)
			(end -0.494 -0.25)
			(stroke
				(width 0.15)
				(type solid)
			)
			(layer "F.Fab")
		)
		(fp_line
			(start -0.494 -0.25)
			(end 0.504 -0.25)
			(stroke
				(width 0.15)
				(type solid)
			)
			(layer "F.Fab")
		)
		(pad "1" smd roundrect
			(at -0.48 0 180)
			(size 0.59 0.64)
			(layers "F.Cu" "F.Mask" "F.Paste")
			(roundrect_rratio 0.25)
			(net 1 "GND")
			(pintype "passive")
		)
		(pad "2" smd roundrect
			(at 0.48 0 180)
			(size 0.59 0.64)
			(layers "F.Cu" "F.Mask" "F.Paste")
			(roundrect_rratio 0.25)
			(net 597 "1V8_FT")
			(pintype "passive")
		)
	)
	(footprint "antmicro-footprints:C_0402_1005Metric"
		(layer "F.Cu")
		(at 141.35 99.0125 180)
		(descr "Capacitor SMD 0402")
		(tags "capacitor SMD 0402")
		(property "Reference" "C7"
			(at -2.35 -0.2875 0)
			(layer "F.SilkS")
			(effects
				(font
					(size 0.7 0.7)
					(thickness 0.15)
				)
				(justify right bottom)
			)
		)
		(property "Value" "C_100n_0402"
			(at 0 1.4 0)
			(layer "F.Fab")
			(effects
				(font
					(size 0.7 0.7)
					(thickness 0.15)
				)
				(justify right bottom)
			)
		)
		(property "Datasheet" "https://www.murata.com/products/productdetail?partno=GRM155R61H104KE14%23"
			(at 0 0 180)
			(layer "F.Fab")
			(hide yes)
			(effects
				(font
					(size 1.27 1.27)
					(thickness 0.15)
				)
			)
		)
		(property "Description" "SMD Multilayer Ceramic Capacitor, 0.1 µF, 50 V, 0402 [1005 Metric], ± 10%, X5R, GRM Series"
			(at 0 0 180)
			(layer "F.Fab")
			(hide yes)
			(effects
				(font
					(size 1.27 1.27)
					(thickness 0.15)
				)
			)
		)
		(property "Author" "Antmicro"
			(at 282.7 198.025 0)
			(layer "F.Fab")
			(hide yes)
			(effects
				(font
					(size 1 1)
					(thickness 0.15)
				)
			)
		)
		(property "Dielectric" "X5R"
			(at 282.7 198.025 0)
			(layer "F.Fab")
			(hide yes)
			(effects
				(font
					(size 1 1)
					(thickness 0.15)
				)
			)
		)
		(property "License" "Apache-2.0"
			(at 282.7 198.025 0)
			(layer "F.Fab")
			(hide yes)
			(effects
				(font
					(size 1 1)
					(thickness 0.15)
				)
			)
		)
		(property "MPN" "GRM155R61H104KE14D"
			(at 282.7 198.025 0)
			(layer "F.Fab")
			(hide yes)
			(effects
				(font
					(size 1 1)
					(thickness 0.15)
				)
			)
		)
		(property "Manufacturer" "Murata"
			(at 282.7 198.025 0)
			(layer "F.Fab")
			(hide yes)
			(effects
				(font
					(size 1 1)
					(thickness 0.15)
				)
			)
		)
		(property "Val" "100n"
			(at 282.7 198.025 0)
			(layer "F.Fab")
			(hide yes)
			(effects
				(font
					(size 1 1)
					(thickness 0.15)
				)
			)
		)
		(property "Voltage" "50V"
			(at 282.7 198.025 0)
			(layer "F.Fab")
			(hide yes)
			(effects
				(font
					(size 1 1)
					(thickness 0.15)
				)
			)
		)
		(sheetname "/Interfaces/")
		(sheetfile "interfaces.kicad_sch")
		(attr smd)
		(fp_rect
			(start -0.925 -0.47)
			(end 0.925 0.47)
			(stroke
				(width 0.05)
				(type default)
			)
			(fill no)
			(layer "F.CrtYd")
		)
		(fp_line
			(start 0.504 0.248)
			(end -0.494 0.248)
			(stroke
				(width 0.15)
				(type solid)
			)
			(layer "F.Fab")
		)
		(fp_line
			(start 0.504 -0.25)
			(end 0.504 0.248)
			(stroke
				(width 0.15)
				(type solid)
			)
			(layer "F.Fab")
		)
		(fp_line
			(start -0.494 0.248)
			(end -0.494 -0.25)
			(stroke
				(width 0.15)
				(type solid)
			)
			(layer "F.Fab")
		)
		(fp_line
			(start -0.494 -0.25)
			(end 0.504 -0.25)
			(stroke
				(width 0.15)
				(type solid)
			)
			(layer "F.Fab")
		)
		(pad "1" smd roundrect
			(at -0.48 0 180)
			(size 0.59 0.64)
			(layers "F.Cu" "F.Mask" "F.Paste")
			(roundrect_rratio 0.25)
			(net 1 "GND")
			(pintype "passive")
		)
		(pad "2" smd roundrect
			(at 0.48 0 180)
			(size 0.59 0.64)
			(layers "F.Cu" "F.Mask" "F.Paste")
			(roundrect_rratio 0.25)
			(net 597 "1V8_FT")
			(pintype "passive")
		)
	)
	(footprint "antmicro-footprints:C_0402_1005Metric"
		(layer "F.Cu")
		(at 132.85 101.8125 90)
		(descr "Capacitor SMD 0402")
		(tags "capacitor SMD 0402")
		(property "Reference" "C107"
			(at -3.6875 0.45 90)
			(layer "F.SilkS")
			(effects
				(font
					(size 0.7 0.7)
					(thickness 0.15)
				)
				(justify left bottom)
			)
		)
		(property "Value" "C_100n_0402"
			(at 0 1.4 90)
			(layer "F.Fab")
			(effects
				(font
					(size 0.7 0.7)
					(thickness 0.15)
				)
				(justify left bottom)
			)
		)
		(property "Datasheet" "https://www.murata.com/products/productdetail?partno=GRM155R61H104KE14%23"
			(at 0 0 90)
			(layer "F.Fab")
			(hide yes)
			(effects
				(font
					(size 1.27 1.27)
					(thickness 0.15)
				)
			)
		)
		(property "Description" "SMD Multilayer Ceramic Capacitor, 0.1 µF, 50 V, 0402 [1005 Metric], ± 10%, X5R, GRM Series"
			(at 0 0 90)
			(layer "F.Fab")
			(hide yes)
			(effects
				(font
					(size 1.27 1.27)
					(thickness 0.15)
				)
			)
		)
		(property "Author" "Antmicro"
			(at 234.6625 -31.0375 0)
			(layer "F.Fab")
			(hide yes)
			(effects
				(font
					(size 1 1)
					(thickness 0.15)
				)
			)
		)
		(property "Dielectric" "X5R"
			(at 234.6625 -31.0375 0)
			(layer "F.Fab")
			(hide yes)
			(effects
				(font
					(size 1 1)
					(thickness 0.15)
				)
			)
		)
		(property "License" "Apache-2.0"
			(at 234.6625 -31.0375 0)
			(layer "F.Fab")
			(hide yes)
			(effects
				(font
					(size 1 1)
					(thickness 0.15)
				)
			)
		)
		(property "MPN" "GRM155R61H104KE14D"
			(at 234.6625 -31.0375 0)
			(layer "F.Fab")
			(hide yes)
			(effects
				(font
					(size 1 1)
					(thickness 0.15)
				)
			)
		)
		(property "Manufacturer" "Murata"
			(at 234.6625 -31.0375 0)
			(layer "F.Fab")
			(hide yes)
			(effects
				(font
					(size 1 1)
					(thickness 0.15)
				)
			)
		)
		(property "Val" "100n"
			(at 234.6625 -31.0375 0)
			(layer "F.Fab")
			(hide yes)
			(effects
				(font
					(size 1 1)
					(thickness 0.15)
				)
			)
		)
		(property "Voltage" "50V"
			(at 234.6625 -31.0375 0)
			(layer "F.Fab")
			(hide yes)
			(effects
				(font
					(size 1 1)
					(thickness 0.15)
				)
			)
		)
		(sheetname "/Interfaces/")
		(sheetfile "interfaces.kicad_sch")
		(attr smd)
		(fp_rect
			(start -0.925 -0.47)
			(end 0.925 0.47)
			(stroke
				(width 0.05)
				(type default)
			)
			(fill no)
			(layer "F.CrtYd")
		)
		(fp_line
			(start 0.504 -0.25)
			(end 0.504 0.248)
			(stroke
				(width 0.15)
				(type solid)
			)
			(layer "F.Fab")
		)
		(fp_line
			(start -0.494 -0.25)
			(end 0.504 -0.25)
			(stroke
				(width 0.15)
				(type solid)
			)
			(layer "F.Fab")
		)
		(fp_line
			(start 0.504 0.248)
			(end -0.494 0.248)
			(stroke
				(width 0.15)
				(type solid)
			)
			(layer "F.Fab")
		)
		(fp_line
			(start -0.494 0.248)
			(end -0.494 -0.25)
			(stroke
				(width 0.15)
				(type solid)
			)
			(layer "F.Fab")
		)
		(pad "1" smd roundrect
			(at -0.48 0 90)
			(size 0.59 0.64)
			(layers "F.Cu" "F.Mask" "F.Paste")
			(roundrect_rratio 0.25)
			(net 1 "GND")
			(pintype "passive")
		)
		(pad "2" smd roundrect
			(at 0.48 0 90)
			(size 0.59 0.64)
			(layers "F.Cu" "F.Mask" "F.Paste")
			(roundrect_rratio 0.25)
			(net 597 "1V8_FT")
			(pintype "passive")
		)
	)
	(footprint "antmicro-footprints:C_0402_1005Metric"
		(layer "F.Cu")
		(at 133.45 88.7125 -90)
		(descr "Capacitor SMD 0402")
		(tags "capacitor SMD 0402")
		(property "Reference" "C149"
			(at -3.7125 -0.35 90)
			(layer "F.SilkS")
			(effects
				(font
					(size 0.7 0.7)
					(thickness 0.15)
				)
				(justify right bottom)
			)
		)
		(property "Value" "C_100n_0402"
			(at 0 1.4 90)
			(layer "F.Fab")
			(effects
				(font
					(size 0.7 0.7)
					(thickness 0.15)
				)
				(justify right bottom)
			)
		)
		(property "Datasheet" "https://www.murata.com/products/productdetail?partno=GRM155R61H104KE14%23"
			(at 0 0 270)
			(layer "F.Fab")
			(hide yes)
			(effects
				(font
					(size 1.27 1.27)
					(thickness 0.15)
				)
			)
		)
		(property "Description" "SMD Multilayer Ceramic Capacitor, 0.1 µF, 50 V, 0402 [1005 Metric], ± 10%, X5R, GRM Series"
			(at 0 0 270)
			(layer "F.Fab")
			(hide yes)
			(effects
				(font
					(size 1.27 1.27)
					(thickness 0.15)
				)
			)
		)
		(property "Author" "Antmicro"
			(at 44.7375 222.1625 0)
			(layer "F.Fab")
			(hide yes)
			(effects
				(font
					(size 1 1)
					(thickness 0.15)
				)
			)
		)
		(property "Dielectric" "X5R"
			(at 44.7375 222.1625 0)
			(layer "F.Fab")
			(hide yes)
			(effects
				(font
					(size 1 1)
					(thickness 0.15)
				)
			)
		)
		(property "License" "Apache-2.0"
			(at 44.7375 222.1625 0)
			(layer "F.Fab")
			(hide yes)
			(effects
				(font
					(size 1 1)
					(thickness 0.15)
				)
			)
		)
		(property "MPN" "GRM155R61H104KE14D"
			(at 44.7375 222.1625 0)
			(layer "F.Fab")
			(hide yes)
			(effects
				(font
					(size 1 1)
					(thickness 0.15)
				)
			)
		)
		(property "Manufacturer" "Murata"
			(at 44.7375 222.1625 0)
			(layer "F.Fab")
			(hide yes)
			(effects
				(font
					(size 1 1)
					(thickness 0.15)
				)
			)
		)
		(property "Val" "100n"
			(at 44.7375 222.1625 0)
			(layer "F.Fab")
			(hide yes)
			(effects
				(font
					(size 1 1)
					(thickness 0.15)
				)
			)
		)
		(property "Voltage" "50V"
			(at 44.7375 222.1625 0)
			(layer "F.Fab")
			(hide yes)
			(effects
				(font
					(size 1 1)
					(thickness 0.15)
				)
			)
		)
		(sheetname "/Interfaces/")
		(sheetfile "interfaces.kicad_sch")
		(attr smd)
		(fp_rect
			(start -0.925 -0.47)
			(end 0.925 0.47)
			(stroke
				(width 0.05)
				(type default)
			)
			(fill no)
			(layer "F.CrtYd")
		)
		(fp_line
			(start -0.494 0.248)
			(end -0.494 -0.25)
			(stroke
				(width 0.15)
				(type solid)
			)
			(layer "F.Fab")
		)
		(fp_line
			(start 0.504 0.248)
			(end -0.494 0.248)
			(stroke
				(width 0.15)
				(type solid)
			)
			(layer "F.Fab")
		)
		(fp_line
			(start -0.494 -0.25)
			(end 0.504 -0.25)
			(stroke
				(width 0.15)
				(type solid)
			)
			(layer "F.Fab")
		)
		(fp_line
			(start 0.504 -0.25)
			(end 0.504 0.248)
			(stroke
				(width 0.15)
				(type solid)
			)
			(layer "F.Fab")
		)
		(pad "1" smd roundrect
			(at -0.48 0 270)
			(size 0.59 0.64)
			(layers "F.Cu" "F.Mask" "F.Paste")
			(roundrect_rratio 0.25)
			(net 1 "GND")
			(pintype "passive")
		)
		(pad "2" smd roundrect
			(at 0.48 0 270)
			(size 0.59 0.64)
			(layers "F.Cu" "F.Mask" "F.Paste")
			(roundrect_rratio 0.25)
			(net 116 "/Interfaces/FT_VPLL")
			(pintype "passive")
		)
	)
	(footprint "antmicro-footprints:C_0402_1005Metric"
		(layer "F.Cu")
		(at 132.45 88.7125 -90)
		(descr "Capacitor SMD 0402")
		(tags "capacitor SMD 0402")
		(property "Reference" "C154"
			(at -3.7125 -0.35 90)
			(layer "F.SilkS")
			(effects
				(font
					(size 0.7 0.7)
					(thickness 0.15)
				)
				(justify right bottom)
			)
		)
		(property "Value" "C_4u7_0402"
			(at 0 1.4 90)
			(layer "F.Fab")
			(effects
				(font
					(size 0.7 0.7)
					(thickness 0.15)
				)
				(justify right bottom)
			)
		)
		(property "Datasheet" "https://www.murata.com/products/productdetail?partno=GRM155R61A475MEAA%23"
			(at 0 0 270)
			(layer "F.Fab")
			(hide yes)
			(effects
				(font
					(size 1.27 1.27)
					(thickness 0.15)
				)
			)
		)
		(property "Description" "SMD Multilayer Ceramic Capacitor, 4.7 µF, 10 V, 0402 [1005 Metric], ± 20%, X5R, GRM Series"
			(at 0 0 270)
			(layer "F.Fab")
			(hide yes)
			(effects
				(font
					(size 1.27 1.27)
					(thickness 0.15)
				)
			)
		)
		(property "Author" "Antmicro"
			(at 43.7375 221.1625 0)
			(layer "F.Fab")
			(hide yes)
			(effects
				(font
					(size 1 1)
					(thickness 0.15)
				)
			)
		)
		(property "Dielectric" ""
			(at 43.7375 221.1625 0)
			(layer "F.Fab")
			(hide yes)
			(effects
				(font
					(size 1 1)
					(thickness 0.15)
				)
			)
		)
		(property "License" "Apache-2.0"
			(at 43.7375 221.1625 0)
			(layer "F.Fab")
			(hide yes)
			(effects
				(font
					(size 1 1)
					(thickness 0.15)
				)
			)
		)
		(property "MPN" "GRM155R61A475MEAAD"
			(at 43.7375 221.1625 0)
			(layer "F.Fab")
			(hide yes)
			(effects
				(font
					(size 1 1)
					(thickness 0.15)
				)
			)
		)
		(property "Manufacturer" "Murata"
			(at 43.7375 221.1625 0)
			(layer "F.Fab")
			(hide yes)
			(effects
				(font
					(size 1 1)
					(thickness 0.15)
				)
			)
		)
		(property "Val" "4u7"
			(at 43.7375 221.1625 0)
			(layer "F.Fab")
			(hide yes)
			(effects
				(font
					(size 1 1)
					(thickness 0.15)
				)
			)
		)
		(property "Voltage" ""
			(at 43.7375 221.1625 0)
			(layer "F.Fab")
			(hide yes)
			(effects
				(font
					(size 1 1)
					(thickness 0.15)
				)
			)
		)
		(sheetname "/Interfaces/")
		(sheetfile "interfaces.kicad_sch")
		(attr smd)
		(fp_rect
			(start -0.925 -0.47)
			(end 0.925 0.47)
			(stroke
				(width 0.05)
				(type default)
			)
			(fill no)
			(layer "F.CrtYd")
		)
		(fp_line
			(start -0.494 0.248)
			(end -0.494 -0.25)
			(stroke
				(width 0.15)
				(type solid)
			)
			(layer "F.Fab")
		)
		(fp_line
			(start 0.504 0.248)
			(end -0.494 0.248)
			(stroke
				(width 0.15)
				(type solid)
			)
			(layer "F.Fab")
		)
		(fp_line
			(start -0.494 -0.25)
			(end 0.504 -0.25)
			(stroke
				(width 0.15)
				(type solid)
			)
			(layer "F.Fab")
		)
		(fp_line
			(start 0.504 -0.25)
			(end 0.504 0.248)
			(stroke
				(width 0.15)
				(type solid)
			)
			(layer "F.Fab")
		)
		(pad "1" smd roundrect
			(at -0.48 0 270)
			(size 0.59 0.64)
			(layers "F.Cu" "F.Mask" "F.Paste")
			(roundrect_rratio 0.25)
			(net 1 "GND")
			(pintype "passive")
		)
		(pad "2" smd roundrect
			(at 0.48 0 270)
			(size 0.59 0.64)
			(layers "F.Cu" "F.Mask" "F.Paste")
			(roundrect_rratio 0.25)
			(net 116 "/Interfaces/FT_VPLL")
			(pintype "passive")
		)
	)
	(footprint "antmicro-footprints:C_0402_1005Metric"
		(layer "F.Cu")
		(at 139.5 83.5 180)
		(descr "Capacitor SMD 0402")
		(tags "capacitor SMD 0402")
		(property "Reference" "C166"
			(at -1.4 0.6 0)
			(layer "F.SilkS")
			(effects
				(font
					(size 0.7 0.7)
					(thickness 0.15)
				)
				(justify right bottom)
			)
		)
		(property "Value" "C_18p_0402"
			(at 0 1.4 0)
			(layer "F.Fab")
			(effects
				(font
					(size 0.7 0.7)
					(thickness 0.15)
				)
				(justify right bottom)
			)
		)
		(property "Datasheet" "https://product.samsungsem.com/mlcc/CL05C180JB51PN.do"
			(at 0 0 180)
			(layer "F.Fab")
			(hide yes)
			(effects
				(font
					(size 1.27 1.27)
					(thickness 0.15)
				)
			)
		)
		(property "Description" "SMD Multilayer Ceramic Capacitor, 18 pF, 50 V, 0402 [1005 Metric], ± 5%, C0G / NP0, MC"
			(at 0 0 180)
			(layer "F.Fab")
			(hide yes)
			(effects
				(font
					(size 1.27 1.27)
					(thickness 0.15)
				)
			)
		)
		(property "Author" "Antmicro"
			(at 279 167 0)
			(layer "F.Fab")
			(hide yes)
			(effects
				(font
					(size 1 1)
					(thickness 0.15)
				)
			)
		)
		(property "Dielectric" ""
			(at 279 167 0)
			(layer "F.Fab")
			(hide yes)
			(effects
				(font
					(size 1 1)
					(thickness 0.15)
				)
			)
		)
		(property "License" "Apache-2.0"
			(at 279 167 0)
			(layer "F.Fab")
			(hide yes)
			(effects
				(font
					(size 1 1)
					(thickness 0.15)
				)
			)
		)
		(property "MPN" "CL05C180JB51PNC"
			(at 279 167 0)
			(layer "F.Fab")
			(hide yes)
			(effects
				(font
					(size 1 1)
					(thickness 0.15)
				)
			)
		)
		(property "Manufacturer" "Samsung Electro-Mechanics"
			(at 279 167 0)
			(layer "F.Fab")
			(hide yes)
			(effects
				(font
					(size 1 1)
					(thickness 0.15)
				)
			)
		)
		(property "Val" "18p"
			(at 279 167 0)
			(layer "F.Fab")
			(hide yes)
			(effects
				(font
					(size 1 1)
					(thickness 0.15)
				)
			)
		)
		(property "Voltage" ""
			(at 279 167 0)
			(layer "F.Fab")
			(hide yes)
			(effects
				(font
					(size 1 1)
					(thickness 0.15)
				)
			)
		)
		(sheetname "/Interfaces/")
		(sheetfile "interfaces.kicad_sch")
		(attr smd)
		(fp_rect
			(start -0.925 -0.47)
			(end 0.925 0.47)
			(stroke
				(width 0.05)
				(type default)
			)
			(fill no)
			(layer "F.CrtYd")
		)
		(fp_line
			(start 0.504 0.248)
			(end -0.494 0.248)
			(stroke
				(width 0.15)
				(type solid)
			)
			(layer "F.Fab")
		)
		(fp_line
			(start 0.504 -0.25)
			(end 0.504 0.248)
			(stroke
				(width 0.15)
				(type solid)
			)
			(layer "F.Fab")
		)
		(fp_line
			(start -0.494 0.248)
			(end -0.494 -0.25)
			(stroke
				(width 0.15)
				(type solid)
			)
			(layer "F.Fab")
		)
		(fp_line
			(start -0.494 -0.25)
			(end 0.504 -0.25)
			(stroke
				(width 0.15)
				(type solid)
			)
			(layer "F.Fab")
		)
		(pad "1" smd roundrect
			(at -0.48 0 180)
			(size 0.59 0.64)
			(layers "F.Cu" "F.Mask" "F.Paste")
			(roundrect_rratio 0.25)
			(net 1 "GND")
			(pintype "passive")
		)
		(pad "2" smd roundrect
			(at 0.48 0 180)
			(size 0.59 0.64)
			(layers "F.Cu" "F.Mask" "F.Paste")
			(roundrect_rratio 0.25)
			(net 197 "Net-(U19-OSCI)")
			(pintype "passive")
		)
	)
	(footprint "antmicro-footprints:C_0402_1005Metric"
		(layer "F.Cu")
		(at 134.55 86.3125 -90)
		(descr "Capacitor SMD 0402")
		(tags "capacitor SMD 0402")
		(property "Reference" "C168"
			(at 0.8875 -0.45 90)
			(layer "F.SilkS")
			(effects
				(font
					(size 0.7 0.7)
					(thickness 0.15)
				)
				(justify right bottom)
			)
		)
		(property "Value" "C_18p_0402"
			(at 0 1.4 90)
			(layer "F.Fab")
			(effects
				(font
					(size 0.7 0.7)
					(thickness 0.15)
				)
				(justify right bottom)
			)
		)
		(property "Datasheet" "https://product.samsungsem.com/mlcc/CL05C180JB51PN.do"
			(at 0 0 270)
			(layer "F.Fab")
			(hide yes)
			(effects
				(font
					(size 1.27 1.27)
					(thickness 0.15)
				)
			)
		)
		(property "Description" "SMD Multilayer Ceramic Capacitor, 18 pF, 50 V, 0402 [1005 Metric], ± 5%, C0G / NP0, MC"
			(at 0 0 270)
			(layer "F.Fab")
			(hide yes)
			(effects
				(font
					(size 1.27 1.27)
					(thickness 0.15)
				)
			)
		)
		(property "Author" "Antmicro"
			(at 48.2375 220.8625 0)
			(layer "F.Fab")
			(hide yes)
			(effects
				(font
					(size 1 1)
					(thickness 0.15)
				)
			)
		)
		(property "Dielectric" ""
			(at 48.2375 220.8625 0)
			(layer "F.Fab")
			(hide yes)
			(effects
				(font
					(size 1 1)
					(thickness 0.15)
				)
			)
		)
		(property "License" "Apache-2.0"
			(at 48.2375 220.8625 0)
			(layer "F.Fab")
			(hide yes)
			(effects
				(font
					(size 1 1)
					(thickness 0.15)
				)
			)
		)
		(property "MPN" "CL05C180JB51PNC"
			(at 48.2375 220.8625 0)
			(layer "F.Fab")
			(hide yes)
			(effects
				(font
					(size 1 1)
					(thickness 0.15)
				)
			)
		)
		(property "Manufacturer" "Samsung Electro-Mechanics"
			(at 48.2375 220.8625 0)
			(layer "F.Fab")
			(hide yes)
			(effects
				(font
					(size 1 1)
					(thickness 0.15)
				)
			)
		)
		(property "Val" "18p"
			(at 48.2375 220.8625 0)
			(layer "F.Fab")
			(hide yes)
			(effects
				(font
					(size 1 1)
					(thickness 0.15)
				)
			)
		)
		(property "Voltage" ""
			(at 48.2375 220.8625 0)
			(layer "F.Fab")
			(hide yes)
			(effects
				(font
					(size 1 1)
					(thickness 0.15)
				)
			)
		)
		(sheetname "/Interfaces/")
		(sheetfile "interfaces.kicad_sch")
		(attr smd)
		(fp_rect
			(start -0.925 -0.47)
			(end 0.925 0.47)
			(stroke
				(width 0.05)
				(type default)
			)
			(fill no)
			(layer "F.CrtYd")
		)
		(fp_line
			(start -0.494 0.248)
			(end -0.494 -0.25)
			(stroke
				(width 0.15)
				(type solid)
			)
			(layer "F.Fab")
		)
		(fp_line
			(start 0.504 0.248)
			(end -0.494 0.248)
			(stroke
				(width 0.15)
				(type solid)
			)
			(layer "F.Fab")
		)
		(fp_line
			(start -0.494 -0.25)
			(end 0.504 -0.25)
			(stroke
				(width 0.15)
				(type solid)
			)
			(layer "F.Fab")
		)
		(fp_line
			(start 0.504 -0.25)
			(end 0.504 0.248)
			(stroke
				(width 0.15)
				(type solid)
			)
			(layer "F.Fab")
		)
		(pad "1" smd roundrect
			(at -0.48 0 270)
			(size 0.59 0.64)
			(layers "F.Cu" "F.Mask" "F.Paste")
			(roundrect_rratio 0.25)
			(net 1 "GND")
			(pintype "passive")
		)
		(pad "2" smd roundrect
			(at 0.48 0 270)
			(size 0.59 0.64)
			(layers "F.Cu" "F.Mask" "F.Paste")
			(roundrect_rratio 0.25)
			(net 198 "Net-(U19-OSCO)")
			(pintype "passive")
		)
	)
	(footprint "antmicro-footprints:C_0402_1005Metric"
		(layer "F.Cu")
		(at 141.35 98.0125 180)
		(descr "Capacitor SMD 0402")
		(tags "capacitor SMD 0402")
		(property "Reference" "C169"
			(at -3.65 -0.2875 0)
			(layer "F.SilkS")
			(effects
				(font
					(size 0.7 0.7)
					(thickness 0.15)
				)
				(justify right bottom)
			)
		)
		(property "Value" "C_100n_0402"
			(at 0 1.4 0)
			(layer "F.Fab")
			(effects
				(font
					(size 0.7 0.7)
					(thickness 0.15)
				)
				(justify right bottom)
			)
		)
		(property "Datasheet" "https://www.murata.com/products/productdetail?partno=GRM155R61H104KE14%23"
			(at 0 0 180)
			(layer "F.Fab")
			(hide yes)
			(effects
				(font
					(size 1.27 1.27)
					(thickness 0.15)
				)
			)
		)
		(property "Description" "SMD Multilayer Ceramic Capacitor, 0.1 µF, 50 V, 0402 [1005 Metric], ± 10%, X5R, GRM Series"
			(at 0 0 180)
			(layer "F.Fab")
			(hide yes)
			(effects
				(font
					(size 1.27 1.27)
					(thickness 0.15)
				)
			)
		)
		(property "Author" "Antmicro"
			(at 282.7 196.025 0)
			(layer "F.Fab")
			(hide yes)
			(effects
				(font
					(size 1 1)
					(thickness 0.15)
				)
			)
		)
		(property "Dielectric" "X5R"
			(at 282.7 196.025 0)
			(layer "F.Fab")
			(hide yes)
			(effects
				(font
					(size 1 1)
					(thickness 0.15)
				)
			)
		)
		(property "License" "Apache-2.0"
			(at 282.7 196.025 0)
			(layer "F.Fab")
			(hide yes)
			(effects
				(font
					(size 1 1)
					(thickness 0.15)
				)
			)
		)
		(property "MPN" "GRM155R61H104KE14D"
			(at 282.7 196.025 0)
			(layer "F.Fab")
			(hide yes)
			(effects
				(font
					(size 1 1)
					(thickness 0.15)
				)
			)
		)
		(property "Manufacturer" "Murata"
			(at 282.7 196.025 0)
			(layer "F.Fab")
			(hide yes)
			(effects
				(font
					(size 1 1)
					(thickness 0.15)
				)
			)
		)
		(property "Val" "100n"
			(at 282.7 196.025 0)
			(layer "F.Fab")
			(hide yes)
			(effects
				(font
					(size 1 1)
					(thickness 0.15)
				)
			)
		)
		(property "Voltage" "50V"
			(at 282.7 196.025 0)
			(layer "F.Fab")
			(hide yes)
			(effects
				(font
					(size 1 1)
					(thickness 0.15)
				)
			)
		)
		(sheetname "/Interfaces/")
		(sheetfile "interfaces.kicad_sch")
		(attr smd)
		(fp_rect
			(start -0.925 -0.47)
			(end 0.925 0.47)
			(stroke
				(width 0.05)
				(type default)
			)
			(fill no)
			(layer "F.CrtYd")
		)
		(fp_line
			(start 0.504 0.248)
			(end -0.494 0.248)
			(stroke
				(width 0.15)
				(type solid)
			)
			(layer "F.Fab")
		)
		(fp_line
			(start 0.504 -0.25)
			(end 0.504 0.248)
			(stroke
				(width 0.15)
				(type solid)
			)
			(layer "F.Fab")
		)
		(fp_line
			(start -0.494 0.248)
			(end -0.494 -0.25)
			(stroke
				(width 0.15)
				(type solid)
			)
			(layer "F.Fab")
		)
		(fp_line
			(start -0.494 -0.25)
			(end 0.504 -0.25)
			(stroke
				(width 0.15)
				(type solid)
			)
			(layer "F.Fab")
		)
		(pad "1" smd roundrect
			(at -0.48 0 180)
			(size 0.59 0.64)
			(layers "F.Cu" "F.Mask" "F.Paste")
			(roundrect_rratio 0.25)
			(net 1 "GND")
			(pintype "passive")
		)
		(pad "2" smd roundrect
			(at 0.48 0 180)
			(size 0.59 0.64)
			(layers "F.Cu" "F.Mask" "F.Paste")
			(roundrect_rratio 0.25)
			(net 2 "VCC3V3")
			(pintype "passive")
		)
	)
	(footprint "antmicro-footprints:C_0402_1005Metric"
		(layer "F.Cu")
		(at 141.35 95.5125 180)
		(descr "Capacitor SMD 0402")
		(tags "capacitor SMD 0402")
		(property "Reference" "C170"
			(at -3.65 -0.2875 0)
			(layer "F.SilkS")
			(effects
				(font
					(size 0.7 0.7)
					(thickness 0.15)
				)
				(justify right bottom)
			)
		)
		(property "Value" "C_100n_0402"
			(at 0 1.4 0)
			(layer "F.Fab")
			(effects
				(font
					(size 0.7 0.7)
					(thickness 0.15)
				)
				(justify right bottom)
			)
		)
		(property "Datasheet" "https://www.murata.com/products/productdetail?partno=GRM155R61H104KE14%23"
			(at 0 0 180)
			(layer "F.Fab")
			(hide yes)
			(effects
				(font
					(size 1.27 1.27)
					(thickness 0.15)
				)
			)
		)
		(property "Description" "SMD Multilayer Ceramic Capacitor, 0.1 µF, 50 V, 0402 [1005 Metric], ± 10%, X5R, GRM Series"
			(at 0 0 180)
			(layer "F.Fab")
			(hide yes)
			(effects
				(font
					(size 1.27 1.27)
					(thickness 0.15)
				)
			)
		)
		(property "Author" "Antmicro"
			(at 282.7 191.025 0)
			(layer "F.Fab")
			(hide yes)
			(effects
				(font
					(size 1 1)
					(thickness 0.15)
				)
			)
		)
		(property "Dielectric" "X5R"
			(at 282.7 191.025 0)
			(layer "F.Fab")
			(hide yes)
			(effects
				(font
					(size 1 1)
					(thickness 0.15)
				)
			)
		)
		(property "License" "Apache-2.0"
			(at 282.7 191.025 0)
			(layer "F.Fab")
			(hide yes)
			(effects
				(font
					(size 1 1)
					(thickness 0.15)
				)
			)
		)
		(property "MPN" "GRM155R61H104KE14D"
			(at 282.7 191.025 0)
			(layer "F.Fab")
			(hide yes)
			(effects
				(font
					(size 1 1)
					(thickness 0.15)
				)
			)
		)
		(property "Manufacturer" "Murata"
			(at 282.7 191.025 0)
			(layer "F.Fab")
			(hide yes)
			(effects
				(font
					(size 1 1)
					(thickness 0.15)
				)
			)
		)
		(property "Val" "100n"
			(at 282.7 191.025 0)
			(layer "F.Fab")
			(hide yes)
			(effects
				(font
					(size 1 1)
					(thickness 0.15)
				)
			)
		)
		(property "Voltage" "50V"
			(at 282.7 191.025 0)
			(layer "F.Fab")
			(hide yes)
			(effects
				(font
					(size 1 1)
					(thickness 0.15)
				)
			)
		)
		(sheetname "/Interfaces/")
		(sheetfile "interfaces.kicad_sch")
		(attr smd)
		(fp_rect
			(start -0.925 -0.47)
			(end 0.925 0.47)
			(stroke
				(width 0.05)
				(type default)
			)
			(fill no)
			(layer "F.CrtYd")
		)
		(fp_line
			(start 0.504 0.248)
			(end -0.494 0.248)
			(stroke
				(width 0.15)
				(type solid)
			)
			(layer "F.Fab")
		)
		(fp_line
			(start 0.504 -0.25)
			(end 0.504 0.248)
			(stroke
				(width 0.15)
				(type solid)
			)
			(layer "F.Fab")
		)
		(fp_line
			(start -0.494 0.248)
			(end -0.494 -0.25)
			(stroke
				(width 0.15)
				(type solid)
			)
			(layer "F.Fab")
		)
		(fp_line
			(start -0.494 -0.25)
			(end 0.504 -0.25)
			(stroke
				(width 0.15)
				(type solid)
			)
			(layer "F.Fab")
		)
		(pad "1" smd roundrect
			(at -0.48 0 180)
			(size 0.59 0.64)
			(layers "F.Cu" "F.Mask" "F.Paste")
			(roundrect_rratio 0.25)
			(net 1 "GND")
			(pintype "passive")
		)
		(pad "2" smd roundrect
			(at 0.48 0 180)
			(size 0.59 0.64)
			(layers "F.Cu" "F.Mask" "F.Paste")
			(roundrect_rratio 0.25)
			(net 2 "VCC3V3")
			(pintype "passive")
		)
	)
	(footprint "antmicro-footprints:C_0402_1005Metric"
		(layer "F.Cu")
		(at 135.35 101.8125 90)
		(descr "Capacitor SMD 0402")
		(tags "capacitor SMD 0402")
		(property "Reference" "C172"
			(at -3.6875 0.35 90)
			(layer "F.SilkS")
			(effects
				(font
					(size 0.7 0.7)
					(thickness 0.15)
				)
				(justify left bottom)
			)
		)
		(property "Value" "C_100n_0402"
			(at 0 1.4 90)
			(layer "F.Fab")
			(effects
				(font
					(size 0.7 0.7)
					(thickness 0.15)
				)
				(justify left bottom)
			)
		)
		(property "Datasheet" "https://www.murata.com/products/productdetail?partno=GRM155R61H104KE14%23"
			(at 0 0 90)
			(layer "F.Fab")
			(hide yes)
			(effects
				(font
					(size 1.27 1.27)
					(thickness 0.15)
				)
			)
		)
		(property "Description" "SMD Multilayer Ceramic Capacitor, 0.1 µF, 50 V, 0402 [1005 Metric], ± 10%, X5R, GRM Series"
			(at 0 0 90)
			(layer "F.Fab")
			(hide yes)
			(effects
				(font
					(size 1.27 1.27)
					(thickness 0.15)
				)
			)
		)
		(property "Author" "Antmicro"
			(at 237.1625 -33.5375 0)
			(layer "F.Fab")
			(hide yes)
			(effects
				(font
					(size 1 1)
					(thickness 0.15)
				)
			)
		)
		(property "Dielectric" "X5R"
			(at 237.1625 -33.5375 0)
			(layer "F.Fab")
			(hide yes)
			(effects
				(font
					(size 1 1)
					(thickness 0.15)
				)
			)
		)
		(property "License" "Apache-2.0"
			(at 237.1625 -33.5375 0)
			(layer "F.Fab")
			(hide yes)
			(effects
				(font
					(size 1 1)
					(thickness 0.15)
				)
			)
		)
		(property "MPN" "GRM155R61H104KE14D"
			(at 237.1625 -33.5375 0)
			(layer "F.Fab")
			(hide yes)
			(effects
				(font
					(size 1 1)
					(thickness 0.15)
				)
			)
		)
		(property "Manufacturer" "Murata"
			(at 237.1625 -33.5375 0)
			(layer "F.Fab")
			(hide yes)
			(effects
				(font
					(size 1 1)
					(thickness 0.15)
				)
			)
		)
		(property "Val" "100n"
			(at 237.1625 -33.5375 0)
			(layer "F.Fab")
			(hide yes)
			(effects
				(font
					(size 1 1)
					(thickness 0.15)
				)
			)
		)
		(property "Voltage" "50V"
			(at 237.1625 -33.5375 0)
			(layer "F.Fab")
			(hide yes)
			(effects
				(font
					(size 1 1)
					(thickness 0.15)
				)
			)
		)
		(sheetname "/Interfaces/")
		(sheetfile "interfaces.kicad_sch")
		(attr smd)
		(fp_rect
			(start -0.925 -0.47)
			(end 0.925 0.47)
			(stroke
				(width 0.05)
				(type default)
			)
			(fill no)
			(layer "F.CrtYd")
		)
		(fp_line
			(start 0.504 -0.25)
			(end 0.504 0.248)
			(stroke
				(width 0.15)
				(type solid)
			)
			(layer "F.Fab")
		)
		(fp_line
			(start -0.494 -0.25)
			(end 0.504 -0.25)
			(stroke
				(width 0.15)
				(type solid)
			)
			(layer "F.Fab")
		)
		(fp_line
			(start 0.504 0.248)
			(end -0.494 0.248)
			(stroke
				(width 0.15)
				(type solid)
			)
			(layer "F.Fab")
		)
		(fp_line
			(start -0.494 0.248)
			(end -0.494 -0.25)
			(stroke
				(width 0.15)
				(type solid)
			)
			(layer "F.Fab")
		)
		(pad "1" smd roundrect
			(at -0.48 0 90)
			(size 0.59 0.64)
			(layers "F.Cu" "F.Mask" "F.Paste")
			(roundrect_rratio 0.25)
			(net 1 "GND")
			(pintype "passive")
		)
		(pad "2" smd roundrect
			(at 0.48 0 90)
			(size 0.59 0.64)
			(layers "F.Cu" "F.Mask" "F.Paste")
			(roundrect_rratio 0.25)
			(net 2 "VCC3V3")
			(pintype "passive")
		)
	)
	(footprint "antmicro-footprints:C_0402_1005Metric"
		(layer "F.Cu")
		(at 127.75 98.6125)
		(descr "Capacitor SMD 0402")
		(tags "capacitor SMD 0402")
		(property "Reference" "C173"
			(at -3.65 0.2875 0)
			(layer "F.SilkS")
			(effects
				(font
					(size 0.7 0.7)
					(thickness 0.15)
				)
				(justify left bottom)
			)
		)
		(property "Value" "C_100n_0402"
			(at 0 1.4 0)
			(layer "F.Fab")
			(effects
				(font
					(size 0.7 0.7)
					(thickness 0.15)
				)
				(justify left bottom)
			)
		)
		(property "Datasheet" "https://www.murata.com/products/productdetail?partno=GRM155R61H104KE14%23"
			(at 0 0 0)
			(layer "F.Fab")
			(hide yes)
			(effects
				(font
					(size 1.27 1.27)
					(thickness 0.15)
				)
			)
		)
		(property "Description" "SMD Multilayer Ceramic Capacitor, 0.1 µF, 50 V, 0402 [1005 Metric], ± 10%, X5R, GRM Series"
			(at 0 0 0)
			(layer "F.Fab")
			(hide yes)
			(effects
				(font
					(size 1.27 1.27)
					(thickness 0.15)
				)
			)
		)
		(property "Author" "Antmicro"
			(at 0 0 0)
			(layer "F.Fab")
			(hide yes)
			(effects
				(font
					(size 1 1)
					(thickness 0.15)
				)
			)
		)
		(property "Dielectric" "X5R"
			(at 0 0 0)
			(layer "F.Fab")
			(hide yes)
			(effects
				(font
					(size 1 1)
					(thickness 0.15)
				)
			)
		)
		(property "License" "Apache-2.0"
			(at 0 0 0)
			(layer "F.Fab")
			(hide yes)
			(effects
				(font
					(size 1 1)
					(thickness 0.15)
				)
			)
		)
		(property "MPN" "GRM155R61H104KE14D"
			(at 0 0 0)
			(layer "F.Fab")
			(hide yes)
			(effects
				(font
					(size 1 1)
					(thickness 0.15)
				)
			)
		)
		(property "Manufacturer" "Murata"
			(at 0 0 0)
			(layer "F.Fab")
			(hide yes)
			(effects
				(font
					(size 1 1)
					(thickness 0.15)
				)
			)
		)
		(property "Val" "100n"
			(at 0 0 0)
			(layer "F.Fab")
			(hide yes)
			(effects
				(font
					(size 1 1)
					(thickness 0.15)
				)
			)
		)
		(property "Voltage" "50V"
			(at 0 0 0)
			(layer "F.Fab")
			(hide yes)
			(effects
				(font
					(size 1 1)
					(thickness 0.15)
				)
			)
		)
		(sheetname "/Interfaces/")
		(sheetfile "interfaces.kicad_sch")
		(attr smd)
		(fp_rect
			(start -0.925 -0.47)
			(end 0.925 0.47)
			(stroke
				(width 0.05)
				(type default)
			)
			(fill no)
			(layer "F.CrtYd")
		)
		(fp_line
			(start -0.494 -0.25)
			(end 0.504 -0.25)
			(stroke
				(width 0.15)
				(type solid)
			)
			(layer "F.Fab")
		)
		(fp_line
			(start -0.494 0.248)
			(end -0.494 -0.25)
			(stroke
				(width 0.15)
				(type solid)
			)
			(layer "F.Fab")
		)
		(fp_line
			(start 0.504 -0.25)
			(end 0.504 0.248)
			(stroke
				(width 0.15)
				(type solid)
			)
			(layer "F.Fab")
		)
		(fp_line
			(start 0.504 0.248)
			(end -0.494 0.248)
			(stroke
				(width 0.15)
				(type solid)
			)
			(layer "F.Fab")
		)
		(pad "1" smd roundrect
			(at -0.48 0)
			(size 0.59 0.64)
			(layers "F.Cu" "F.Mask" "F.Paste")
			(roundrect_rratio 0.25)
			(net 1 "GND")
			(pintype "passive")
		)
		(pad "2" smd roundrect
			(at 0.48 0)
			(size 0.59 0.64)
			(layers "F.Cu" "F.Mask" "F.Paste")
			(roundrect_rratio 0.25)
			(net 2 "VCC3V3")
			(pintype "passive")
		)
	)
	(footprint "antmicro-footprints:C_0402_1005Metric"
		(layer "F.Cu")
		(at 127.45 94.1125)
		(descr "Capacitor SMD 0402")
		(tags "capacitor SMD 0402")
		(property "Reference" "C174"
			(at -3.65 0.3875 0)
			(layer "F.SilkS")
			(effects
				(font
					(size 0.7 0.7)
					(thickness 0.15)
				)
				(justify left bottom)
			)
		)
		(property "Value" "C_100n_0402"
			(at 0 1.4 0)
			(layer "F.Fab")
			(effects
				(font
					(size 0.7 0.7)
					(thickness 0.15)
				)
				(justify left bottom)
			)
		)
		(property "Datasheet" "https://www.murata.com/products/productdetail?partno=GRM155R61H104KE14%23"
			(at 0 0 0)
			(layer "F.Fab")
			(hide yes)
			(effects
				(font
					(size 1.27 1.27)
					(thickness 0.15)
				)
			)
		)
		(property "Description" "SMD Multilayer Ceramic Capacitor, 0.1 µF, 50 V, 0402 [1005 Metric], ± 10%, X5R, GRM Series"
			(at 0 0 0)
			(layer "F.Fab")
			(hide yes)
			(effects
				(font
					(size 1.27 1.27)
					(thickness 0.15)
				)
			)
		)
		(property "Author" "Antmicro"
			(at 0 0 0)
			(layer "F.Fab")
			(hide yes)
			(effects
				(font
					(size 1 1)
					(thickness 0.15)
				)
			)
		)
		(property "Dielectric" "X5R"
			(at 0 0 0)
			(layer "F.Fab")
			(hide yes)
			(effects
				(font
					(size 1 1)
					(thickness 0.15)
				)
			)
		)
		(property "License" "Apache-2.0"
			(at 0 0 0)
			(layer "F.Fab")
			(hide yes)
			(effects
				(font
					(size 1 1)
					(thickness 0.15)
				)
			)
		)
		(property "MPN" "GRM155R61H104KE14D"
			(at 0 0 0)
			(layer "F.Fab")
			(hide yes)
			(effects
				(font
					(size 1 1)
					(thickness 0.15)
				)
			)
		)
		(property "Manufacturer" "Murata"
			(at 0 0 0)
			(layer "F.Fab")
			(hide yes)
			(effects
				(font
					(size 1 1)
					(thickness 0.15)
				)
			)
		)
		(property "Val" "100n"
			(at 0 0 0)
			(layer "F.Fab")
			(hide yes)
			(effects
				(font
					(size 1 1)
					(thickness 0.15)
				)
			)
		)
		(property "Voltage" "50V"
			(at 0 0 0)
			(layer "F.Fab")
			(hide yes)
			(effects
				(font
					(size 1 1)
					(thickness 0.15)
				)
			)
		)
		(sheetname "/Interfaces/")
		(sheetfile "interfaces.kicad_sch")
		(attr smd)
		(fp_rect
			(start -0.925 -0.47)
			(end 0.925 0.47)
			(stroke
				(width 0.05)
				(type default)
			)
			(fill no)
			(layer "F.CrtYd")
		)
		(fp_line
			(start -0.494 -0.25)
			(end 0.504 -0.25)
			(stroke
				(width 0.15)
				(type solid)
			)
			(layer "F.Fab")
		)
		(fp_line
			(start -0.494 0.248)
			(end -0.494 -0.25)
			(stroke
				(width 0.15)
				(type solid)
			)
			(layer "F.Fab")
		)
		(fp_line
			(start 0.504 -0.25)
			(end 0.504 0.248)
			(stroke
				(width 0.15)
				(type solid)
			)
			(layer "F.Fab")
		)
		(fp_line
			(start 0.504 0.248)
			(end -0.494 0.248)
			(stroke
				(width 0.15)
				(type solid)
			)
			(layer "F.Fab")
		)
		(pad "1" smd roundrect
			(at -0.48 0)
			(size 0.59 0.64)
			(layers "F.Cu" "F.Mask" "F.Paste")
			(roundrect_rratio 0.25)
			(net 1 "GND")
			(pintype "passive")
		)
		(pad "2" smd roundrect
			(at 0.48 0)
			(size 0.59 0.64)
			(layers "F.Cu" "F.Mask" "F.Paste")
			(roundrect_rratio 0.25)
			(net 2 "VCC3V3")
			(pintype "passive")
		)
	)
	(footprint "antmicro-footprints:SOT-723"
		(layer "F.Cu")
		(at 126.55 69.0125 -90)
		(property "Reference" "D15"
			(at 1.6875 -1.05 180)
			(layer "F.SilkS")
			(effects
				(font
					(size 0.7 0.7)
					(thickness 0.15)
				)
				(justify right bottom)
			)
		)
		(property "Value" "TPD2E009_SOT-9X3"
			(at 0 1.7 90)
			(layer "F.Fab")
			(effects
				(font
					(size 0.7 0.7)
					(thickness 0.15)
				)
				(justify right bottom)
			)
		)
		(property "Datasheet" "https://www.ti.com/lit/ds/symlink/tpd2e009.pdf?ts=1597910439511&ref_url=https%253A%252F%252Fwww.google.com%252F"
			(at 0 0 270)
			(layer "F.Fab")
			(hide yes)
			(effects
				(font
					(size 1.27 1.27)
					(thickness 0.15)
				)
			)
		)
		(property "Description" "TVS diode array, 8 kV, SOT-723, 5.5 V, 0.9 pF"
			(at 0 0 270)
			(layer "F.Fab")
			(hide yes)
			(effects
				(font
					(size 1.27 1.27)
					(thickness 0.15)
				)
			)
		)
		(property "Author" "Antmicro"
			(at 57.5375 195.5625 0)
			(layer "F.Fab")
			(hide yes)
			(effects
				(font
					(size 1 1)
					(thickness 0.15)
				)
			)
		)
		(property "License" "Apache-2.0"
			(at 57.5375 195.5625 0)
			(layer "F.Fab")
			(hide yes)
			(effects
				(font
					(size 1 1)
					(thickness 0.15)
				)
			)
		)
		(property "MPN" "TPD2E009DRTR"
			(at 57.5375 195.5625 0)
			(layer "F.Fab")
			(hide yes)
			(effects
				(font
					(size 1 1)
					(thickness 0.15)
				)
			)
		)
		(property "Manufacturer" "Texas Instruments"
			(at 57.5375 195.5625 0)
			(layer "F.Fab")
			(hide yes)
			(effects
				(font
					(size 1 1)
					(thickness 0.15)
				)
			)
		)
		(sheetname "/Interfaces/")
		(sheetfile "interfaces.kicad_sch")
		(attr smd)
		(fp_line
			(start 0.43 0.63)
			(end -0.22 0.63)
			(stroke
				(width 0.15)
				(type solid)
			)
			(layer "F.SilkS")
		)
		(fp_line
			(start 0.43 0.23)
			(end 0.43 0.63)
			(stroke
				(width 0.15)
				(type solid)
			)
			(layer "F.SilkS")
		)
		(fp_line
			(start -0.43 -0.1375)
			(end -0.43 0.1375)
			(stroke
				(width 0.15)
				(type solid)
			)
			(layer "F.SilkS")
		)
		(fp_line
			(start 0.43 -0.23)
			(end 0.43 -0.63)
			(stroke
				(width 0.15)
				(type solid)
			)
			(layer "F.SilkS")
		)
		(fp_line
			(start 0.43 -0.63)
			(end -0.2175 -0.63)
			(stroke
				(width 0.15)
				(type solid)
			)
			(layer "F.SilkS")
		)
		(fp_rect
			(start -0.83 -0.83)
			(end 0.83 0.83)
			(stroke
				(width 0.05)
				(type solid)
			)
			(fill no)
			(layer "F.CrtYd")
		)
		(fp_line
			(start 0.424 0.524)
			(end -0.424 0.524)
			(stroke
				(width 0.15)
				(type solid)
			)
			(layer "F.Fab")
		)
		(fp_line
			(start 0.424 -0.528)
			(end 0.424 0.524)
			(stroke
				(width 0.15)
				(type solid)
			)
			(layer "F.Fab")
		)
		(fp_line
			(start -0.09 -0.53)
			(end -0.43 -0.19)
			(stroke
				(width 0.15)
				(type solid)
			)
			(layer "F.Fab")
		)
		(fp_rect
			(start 0.424 0.524)
			(end -0.43 -0.528)
			(stroke
				(width 0.15)
				(type solid)
			)
			(fill no)
			(layer "F.Fab")
		)
		(pad "1" smd rect
			(at -0.501 -0.401 180)
			(size 0.3 0.4)
			(layers "F.Cu" "F.Mask" "F.Paste")
			(net 213 "/Interfaces/DBG_USB_D_N")
			(pinfunction "1")
			(pintype "passive")
		)
		(pad "2" smd rect
			(at -0.501 0.399 180)
			(size 0.3 0.4)
			(layers "F.Cu" "F.Mask" "F.Paste")
			(net 212 "/Interfaces/DBG_USB_D_P")
			(pinfunction "2")
			(pintype "passive")
		)
		(pad "3" smd rect
			(at 0.499 -0.001 180)
			(size 0.3 0.4)
			(layers "F.Cu" "F.Mask" "F.Paste")
			(net 1 "GND")
			(pinfunction "3")
			(pintype "passive")
		)
	)
	(footprint "antmicro-footprints:FB_0402_1005Metric"
		(layer "F.Cu")
		(at 131.45 88.7125 -90)
		(descr "Ferrite Bead SMD 0402")
		(tags "ferrite bead SMD 0402")
		(property "Reference" "FB1"
			(at -2.9125 -0.35 90)
			(layer "F.SilkS")
			(effects
				(font
					(size 0.7 0.7)
					(thickness 0.15)
				)
				(justify right bottom)
			)
		)
		(property "Value" "FB_600Z_0.3A_Murata-BLM15AG_0402"
			(at 0 1.4 90)
			(layer "F.Fab")
			(effects
				(font
					(size 0.7 0.7)
					(thickness 0.15)
				)
				(justify right bottom)
			)
		)
		(property "Datasheet" "https://www.murata.com/en-us/products/productdata/8796740059166/ENFA0018.pdf"
			(at 0 0 270)
			(layer "F.Fab")
			(hide yes)
			(effects
				(font
					(size 1.27 1.27)
					(thickness 0.15)
				)
			)
		)
		(property "Description" "Ferrite Bead, 0402 [1005 Metric], 600 ohm, 300 mA, BLM15AG_SN, 0.6 ohm, ± 25%, General use"
			(at 0 0 270)
			(layer "F.Fab")
			(hide yes)
			(effects
				(font
					(size 1.27 1.27)
					(thickness 0.15)
				)
			)
		)
		(property "Author" "Antmicro"
			(at 42.7375 220.1625 0)
			(layer "F.Fab")
			(hide yes)
			(effects
				(font
					(size 1 1)
					(thickness 0.15)
				)
			)
		)
		(property "Current" ""
			(at 42.7375 220.1625 0)
			(layer "F.Fab")
			(hide yes)
			(effects
				(font
					(size 1 1)
					(thickness 0.15)
				)
			)
		)
		(property "License" "Apache-2.0"
			(at 42.7375 220.1625 0)
			(layer "F.Fab")
			(hide yes)
			(effects
				(font
					(size 1 1)
					(thickness 0.15)
				)
			)
		)
		(property "MPN" "BLM15AG601SN1D"
			(at 42.7375 220.1625 0)
			(layer "F.Fab")
			(hide yes)
			(effects
				(font
					(size 1 1)
					(thickness 0.15)
				)
			)
		)
		(property "Manufacturer" "Murata"
			(at 42.7375 220.1625 0)
			(layer "F.Fab")
			(hide yes)
			(effects
				(font
					(size 1 1)
					(thickness 0.15)
				)
			)
		)
		(property "Val" "600Z/0.3A"
			(at 42.7375 220.1625 0)
			(layer "F.Fab")
			(hide yes)
			(effects
				(font
					(size 1 1)
					(thickness 0.15)
				)
			)
		)
		(sheetname "/Interfaces/")
		(sheetfile "interfaces.kicad_sch")
		(attr smd)
		(fp_rect
			(start -0.925 -0.47)
			(end 0.925 0.47)
			(stroke
				(width 0.05)
				(type default)
			)
			(fill no)
			(layer "F.CrtYd")
		)
		(fp_rect
			(start -0.5 -0.25)
			(end 0.5 0.25)
			(stroke
				(width 0.15)
				(type solid)
			)
			(fill no)
			(layer "F.Fab")
		)
		(pad "1" smd roundrect
			(at -0.48 0 270)
			(size 0.59 0.64)
			(layers "F.Cu" "F.Mask" "F.Paste")
			(roundrect_rratio 0.25)
			(net 2 "VCC3V3")
			(pintype "passive")
		)
		(pad "2" smd roundrect
			(at 0.48 0 270)
			(size 0.59 0.64)
			(layers "F.Cu" "F.Mask" "F.Paste")
			(roundrect_rratio 0.25)
			(net 116 "/Interfaces/FT_VPLL")
			(pintype "passive")
		)
	)
	(footprint "antmicro-footprints:R_0402_1005Metric"
		(layer "F.Cu")
		(at 135.85 89.0125 -90)
		(descr "Resistor SMD 0402")
		(tags "resistor SMD 0402")
		(property "Reference" "R3"
			(at -0.7125 -1.35 90)
			(layer "F.SilkS")
			(effects
				(font
					(size 0.7 0.7)
					(thickness 0.15)
				)
				(justify right bottom)
			)
		)
		(property "Value" "R_12k1_0402"
			(at 0 1.4 90)
			(layer "F.Fab")
			(effects
				(font
					(size 0.7 0.7)
					(thickness 0.15)
				)
				(justify right bottom)
			)
		)
		(property "Datasheet" "https://www.bourns.com/docs/product-datasheets/cr.pdf"
			(at 0 0 270)
			(layer "F.Fab")
			(hide yes)
			(effects
				(font
					(size 1.27 1.27)
					(thickness 0.15)
				)
			)
		)
		(property "Description" "SMD Chip Resistor, 12.1 kohm, ± 1%, 62.5 mW, 0402 [1005 Metric], Thick Film, General Purpose"
			(at 0 0 270)
			(layer "F.Fab")
			(hide yes)
			(effects
				(font
					(size 1.27 1.27)
					(thickness 0.15)
				)
			)
		)
		(property "Author" "Antmicro"
			(at 46.8375 224.8625 0)
			(layer "F.Fab")
			(hide yes)
			(effects
				(font
					(size 1 1)
					(thickness 0.15)
				)
			)
		)
		(property "License" "Apache-2.0"
			(at 46.8375 224.8625 0)
			(layer "F.Fab")
			(hide yes)
			(effects
				(font
					(size 1 1)
					(thickness 0.15)
				)
			)
		)
		(property "MPN" "CR0402-FX-1212GLF"
			(at 46.8375 224.8625 0)
			(layer "F.Fab")
			(hide yes)
			(effects
				(font
					(size 1 1)
					(thickness 0.15)
				)
			)
		)
		(property "Manufacturer" "Bourns"
			(at 46.8375 224.8625 0)
			(layer "F.Fab")
			(hide yes)
			(effects
				(font
					(size 1 1)
					(thickness 0.15)
				)
			)
		)
		(property "Tolerance" "1%"
			(at 46.8375 224.8625 0)
			(layer "F.Fab")
			(hide yes)
			(effects
				(font
					(size 1 1)
					(thickness 0.15)
				)
			)
		)
		(property "Val" "12k1"
			(at 46.8375 224.8625 0)
			(layer "F.Fab")
			(hide yes)
			(effects
				(font
					(size 1 1)
					(thickness 0.15)
				)
			)
		)
		(sheetname "/Interfaces/")
		(sheetfile "interfaces.kicad_sch")
		(attr smd)
		(fp_rect
			(start -0.925 -0.47)
			(end 0.925 0.47)
			(stroke
				(width 0.05)
				(type default)
			)
			(fill no)
			(layer "F.CrtYd")
		)
		(fp_rect
			(start -0.5 -0.25)
			(end 0.5 0.25)
			(stroke
				(width 0.15)
				(type solid)
			)
			(fill no)
			(layer "F.Fab")
		)
		(pad "1" smd roundrect
			(at -0.48 0 270)
			(size 0.59 0.64)
			(layers "F.Cu" "F.Mask" "F.Paste")
			(roundrect_rratio 0.25)
			(net 1 "GND")
			(pintype "passive")
		)
		(pad "2" smd roundrect
			(at 0.48 0 270)
			(size 0.59 0.64)
			(layers "F.Cu" "F.Mask" "F.Paste")
			(roundrect_rratio 0.25)
			(net 298 "Net-(U19-REF)")
			(pintype "passive")
		)
	)
	(footprint "antmicro-footprints:R_0402_1005Metric"
		(layer "F.Cu")
		(at 129.375 88.7125 90)
		(descr "Resistor SMD 0402")
		(tags "resistor SMD 0402")
		(property "Reference" "R4"
			(at 0.8125 0.425 90)
			(layer "F.SilkS")
			(effects
				(font
					(size 0.7 0.7)
					(thickness 0.15)
				)
				(justify left bottom)
			)
		)
		(property "Value" "R_10k_0402"
			(at 0 1.4 90)
			(layer "F.Fab")
			(effects
				(font
					(size 0.7 0.7)
					(thickness 0.15)
				)
				(justify left bottom)
			)
		)
		(property "Datasheet" "https://www.bourns.com/docs/product-datasheets/cr.pdf"
			(at 0 0 90)
			(layer "F.Fab")
			(hide yes)
			(effects
				(font
					(size 1.27 1.27)
					(thickness 0.15)
				)
			)
		)
		(property "Description" "SMD Chip Resistor, 10 kohm, ± 1%, 62.5 mW, 0402 [1005 Metric], Thick Film, General Purpose"
			(at 0 0 90)
			(layer "F.Fab")
			(hide yes)
			(effects
				(font
					(size 1.27 1.27)
					(thickness 0.15)
				)
			)
		)
		(property "Author" "Antmicro"
			(at 218.0875 -40.6625 0)
			(layer "F.Fab")
			(hide yes)
			(effects
				(font
					(size 1 1)
					(thickness 0.15)
				)
			)
		)
		(property "License" "Apache-2.0"
			(at 218.0875 -40.6625 0)
			(layer "F.Fab")
			(hide yes)
			(effects
				(font
					(size 1 1)
					(thickness 0.15)
				)
			)
		)
		(property "MPN" "CR0402-FX-1002GLF"
			(at 218.0875 -40.6625 0)
			(layer "F.Fab")
			(hide yes)
			(effects
				(font
					(size 1 1)
					(thickness 0.15)
				)
			)
		)
		(property "Manufacturer" "Bourns"
			(at 218.0875 -40.6625 0)
			(layer "F.Fab")
			(hide yes)
			(effects
				(font
					(size 1 1)
					(thickness 0.15)
				)
			)
		)
		(property "Tolerance" "1%"
			(at 218.0875 -40.6625 0)
			(layer "F.Fab")
			(hide yes)
			(effects
				(font
					(size 1 1)
					(thickness 0.15)
				)
			)
		)
		(property "Val" "10k"
			(at 218.0875 -40.6625 0)
			(layer "F.Fab")
			(hide yes)
			(effects
				(font
					(size 1 1)
					(thickness 0.15)
				)
			)
		)
		(sheetname "/Interfaces/")
		(sheetfile "interfaces.kicad_sch")
		(attr smd)
		(fp_rect
			(start -0.925 -0.47)
			(end 0.925 0.47)
			(stroke
				(width 0.05)
				(type default)
			)
			(fill no)
			(layer "F.CrtYd")
		)
		(fp_rect
			(start -0.5 -0.25)
			(end 0.5 0.25)
			(stroke
				(width 0.15)
				(type solid)
			)
			(fill no)
			(layer "F.Fab")
		)
		(pad "1" smd roundrect
			(at -0.48 0 90)
			(size 0.59 0.64)
			(layers "F.Cu" "F.Mask" "F.Paste")
			(roundrect_rratio 0.25)
			(net 299 "Net-(U19-~{RESET})")
			(pintype "passive")
		)
		(pad "2" smd roundrect
			(at 0.48 0 90)
			(size 0.59 0.64)
			(layers "F.Cu" "F.Mask" "F.Paste")
			(roundrect_rratio 0.25)
			(net 1 "GND")
			(pintype "passive")
		)
	)
	(footprint "antmicro-footprints:R_0402_1005Metric"
		(layer "F.Cu")
		(at 127.45 89.7125 180)
		(descr "Resistor SMD 0402")
		(tags "resistor SMD 0402")
		(property "Reference" "R160"
			(at 0.85 -0.254167 0)
			(layer "F.SilkS")
			(effects
				(font
					(size 0.7 0.7)
					(thickness 0.15)
				)
				(justify right bottom)
			)
		)
		(property "Value" "R_22R_0402"
			(at 0 1.4 0)
			(layer "F.Fab")
			(effects
				(font
					(size 0.7 0.7)
					(thickness 0.15)
				)
				(justify right bottom)
			)
		)
		(property "Datasheet" "https://www.bourns.com/docs/product-datasheets/cr.pdf"
			(at 0 0 180)
			(layer "F.Fab")
			(hide yes)
			(effects
				(font
					(size 1.27 1.27)
					(thickness 0.15)
				)
			)
		)
		(property "Description" "SMD Chip Resistor, 22 ohm, ± 1%, 62.5 mW, 0402 [1005 Metric], Thick Film, General Purpose"
			(at 0 0 180)
			(layer "F.Fab")
			(hide yes)
			(effects
				(font
					(size 1.27 1.27)
					(thickness 0.15)
				)
			)
		)
		(property "Author" "Antmicro"
			(at 254.9 179.425 0)
			(layer "F.Fab")
			(hide yes)
			(effects
				(font
					(size 1 1)
					(thickness 0.15)
				)
			)
		)
		(property "License" "Apache-2.0"
			(at 254.9 179.425 0)
			(layer "F.Fab")
			(hide yes)
			(effects
				(font
					(size 1 1)
					(thickness 0.15)
				)
			)
		)
		(property "MPN" "CR0402-FX-22R0GLF"
			(at 254.9 179.425 0)
			(layer "F.Fab")
			(hide yes)
			(effects
				(font
					(size 1 1)
					(thickness 0.15)
				)
			)
		)
		(property "Manufacturer" "Bourns"
			(at 254.9 179.425 0)
			(layer "F.Fab")
			(hide yes)
			(effects
				(font
					(size 1 1)
					(thickness 0.15)
				)
			)
		)
		(property "Tolerance" "1%"
			(at 254.9 179.425 0)
			(layer "F.Fab")
			(hide yes)
			(effects
				(font
					(size 1 1)
					(thickness 0.15)
				)
			)
		)
		(property "Val" "22R"
			(at 254.9 179.425 0)
			(layer "F.Fab")
			(hide yes)
			(effects
				(font
					(size 1 1)
					(thickness 0.15)
				)
			)
		)
		(sheetname "/Interfaces/")
		(sheetfile "interfaces.kicad_sch")
		(attr smd)
		(fp_rect
			(start -0.925 -0.47)
			(end 0.925 0.47)
			(stroke
				(width 0.05)
				(type default)
			)
			(fill no)
			(layer "F.CrtYd")
		)
		(fp_rect
			(start -0.5 -0.25)
			(end 0.5 0.25)
			(stroke
				(width 0.15)
				(type solid)
			)
			(fill no)
			(layer "F.Fab")
		)
		(pad "1" smd roundrect
			(at -0.48 0 180)
			(size 0.59 0.64)
			(layers "F.Cu" "F.Mask" "F.Paste")
			(roundrect_rratio 0.25)
			(net 346 "Net-(U19-ADBUS0)")
			(pintype "passive")
		)
		(pad "2" smd roundrect
			(at 0.48 0 180)
			(size 0.59 0.64)
			(layers "F.Cu" "F.Mask" "F.Paste")
			(roundrect_rratio 0.25)
			(net 15 "JTAG_TCK")
			(pintype "passive")
		)
	)
	(footprint "antmicro-footprints:R_0402_1005Metric"
		(layer "F.Cu")
		(at 127.45 91.979166 180)
		(descr "Resistor SMD 0402")
		(tags "resistor SMD 0402")
		(property "Reference" "R192"
			(at 0.85 -0.254167 0)
			(layer "F.SilkS")
			(effects
				(font
					(size 0.7 0.7)
					(thickness 0.15)
				)
				(justify right bottom)
			)
		)
		(property "Value" "R_22R_0402"
			(at 0 1.4 0)
			(layer "F.Fab")
			(effects
				(font
					(size 0.7 0.7)
					(thickness 0.15)
				)
				(justify right bottom)
			)
		)
		(property "Datasheet" "https://www.bourns.com/docs/product-datasheets/cr.pdf"
			(at 0 0 180)
			(layer "F.Fab")
			(hide yes)
			(effects
				(font
					(size 1.27 1.27)
					(thickness 0.15)
				)
			)
		)
		(property "Description" "SMD Chip Resistor, 22 ohm, ± 1%, 62.5 mW, 0402 [1005 Metric], Thick Film, General Purpose"
			(at 0 0 180)
			(layer "F.Fab")
			(hide yes)
			(effects
				(font
					(size 1.27 1.27)
					(thickness 0.15)
				)
			)
		)
		(property "Author" "Antmicro"
			(at 254.9 183.958332 0)
			(layer "F.Fab")
			(hide yes)
			(effects
				(font
					(size 1 1)
					(thickness 0.15)
				)
			)
		)
		(property "License" "Apache-2.0"
			(at 254.9 183.958332 0)
			(layer "F.Fab")
			(hide yes)
			(effects
				(font
					(size 1 1)
					(thickness 0.15)
				)
			)
		)
		(property "MPN" "CR0402-FX-22R0GLF"
			(at 254.9 183.958332 0)
			(layer "F.Fab")
			(hide yes)
			(effects
				(font
					(size 1 1)
					(thickness 0.15)
				)
			)
		)
		(property "Manufacturer" "Bourns"
			(at 254.9 183.958332 0)
			(layer "F.Fab")
			(hide yes)
			(effects
				(font
					(size 1 1)
					(thickness 0.15)
				)
			)
		)
		(property "Tolerance" "1%"
			(at 254.9 183.958332 0)
			(layer "F.Fab")
			(hide yes)
			(effects
				(font
					(size 1 1)
					(thickness 0.15)
				)
			)
		)
		(property "Val" "22R"
			(at 254.9 183.958332 0)
			(layer "F.Fab")
			(hide yes)
			(effects
				(font
					(size 1 1)
					(thickness 0.15)
				)
			)
		)
		(sheetname "/Interfaces/")
		(sheetfile "interfaces.kicad_sch")
		(attr smd)
		(fp_rect
			(start -0.925 -0.47)
			(end 0.925 0.47)
			(stroke
				(width 0.05)
				(type default)
			)
			(fill no)
			(layer "F.CrtYd")
		)
		(fp_rect
			(start -0.5 -0.25)
			(end 0.5 0.25)
			(stroke
				(width 0.15)
				(type solid)
			)
			(fill no)
			(layer "F.Fab")
		)
		(pad "1" smd roundrect
			(at -0.48 0 180)
			(size 0.59 0.64)
			(layers "F.Cu" "F.Mask" "F.Paste")
			(roundrect_rratio 0.25)
			(net 349 "Net-(U19-ADBUS2)")
			(pintype "passive")
		)
		(pad "2" smd roundrect
			(at 0.48 0 180)
			(size 0.59 0.64)
			(layers "F.Cu" "F.Mask" "F.Paste")
			(roundrect_rratio 0.25)
			(net 14 "JTAG_TDO")
			(pintype "passive")
		)
	)
	(footprint "antmicro-footprints:TP_SMD_1mm"
		(layer "F.Cu")
		(at 126.25 95.4125)
		(property "Reference" "TP8"
			(at -2.55 0.5875 0)
			(layer "F.SilkS")
			(effects
				(font
					(size 0.7 0.7)
					(thickness 0.15)
				)
				(justify left bottom)
			)
		)
		(property "Value" "TP_1mm_SMD"
			(at 0 1.4 0)
			(layer "F.Fab")
			(effects
				(font
					(size 0.7 0.7)
					(thickness 0.15)
				)
				(justify left bottom)
			)
		)
		(property "Description" "Test point 1mm SMD"
			(at 0 0 0)
			(layer "F.Fab")
			(hide yes)
			(effects
				(font
					(size 1.27 1.27)
					(thickness 0.15)
				)
			)
		)
		(property "Author" "Antmicro"
			(at 0 0 0)
			(layer "F.Fab")
			(hide yes)
			(effects
				(font
					(size 1 1)
					(thickness 0.15)
				)
			)
		)
		(property "License" "Apache-2.0"
			(at 0 0 0)
			(layer "F.Fab")
			(hide yes)
			(effects
				(font
					(size 1 1)
					(thickness 0.15)
				)
			)
		)
		(property "MPN" ""
			(at 0 0 0)
			(layer "F.Fab")
			(hide yes)
			(effects
				(font
					(size 1 1)
					(thickness 0.15)
				)
			)
		)
		(property "Manufacturer" ""
			(at 0 0 0)
			(layer "F.Fab")
			(hide yes)
			(effects
				(font
					(size 1 1)
					(thickness 0.15)
				)
			)
		)
		(sheetname "/Interfaces/")
		(sheetfile "interfaces.kicad_sch")
		(attr exclude_from_pos_files exclude_from_bom)
		(fp_circle
			(center 0 0)
			(end 0.6 0)
			(stroke
				(width 0.05)
				(type default)
			)
			(fill no)
			(layer "F.CrtYd")
		)
		(pad "1" smd circle
			(at 0 0)
			(size 1 1)
			(layers "F.Cu" "F.Mask")
			(net 403 "Net-(U19-ADBUS5)")
			(pinfunction "1")
			(pintype "passive")
		)
	)
	(footprint "antmicro-footprints:Resonator_SMD_Abracon_ABM8G_3.2x2.5mm"
		(layer "F.Cu")
		(at 137.9 86 180)
		(property "Reference" "Y1"
			(at -1.75 -1.75 0)
			(layer "F.SilkS")
			(effects
				(font
					(size 0.7 0.7)
					(thickness 0.15)
				)
				(justify left bottom)
			)
		)
		(property "Value" "Resonator_12MHz_ABM8G"
			(at -1.75 2.548 180)
			(layer "F.Fab")
			(effects
				(font
					(size 0.7 0.7)
					(thickness 0.15)
				)
				(justify left bottom)
			)
		)
		(property "Datasheet" "https://abracon.com/Resonators/ABM8G.pdf"
			(at 0 0 180)
			(layer "F.Fab")
			(hide yes)
			(effects
				(font
					(size 1.27 1.27)
					(thickness 0.15)
				)
			)
		)
		(property "Description" "Crystal, 12 MHz, SMT, 3.2mm x 2.5mm, 30 ppm, 18 pF, 20 ppm, ABM8G"
			(at 0 0 180)
			(layer "F.Fab")
			(hide yes)
			(effects
				(font
					(size 1.27 1.27)
					(thickness 0.15)
				)
			)
		)
		(property "Author" "Antmicro"
			(at 275.8 172 0)
			(layer "F.Fab")
			(hide yes)
			(effects
				(font
					(size 1 1)
					(thickness 0.15)
				)
			)
		)
		(property "License" "Apache-2.0"
			(at 275.8 172 0)
			(layer "F.Fab")
			(hide yes)
			(effects
				(font
					(size 1 1)
					(thickness 0.15)
				)
			)
		)
		(property "MPN" "ABM8G-12.000MHZ-18-D2Y-T"
			(at 275.8 172 0)
			(layer "F.Fab")
			(hide yes)
			(effects
				(font
					(size 1 1)
					(thickness 0.15)
				)
			)
		)
		(property "Manufacturer" "Abracon"
			(at 275.8 172 0)
			(layer "F.Fab")
			(hide yes)
			(effects
				(font
					(size 1 1)
					(thickness 0.15)
				)
			)
		)
		(property "Val" "12 MHz"
			(at 275.8 172 0)
			(layer "F.Fab")
			(hide yes)
			(effects
				(font
					(size 1 1)
					(thickness 0.15)
				)
			)
		)
		(sheetname "/Interfaces/")
		(sheetfile "interfaces.kicad_sch")
		(attr smd)
		(fp_line
			(start 1.6 0.3)
			(end 1.6 -0.2)
			(stroke
				(width 0.15)
				(type solid)
			)
			(layer "F.SilkS")
		)
		(fp_line
			(start -0.35 1.25)
			(end 0.45 1.25)
			(stroke
				(width 0.15)
				(type solid)
			)
			(layer "F.SilkS")
		)
		(fp_line
			(start -0.35 -1.25)
			(end 0.45 -1.25)
			(stroke
				(width 0.15)
				(type solid)
			)
			(layer "F.SilkS")
		)
		(fp_line
			(start -1.6 0.3)
			(end -1.6 -0.2)
			(stroke
				(width 0.15)
				(type solid)
			)
			(layer "F.SilkS")
		)
		(fp_circle
			(center -1.75 1.5)
			(end -1.7 1.5)
			(stroke
				(width 0.15)
				(type solid)
			)
			(fill no)
			(layer "F.SilkS")
		)
		(fp_rect
			(start -1.907 -1.55)
			(end 2.006 1.649)
			(stroke
				(width 0.05)
				(type solid)
			)
			(fill no)
			(layer "F.CrtYd")
		)
		(pad "1" smd roundrect
			(at -1.101 0.949 180)
			(size 1.3 1.1)
			(layers "F.Cu" "F.Mask" "F.Paste")
			(roundrect_rratio 0)
			(chamfer_ratio 0.2)
			(chamfer bottom_left)
			(net 197 "Net-(U19-OSCI)")
			(pintype "passive")
		)
		(pad "2" smd rect
			(at 1.199 0.949 180)
			(size 1.3 1.1)
			(layers "F.Cu" "F.Mask" "F.Paste")
			(net 1 "GND")
			(pinfunction "SH")
			(pintype "passive")
		)
		(pad "3" smd rect
			(at 1.199 -0.85 180)
			(size 1.3 1.1)
			(layers "F.Cu" "F.Mask" "F.Paste")
			(net 198 "Net-(U19-OSCO)")
			(pintype "passive")
		)
		(pad "4" smd rect
			(at -1.101 -0.85 180)
			(size 1.3 1.1)
			(layers "F.Cu" "F.Mask" "F.Paste")
			(net 1 "GND")
			(pinfunction "SH")
			(pintype "passive")
		)
	)
	(footprint "antmicro-footprints:QFN-64-1EP_9x9mm_P0.5mm"
		(layer "F.Cu")
		(at 134.6 95.3 -90)
		(property "Reference" "U19"
			(at 5.075 4.925 0)
			(layer "F.SilkS")
			(effects
				(font
					(size 0.7 0.7)
					(thickness 0.15)
				)
				(justify left top)
			)
		)
		(property "Value" "FT4232H_QFN"
			(at 0 5.9 90)
			(layer "F.Fab")
			(effects
				(font
					(size 0.7 0.7)
					(thickness 0.15)
				)
				(justify right bottom)
			)
		)
		(property "Datasheet" "https://www.ftdichip.com/Support/Documents/DataSheets/ICs/DS_FT4232H.pdf"
			(at 0 0 90)
			(layer "F.Fab")
			(hide yes)
			(effects
				(font
					(size 1.27 1.27)
					(thickness 0.15)
				)
			)
		)
		(property "Description" "Interface Bridges, USB to UART, MPSSE, 1.62 V, 1.98 V, QFN, 64 Pins, -40 °C"
			(at 0 0 90)
			(layer "F.Fab")
			(hide yes)
			(effects
				(font
					(size 1.27 1.27)
					(thickness 0.15)
				)
			)
		)
		(property "Author" "Antmicro"
			(at 39.3 229.9 0)
			(layer "F.Fab")
			(hide yes)
			(effects
				(font
					(size 1 1)
					(thickness 0.15)
				)
			)
		)
		(property "License" "Apache-2.0"
			(at 39.3 229.9 0)
			(layer "F.Fab")
			(hide yes)
			(effects
				(font
					(size 1 1)
					(thickness 0.15)
				)
			)
		)
		(property "MPN" "FT4232HQ-TRAY"
			(at 39.3 229.9 0)
			(layer "F.Fab")
			(hide yes)
			(effects
				(font
					(size 1 1)
					(thickness 0.15)
				)
			)
		)
		(property "Manufacturer" "FTDI Chip"
			(at 39.3 229.9 0)
			(layer "F.Fab")
			(hide yes)
			(effects
				(font
					(size 1 1)
					(thickness 0.15)
				)
			)
		)
		(sheetname "/Interfaces/")
		(sheetfile "interfaces.kicad_sch")
		(attr smd)
		(fp_line
			(start -4.611 4.61)
			(end -4.611 4.11)
			(stroke
				(width 0.15)
				(type solid)
			)
			(layer "F.SilkS")
		)
		(fp_line
			(start -4.111 4.61)
			(end -4.611 4.61)
			(stroke
				(width 0.15)
				(type solid)
			)
			(layer "F.SilkS")
		)
		(fp_line
			(start 4.11 4.61)
			(end 4.61 4.61)
			(stroke
				(width 0.15)
				(type solid)
			)
			(layer "F.SilkS")
		)
		(fp_line
			(start 4.61 4.61)
			(end 4.61 4.11)
			(stroke
				(width 0.15)
				(type solid)
			)
			(layer "F.SilkS")
		)
		(fp_line
			(start -4.611 -4.111)
			(end -4.611 -4.611)
			(stroke
				(width 0.15)
				(type solid)
			)
			(layer "F.SilkS")
		)
		(fp_line
			(start -4.111 -4.611)
			(end -4.611 -4.611)
			(stroke
				(width 0.15)
				(type solid)
			)
			(layer "F.SilkS")
		)
		(fp_line
			(start 4.11 -4.611)
			(end 4.61 -4.611)
			(stroke
				(width 0.15)
				(type solid)
			)
			(layer "F.SilkS")
		)
		(fp_line
			(start 4.61 -4.611)
			(end 4.61 -4.111)
			(stroke
				(width 0.15)
				(type solid)
			)
			(layer "F.SilkS")
		)
		(fp_circle
			(center -4.8 -4)
			(end -4.75 -4)
			(stroke
				(width 0.15)
				(type solid)
			)
			(fill yes)
			(layer "F.SilkS")
		)
		(fp_rect
			(start -4.9 -4.9)
			(end 4.9 4.9)
			(stroke
				(width 0.05)
				(type solid)
			)
			(fill no)
			(layer "F.CrtYd")
		)
		(fp_line
			(start -4.5 -3.5)
			(end -3.5 -4.5)
			(stroke
				(width 0.15)
				(type solid)
			)
			(layer "F.Fab")
		)
		(fp_rect
			(start 4.5 4.5)
			(end -4.5 -4.5)
			(stroke
				(width 0.15)
				(type solid)
			)
			(fill no)
			(layer "F.Fab")
		)
		(fp_text user "Author: Antmicro"
			(at -4.9 7.9 270)
			(layer "F.Fab")
			(effects
				(font
					(size 0.7 0.7)
					(thickness 0.15)
				)
				(justify left bottom)
			)
		)
		(fp_text user "${REFERENCE}"
			(at -4.9 10.3 270)
			(layer "F.Fab")
			(effects
				(font
					(size 0.7 0.7)
					(thickness 0.15)
				)
				(justify left bottom)
			)
		)
		(fp_text user "License: Apache-2.0"
			(at -4.9 9.1 270)
			(layer "F.Fab")
			(effects
				(font
					(size 0.7 0.7)
					(thickness 0.15)
				)
				(justify left bottom)
			)
		)
		(pad "" smd roundrect
			(at -1.401 -1.401 270)
			(size 1.05 1.05)
			(layers "F.Paste")
			(roundrect_rratio 0.197928)
		)
		(pad "" smd roundrect
			(at -1.401 0 270)
			(size 1.05 1.05)
			(layers "F.Paste")
			(roundrect_rratio 0.197928)
		)
		(pad "" smd roundrect
			(at -1.401 1.398 270)
			(size 1.05 1.05)
			(layers "F.Paste")
			(roundrect_rratio 0.197928)
		)
		(pad "" smd roundrect
			(at 0 -1.401 270)
			(size 1.05 1.05)
			(layers "F.Paste")
			(roundrect_rratio 0.197928)
		)
		(pad "" smd roundrect
			(at 0 0 270)
			(size 1.05 1.05)
			(layers "F.Paste")
			(roundrect_rratio 0.197928)
		)
		(pad "" smd roundrect
			(at 0 1.398 270)
			(size 1.05 1.05)
			(layers "F.Paste")
			(roundrect_rratio 0.197928)
		)
		(pad "" smd roundrect
			(at 1.398 -1.401 270)
			(size 1.05 1.05)
			(layers "F.Paste")
			(roundrect_rratio 0.197928)
		)
		(pad "" smd roundrect
			(at 1.398 0 270)
			(size 1.05 1.05)
			(layers "F.Paste")
			(roundrect_rratio 0.197928)
		)
		(pad "" smd roundrect
			(at 1.398 1.398 270)
			(size 1.05 1.05)
			(layers "F.Paste")
			(roundrect_rratio 0.197928)
		)
		(pad "1" smd roundrect
			(at -4.414 -3.75 270)
			(size 0.875 0.2)
			(layers "F.Cu" "F.Mask" "F.Paste")
			(roundrect_rratio 0.25)
			(net 1 "GND")
			(pinfunction "GND")
			(pintype "power_in")
		)
		(pad "2" smd roundrect
			(at -4.414 -3.25 270)
			(size 0.875 0.2)
			(layers "F.Cu" "F.Mask" "F.Paste")
			(roundrect_rratio 0.25)
			(net 197 "Net-(U19-OSCI)")
			(pinfunction "OSCI")
			(pintype "input")
		)
		(pad "3" smd roundrect
			(at -4.414 -2.75 270)
			(size 0.875 0.2)
			(layers "F.Cu" "F.Mask" "F.Paste")
			(roundrect_rratio 0.25)
			(net 198 "Net-(U19-OSCO)")
			(pinfunction "OSCO")
			(pintype "output")
		)
		(pad "4" smd roundrect
			(at -4.414 -2.25 270)
			(size 0.875 0.2)
			(layers "F.Cu" "F.Mask" "F.Paste")
			(roundrect_rratio 0.25)
			(net 115 "/Interfaces/FT_VPHY")
			(pinfunction "V_{PHY}")
			(pintype "power_in")
		)
		(pad "5" smd roundrect
			(at -4.414 -1.75 270)
			(size 0.875 0.2)
			(layers "F.Cu" "F.Mask" "F.Paste")
			(roundrect_rratio 0.25)
			(net 1 "GND")
			(pinfunction "GND")
			(pintype "passive")
		)
		(pad "6" smd roundrect
			(at -4.414 -1.25 270)
			(size 0.875 0.2)
			(layers "F.Cu" "F.Mask" "F.Paste")
			(roundrect_rratio 0.25)
			(net 298 "Net-(U19-REF)")
			(pinfunction "REF")
			(pintype "input")
		)
		(pad "7" smd roundrect
			(at -4.414 -0.75 270)
			(size 0.875 0.2)
			(layers "F.Cu" "F.Mask" "F.Paste")
			(roundrect_rratio 0.25)
			(net 213 "/Interfaces/DBG_USB_D_N")
			(pinfunction "D-")
			(pintype "bidirectional")
		)
		(pad "8" smd roundrect
			(at -4.414 -0.25 270)
			(size 0.875 0.2)
			(layers "F.Cu" "F.Mask" "F.Paste")
			(roundrect_rratio 0.25)
			(net 212 "/Interfaces/DBG_USB_D_P")
			(pinfunction "D+")
			(pintype "bidirectional")
		)
		(pad "9" smd roundrect
			(at -4.414 0.248 270)
			(size 0.875 0.2)
			(layers "F.Cu" "F.Mask" "F.Paste")
			(roundrect_rratio 0.25)
			(net 116 "/Interfaces/FT_VPLL")
			(pinfunction "V_{PLL}")
			(pintype "power_in")
		)
		(pad "10" smd roundrect
			(at -4.414 0.748 270)
			(size 0.875 0.2)
			(layers "F.Cu" "F.Mask" "F.Paste")
			(roundrect_rratio 0.25)
			(net 1 "GND")
			(pinfunction "AGND")
			(pintype "power_in")
		)
		(pad "11" smd roundrect
			(at -4.414 1.249 270)
			(size 0.875 0.2)
			(layers "F.Cu" "F.Mask" "F.Paste")
			(roundrect_rratio 0.25)
			(net 1 "GND")
			(pinfunction "GND")
			(pintype "passive")
		)
		(pad "12" smd roundrect
			(at -4.414 1.749 270)
			(size 0.875 0.2)
			(layers "F.Cu" "F.Mask" "F.Paste")
			(roundrect_rratio 0.25)
			(net 597 "1V8_FT")
			(pinfunction "V_{CORE}")
			(pintype "power_in")
		)
		(pad "13" smd roundrect
			(at -4.414 2.249 270)
			(size 0.875 0.2)
			(layers "F.Cu" "F.Mask" "F.Paste")
			(roundrect_rratio 0.25)
			(net 1 "GND")
			(pinfunction "TEST")
			(pintype "input")
		)
		(pad "14" smd roundrect
			(at -4.414 2.749 270)
			(size 0.875 0.2)
			(layers "F.Cu" "F.Mask" "F.Paste")
			(roundrect_rratio 0.25)
			(net 299 "Net-(U19-~{RESET})")
			(pinfunction "~{RESET}")
			(pintype "input")
		)
		(pad "15" smd roundrect
			(at -4.414 3.249 270)
			(size 0.875 0.2)
			(layers "F.Cu" "F.Mask" "F.Paste")
			(roundrect_rratio 0.25)
			(net 1 "GND")
			(pinfunction "GND")
			(pintype "passive")
		)
		(pad "16" smd roundrect
			(at -4.414 3.749 270)
			(size 0.875 0.2)
			(layers "F.Cu" "F.Mask" "F.Paste")
			(roundrect_rratio 0.25)
			(net 346 "Net-(U19-ADBUS0)")
			(pinfunction "ADBUS0")
			(pintype "bidirectional")
		)
		(pad "17" smd roundrect
			(at -3.75 4.411 270)
			(size 0.2 0.875)
			(layers "F.Cu" "F.Mask" "F.Paste")
			(roundrect_rratio 0.25)
			(net 348 "Net-(U19-ADBUS1)")
			(pinfunction "ADBUS1")
			(pintype "bidirectional")
		)
		(pad "18" smd roundrect
			(at -3.25 4.411 270)
			(size 0.2 0.875)
			(layers "F.Cu" "F.Mask" "F.Paste")
			(roundrect_rratio 0.25)
			(net 349 "Net-(U19-ADBUS2)")
			(pinfunction "ADBUS2")
			(pintype "bidirectional")
		)
		(pad "19" smd roundrect
			(at -2.75 4.411 270)
			(size 0.2 0.875)
			(layers "F.Cu" "F.Mask" "F.Paste")
			(roundrect_rratio 0.25)
			(net 399 "Net-(U19-ADBUS3)")
			(pinfunction "ADBUS3")
			(pintype "bidirectional")
		)
		(pad "20" smd roundrect
			(at -2.25 4.411 270)
			(size 0.2 0.875)
			(layers "F.Cu" "F.Mask" "F.Paste")
			(roundrect_rratio 0.25)
			(net 2 "VCC3V3")
			(pinfunction "V_{CCIO}")
			(pintype "power_in")
		)
		(pad "21" smd roundrect
			(at -1.75 4.411 270)
			(size 0.2 0.875)
			(layers "F.Cu" "F.Mask" "F.Paste")
			(roundrect_rratio 0.25)
			(net 657 "unconnected-(U19-ADBUS4-Pad21)")
			(pinfunction "ADBUS4")
			(pintype "bidirectional+no_connect")
		)
		(pad "22" smd roundrect
			(at -1.25 4.411 270)
			(size 0.2 0.875)
			(layers "F.Cu" "F.Mask" "F.Paste")
			(roundrect_rratio 0.25)
			(net 403 "Net-(U19-ADBUS5)")
			(pinfunction "ADBUS5")
			(pintype "bidirectional")
		)
		(pad "23" smd roundrect
			(at -0.75 4.411 270)
			(size 0.2 0.875)
			(layers "F.Cu" "F.Mask" "F.Paste")
			(roundrect_rratio 0.25)
			(net 658 "unconnected-(U19-ADBUS6-Pad23)")
			(pinfunction "ADBUS6")
			(pintype "bidirectional+no_connect")
		)
		(pad "24" smd roundrect
			(at -0.25 4.411 270)
			(size 0.2 0.875)
			(layers "F.Cu" "F.Mask" "F.Paste")
			(roundrect_rratio 0.25)
			(net 659 "unconnected-(U19-ADBUS7-Pad24)")
			(pinfunction "ADBUS7")
			(pintype "bidirectional+no_connect")
		)
		(pad "25" smd roundrect
			(at 0.248 4.411 270)
			(size 0.2 0.875)
			(layers "F.Cu" "F.Mask" "F.Paste")
			(roundrect_rratio 0.25)
			(net 1 "GND")
			(pinfunction "GND")
			(pintype "passive")
		)
		(pad "26" smd roundrect
			(at 0.748 4.411 270)
			(size 0.2 0.875)
			(layers "F.Cu" "F.Mask" "F.Paste")
			(roundrect_rratio 0.25)
			(net 660 "unconnected-(U19-BDBUS0-Pad26)")
			(pinfunction "BDBUS0")
			(pintype "bidirectional+no_connect")
		)
		(pad "27" smd roundrect
			(at 1.249 4.411 270)
			(size 0.2 0.875)
			(layers "F.Cu" "F.Mask" "F.Paste")
			(roundrect_rratio 0.25)
			(net 661 "unconnected-(U19-BDBUS1-Pad27)")
			(pinfunction "BDBUS1")
			(pintype "bidirectional+no_connect")
		)
		(pad "28" smd roundrect
			(at 1.749 4.411 270)
			(size 0.2 0.875)
			(layers "F.Cu" "F.Mask" "F.Paste")
			(roundrect_rratio 0.25)
			(net 662 "unconnected-(U19-BDBUS2-Pad28)")
			(pinfunction "BDBUS2")
			(pintype "bidirectional+no_connect")
		)
		(pad "29" smd roundrect
			(at 2.249 4.411 270)
			(size 0.2 0.875)
			(layers "F.Cu" "F.Mask" "F.Paste")
			(roundrect_rratio 0.25)
			(net 663 "unconnected-(U19-BDBUS3-Pad29)")
			(pinfunction "BDBUS3")
			(pintype "bidirectional+no_connect")
		)
		(pad "30" smd roundrect
			(at 2.749 4.411 270)
			(size 0.2 0.875)
			(layers "F.Cu" "F.Mask" "F.Paste")
			(roundrect_rratio 0.25)
			(net 664 "unconnected-(U19-BDBUS4-Pad30)")
			(pinfunction "BDBUS4")
			(pintype "bidirectional+no_connect")
		)
		(pad "31" smd roundrect
			(at 3.249 4.411 270)
			(size 0.2 0.875)
			(layers "F.Cu" "F.Mask" "F.Paste")
			(roundrect_rratio 0.25)
			(net 2 "VCC3V3")
			(pinfunction "V_{CCIO}")
			(pintype "passive")
		)
		(pad "32" smd roundrect
			(at 3.749 4.411 270)
			(size 0.2 0.875)
			(layers "F.Cu" "F.Mask" "F.Paste")
			(roundrect_rratio 0.25)
			(net 665 "unconnected-(U19-BDBUS5-Pad32)")
			(pinfunction "BDBUS5")
			(pintype "bidirectional+no_connect")
		)
		(pad "33" smd roundrect
			(at 4.411 3.749 270)
			(size 0.875 0.2)
			(layers "F.Cu" "F.Mask" "F.Paste")
			(roundrect_rratio 0.25)
			(net 666 "unconnected-(U19-BDBUS6-Pad33)")
			(pinfunction "BDBUS6")
			(pintype "bidirectional+no_connect")
		)
		(pad "34" smd roundrect
			(at 4.411 3.249 270)
			(size 0.875 0.2)
			(layers "F.Cu" "F.Mask" "F.Paste")
			(roundrect_rratio 0.25)
			(net 667 "unconnected-(U19-BDBUS7-Pad34)")
			(pinfunction "BDBUS7")
			(pintype "bidirectional+no_connect")
		)
		(pad "35" smd roundrect
			(at 4.411 2.749 270)
			(size 0.875 0.2)
			(layers "F.Cu" "F.Mask" "F.Paste")
			(roundrect_rratio 0.25)
			(net 1 "GND")
			(pinfunction "GND")
			(pintype "passive")
		)
		(pad "36" smd roundrect
			(at 4.411 2.249 270)
			(size 0.875 0.2)
			(layers "F.Cu" "F.Mask" "F.Paste")
			(roundrect_rratio 0.25)
			(net 668 "unconnected-(U19-SUSPEND-Pad36)")
			(pinfunction "SUSPEND")
			(pintype "output+no_connect")
		)
		(pad "37" smd roundrect
			(at 4.411 1.749 270)
			(size 0.875 0.2)
			(layers "F.Cu" "F.Mask" "F.Paste")
			(roundrect_rratio 0.25)
			(net 597 "1V8_FT")
			(pinfunction "V_{CORE}")
			(pintype "passive")
		)
		(pad "38" smd roundrect
			(at 4.411 1.249 270)
			(size 0.875 0.2)
			(layers "F.Cu" "F.Mask" "F.Paste")
			(roundrect_rratio 0.25)
			(net 400 "Net-(U19-CDBUS0)")
			(pinfunction "CDBUS0")
			(pintype "bidirectional")
		)
		(pad "39" smd roundrect
			(at 4.411 0.748 270)
			(size 0.875 0.2)
			(layers "F.Cu" "F.Mask" "F.Paste")
			(roundrect_rratio 0.25)
			(net 401 "Net-(U19-CDBUS1)")
			(pinfunction "CDBUS1")
			(pintype "bidirectional")
		)
		(pad "40" smd roundrect
			(at 4.411 0.248 270)
			(size 0.875 0.2)
			(layers "F.Cu" "F.Mask" "F.Paste")
			(roundrect_rratio 0.25)
			(net 669 "unconnected-(U19-CDBUS2-Pad40)")
			(pinfunction "CDBUS2")
			(pintype "bidirectional+no_connect")
		)
		(pad "41" smd roundrect
			(at 4.411 -0.25 270)
			(size 0.875 0.2)
			(layers "F.Cu" "F.Mask" "F.Paste")
			(roundrect_rratio 0.25)
			(net 670 "unconnected-(U19-CDBUS3-Pad41)")
			(pinfunction "CDBUS3")
			(pintype "bidirectional+no_connect")
		)
		(pad "42" smd roundrect
			(at 4.411 -0.75 270)
			(size 0.875 0.2)
			(layers "F.Cu" "F.Mask" "F.Paste")
			(roundrect_rratio 0.25)
			(net 2 "VCC3V3")
			(pinfunction "V_{CCIO}")
			(pintype "passive")
		)
		(pad "43" smd roundrect
			(at 4.411 -1.25 270)
			(size 0.875 0.2)
			(layers "F.Cu" "F.Mask" "F.Paste")
			(roundrect_rratio 0.25)
			(net 671 "unconnected-(U19-CDBUS4-Pad43)")
			(pinfunction "CDBUS4")
			(pintype "bidirectional+no_connect")
		)
		(pad "44" smd roundrect
			(at 4.411 -1.75 270)
			(size 0.875 0.2)
			(layers "F.Cu" "F.Mask" "F.Paste")
			(roundrect_rratio 0.25)
			(net 672 "unconnected-(U19-CDBUS5-Pad44)")
			(pinfunction "CDBUS5")
			(pintype "bidirectional+no_connect")
		)
		(pad "45" smd roundrect
			(at 4.411 -2.25 270)
			(size 0.875 0.2)
			(layers "F.Cu" "F.Mask" "F.Paste")
			(roundrect_rratio 0.25)
			(net 673 "unconnected-(U19-CDBUS6-Pad45)")
			(pinfunction "CDBUS6")
			(pintype "bidirectional+no_connect")
		)
		(pad "46" smd roundrect
			(at 4.411 -2.75 270)
			(size 0.875 0.2)
			(layers "F.Cu" "F.Mask" "F.Paste")
			(roundrect_rratio 0.25)
			(net 674 "unconnected-(U19-CDBUS7-Pad46)")
			(pinfunction "CDBUS7")
			(pintype "bidirectional+no_connect")
		)
		(pad "47" smd roundrect
			(at 4.411 -3.25 270)
			(size 0.875 0.2)
			(layers "F.Cu" "F.Mask" "F.Paste")
			(roundrect_rratio 0.25)
			(net 1 "GND")
			(pinfunction "GND")
			(pintype "passive")
		)
		(pad "48" smd roundrect
			(at 4.411 -3.75 270)
			(size 0.875 0.2)
			(layers "F.Cu" "F.Mask" "F.Paste")
			(roundrect_rratio 0.25)
			(net 675 "unconnected-(U19-DDBUS0-Pad48)")
			(pinfunction "DDBUS0")
			(pintype "bidirectional+no_connect")
		)
		(pad "49" smd roundrect
			(at 3.749 -4.414 270)
			(size 0.2 0.875)
			(layers "F.Cu" "F.Mask" "F.Paste")
			(roundrect_rratio 0.25)
			(net 597 "1V8_FT")
			(pinfunction "V_{REGOUT}")
			(pintype "power_out")
		)
		(pad "50" smd roundrect
			(at 3.249 -4.414 270)
			(size 0.2 0.875)
			(layers "F.Cu" "F.Mask" "F.Paste")
			(roundrect_rratio 0.25)
			(net 2 "VCC3V3")
			(pinfunction "V_{REGIN}")
			(pintype "power_in")
		)
		(pad "51" smd roundrect
			(at 2.749 -4.414 270)
			(size 0.2 0.875)
			(layers "F.Cu" "F.Mask" "F.Paste")
			(roundrect_rratio 0.25)
			(net 1 "GND")
			(pinfunction "GND")
			(pintype "passive")
		)
		(pad "52" smd roundrect
			(at 2.249 -4.414 270)
			(size 0.2 0.875)
			(layers "F.Cu" "F.Mask" "F.Paste")
			(roundrect_rratio 0.25)
			(net 676 "unconnected-(U19-DDBUS1-Pad52)")
			(pinfunction "DDBUS1")
			(pintype "bidirectional+no_connect")
		)
		(pad "53" smd roundrect
			(at 1.749 -4.414 270)
			(size 0.2 0.875)
			(layers "F.Cu" "F.Mask" "F.Paste")
			(roundrect_rratio 0.25)
			(net 677 "unconnected-(U19-DDBUS2-Pad53)")
			(pinfunction "DDBUS2")
			(pintype "bidirectional+no_connect")
		)
		(pad "54" smd roundrect
			(at 1.249 -4.414 270)
			(size 0.2 0.875)
			(layers "F.Cu" "F.Mask" "F.Paste")
			(roundrect_rratio 0.25)
			(net 678 "unconnected-(U19-DDBUS3-Pad54)")
			(pinfunction "DDBUS3")
			(pintype "bidirectional+no_connect")
		)
		(pad "55" smd roundrect
			(at 0.748 -4.414 270)
			(size 0.2 0.875)
			(layers "F.Cu" "F.Mask" "F.Paste")
			(roundrect_rratio 0.25)
			(net 679 "unconnected-(U19-DDBUS4-Pad55)")
			(pinfunction "DDBUS4")
			(pintype "bidirectional+no_connect")
		)
		(pad "56" smd roundrect
			(at 0.248 -4.414 270)
			(size 0.2 0.875)
			(layers "F.Cu" "F.Mask" "F.Paste")
			(roundrect_rratio 0.25)
			(net 2 "VCC3V3")
			(pinfunction "V_{CCIO}")
			(pintype "passive")
		)
		(pad "57" smd roundrect
			(at -0.25 -4.414 270)
			(size 0.2 0.875)
			(layers "F.Cu" "F.Mask" "F.Paste")
			(roundrect_rratio 0.25)
			(net 680 "unconnected-(U19-DDBUS5-Pad57)")
			(pinfunction "DDBUS5")
			(pintype "bidirectional+no_connect")
		)
		(pad "58" smd roundrect
			(at -0.75 -4.414 270)
			(size 0.2 0.875)
			(layers "F.Cu" "F.Mask" "F.Paste")
			(roundrect_rratio 0.25)
			(net 681 "unconnected-(U19-DDBUS6-Pad58)")
			(pinfunction "DDBUS6")
			(pintype "bidirectional+no_connect")
		)
		(pad "59" smd roundrect
			(at -1.25 -4.414 270)
			(size 0.2 0.875)
			(layers "F.Cu" "F.Mask" "F.Paste")
			(roundrect_rratio 0.25)
			(net 682 "unconnected-(U19-DDBUS7-Pad59)")
			(pinfunction "DDBUS7")
			(pintype "bidirectional+no_connect")
		)
		(pad "60" smd roundrect
			(at -1.75 -4.414 270)
			(size 0.2 0.875)
			(layers "F.Cu" "F.Mask" "F.Paste")
			(roundrect_rratio 0.25)
			(net 683 "unconnected-(U19-PWREN-Pad60)")
			(pinfunction "PWREN")
			(pintype "output+no_connect")
		)
		(pad "61" smd roundrect
			(at -2.25 -4.414 270)
			(size 0.2 0.875)
			(layers "F.Cu" "F.Mask" "F.Paste")
			(roundrect_rratio 0.25)
			(net 684 "unconnected-(U19-EEDATA-Pad61)")
			(pinfunction "EEDATA")
			(pintype "bidirectional+no_connect")
		)
		(pad "62" smd roundrect
			(at -2.75 -4.414 270)
			(size 0.2 0.875)
			(layers "F.Cu" "F.Mask" "F.Paste")
			(roundrect_rratio 0.25)
			(net 685 "unconnected-(U19-EECLK-Pad62)")
			(pinfunction "EECLK")
			(pintype "output+no_connect")
		)
		(pad "63" smd roundrect
			(at -3.25 -4.414 270)
			(size 0.2 0.875)
			(layers "F.Cu" "F.Mask" "F.Paste")
			(roundrect_rratio 0.25)
			(net 686 "unconnected-(U19-EECS-Pad63)")
			(pinfunction "EECS")
			(pintype "bidirectional+no_connect")
		)
		(pad "64" smd roundrect
			(at -3.75 -4.414 270)
			(size 0.2 0.875)
			(layers "F.Cu" "F.Mask" "F.Paste")
			(roundrect_rratio 0.25)
			(net 597 "1V8_FT")
			(pinfunction "V_{CORE}")
			(pintype "passive")
		)
		(pad "65" smd roundrect
			(at 0 0 270)
			(size 4.7 4.7)
			(layers "F.Cu" "F.Mask")
			(roundrect_rratio 0.053191)
			(net 1 "GND")
			(pinfunction "GND")
			(pintype "passive")
		)
	)
	(footprint "antmicro-footprints:R_0402_1005Metric"
		(layer "F.Cu")
		(at 127.45 93.1125 180)
		(descr "Resistor SMD 0402")
		(tags "resistor SMD 0402")
		(property "Reference" "R193"
			(at 0.85 -0.254167 0)
			(layer "F.SilkS")
			(effects
				(font
					(size 0.7 0.7)
					(thickness 0.15)
				)
				(justify right bottom)
			)
		)
		(property "Value" "R_22R_0402"
			(at 0 1.4 0)
			(layer "F.Fab")
			(effects
				(font
					(size 0.7 0.7)
					(thickness 0.15)
				)
				(justify right bottom)
			)
		)
		(property "Datasheet" "https://www.bourns.com/docs/product-datasheets/cr.pdf"
			(at 0 0 180)
			(layer "F.Fab")
			(hide yes)
			(effects
				(font
					(size 1.27 1.27)
					(thickness 0.15)
				)
			)
		)
		(property "Description" "SMD Chip Resistor, 22 ohm, ± 1%, 62.5 mW, 0402 [1005 Metric], Thick Film, General Purpose"
			(at 0 0 180)
			(layer "F.Fab")
			(hide yes)
			(effects
				(font
					(size 1.27 1.27)
					(thickness 0.15)
				)
			)
		)
		(property "Author" "Antmicro"
			(at 254.9 186.225 0)
			(layer "F.Fab")
			(hide yes)
			(effects
				(font
					(size 1 1)
					(thickness 0.15)
				)
			)
		)
		(property "License" "Apache-2.0"
			(at 254.9 186.225 0)
			(layer "F.Fab")
			(hide yes)
			(effects
				(font
					(size 1 1)
					(thickness 0.15)
				)
			)
		)
		(property "MPN" "CR0402-FX-22R0GLF"
			(at 254.9 186.225 0)
			(layer "F.Fab")
			(hide yes)
			(effects
				(font
					(size 1 1)
					(thickness 0.15)
				)
			)
		)
		(property "Manufacturer" "Bourns"
			(at 254.9 186.225 0)
			(layer "F.Fab")
			(hide yes)
			(effects
				(font
					(size 1 1)
					(thickness 0.15)
				)
			)
		)
		(property "Tolerance" "1%"
			(at 254.9 186.225 0)
			(layer "F.Fab")
			(hide yes)
			(effects
				(font
					(size 1 1)
					(thickness 0.15)
				)
			)
		)
		(property "Val" "22R"
			(at 254.9 186.225 0)
			(layer "F.Fab")
			(hide yes)
			(effects
				(font
					(size 1 1)
					(thickness 0.15)
				)
			)
		)
		(sheetname "/Interfaces/")
		(sheetfile "interfaces.kicad_sch")
		(attr smd)
		(fp_rect
			(start -0.925 -0.47)
			(end 0.925 0.47)
			(stroke
				(width 0.05)
				(type default)
			)
			(fill no)
			(layer "F.CrtYd")
		)
		(fp_rect
			(start -0.5 -0.25)
			(end 0.5 0.25)
			(stroke
				(width 0.15)
				(type solid)
			)
			(fill no)
			(layer "F.Fab")
		)
		(pad "1" smd roundrect
			(at -0.48 0 180)
			(size 0.59 0.64)
			(layers "F.Cu" "F.Mask" "F.Paste")
			(roundrect_rratio 0.25)
			(net 399 "Net-(U19-ADBUS3)")
			(pintype "passive")
		)
		(pad "2" smd roundrect
			(at 0.48 0 180)
			(size 0.59 0.64)
			(layers "F.Cu" "F.Mask" "F.Paste")
			(roundrect_rratio 0.25)
			(net 16 "JTAG_TMS")
			(pintype "passive")
		)
	)
	(footprint "antmicro-footprints:R_0402_1005Metric"
		(layer "F.Cu")
		(at 127.45 90.845833 180)
		(descr "Resistor SMD 0402")
		(tags "resistor SMD 0402")
		(property "Reference" "R191"
			(at 0.85 -0.254167 0)
			(layer "F.SilkS")
			(effects
				(font
					(size 0.7 0.7)
					(thickness 0.15)
				)
				(justify right bottom)
			)
		)
		(property "Value" "R_22R_0402"
			(at 0 1.4 0)
			(layer "F.Fab")
			(effects
				(font
					(size 0.7 0.7)
					(thickness 0.15)
				)
				(justify right bottom)
			)
		)
		(property "Datasheet" "https://www.bourns.com/docs/product-datasheets/cr.pdf"
			(at 0 0 180)
			(layer "F.Fab")
			(hide yes)
			(effects
				(font
					(size 1.27 1.27)
					(thickness 0.15)
				)
			)
		)
		(property "Description" "SMD Chip Resistor, 22 ohm, ± 1%, 62.5 mW, 0402 [1005 Metric], Thick Film, General Purpose"
			(at 0 0 180)
			(layer "F.Fab")
			(hide yes)
			(effects
				(font
					(size 1.27 1.27)
					(thickness 0.15)
				)
			)
		)
		(property "Author" "Antmicro"
			(at 254.9 181.691666 0)
			(layer "F.Fab")
			(hide yes)
			(effects
				(font
					(size 1 1)
					(thickness 0.15)
				)
			)
		)
		(property "License" "Apache-2.0"
			(at 254.9 181.691666 0)
			(layer "F.Fab")
			(hide yes)
			(effects
				(font
					(size 1 1)
					(thickness 0.15)
				)
			)
		)
		(property "MPN" "CR0402-FX-22R0GLF"
			(at 254.9 181.691666 0)
			(layer "F.Fab")
			(hide yes)
			(effects
				(font
					(size 1 1)
					(thickness 0.15)
				)
			)
		)
		(property "Manufacturer" "Bourns"
			(at 254.9 181.691666 0)
			(layer "F.Fab")
			(hide yes)
			(effects
				(font
					(size 1 1)
					(thickness 0.15)
				)
			)
		)
		(property "Tolerance" "1%"
			(at 254.9 181.691666 0)
			(layer "F.Fab")
			(hide yes)
			(effects
				(font
					(size 1 1)
					(thickness 0.15)
				)
			)
		)
		(property "Val" "22R"
			(at 254.9 181.691666 0)
			(layer "F.Fab")
			(hide yes)
			(effects
				(font
					(size 1 1)
					(thickness 0.15)
				)
			)
		)
		(sheetname "/Interfaces/")
		(sheetfile "interfaces.kicad_sch")
		(attr smd)
		(fp_rect
			(start -0.925 -0.47)
			(end 0.925 0.47)
			(stroke
				(width 0.05)
				(type default)
			)
			(fill no)
			(layer "F.CrtYd")
		)
		(fp_rect
			(start -0.5 -0.25)
			(end 0.5 0.25)
			(stroke
				(width 0.15)
				(type solid)
			)
			(fill no)
			(layer "F.Fab")
		)
		(pad "1" smd roundrect
			(at -0.48 0 180)
			(size 0.59 0.64)
			(layers "F.Cu" "F.Mask" "F.Paste")
			(roundrect_rratio 0.25)
			(net 348 "Net-(U19-ADBUS1)")
			(pintype "passive")
		)
		(pad "2" smd roundrect
			(at 0.48 0 180)
			(size 0.59 0.64)
			(layers "F.Cu" "F.Mask" "F.Paste")
			(roundrect_rratio 0.25)
			(net 13 "JTAG_TDI")
			(pintype "passive")
		)
	)
	(footprint "antmicro-footprints:R_0402_1005Metric"
		(layer "F.Cu")
		(at 130.425 88.7125 90)
		(descr "Resistor SMD 0402")
		(tags "resistor SMD 0402")
		(property "Reference" "R197"
			(at 0.8125 0.375 90)
			(layer "F.SilkS")
			(effects
				(font
					(size 0.7 0.7)
					(thickness 0.15)
				)
				(justify left bottom)
			)
		)
		(property "Value" "R_4k7_0402"
			(at 0 1.4 90)
			(layer "F.Fab")
			(effects
				(font
					(size 0.7 0.7)
					(thickness 0.15)
				)
				(justify left bottom)
			)
		)
		(property "Datasheet" "https://www.bourns.com/docs/product-datasheets/cr.pdf"
			(at 0 0 90)
			(layer "F.Fab")
			(hide yes)
			(effects
				(font
					(size 1.27 1.27)
					(thickness 0.15)
				)
			)
		)
		(property "Description" "SMD Chip Resistor, 4.7 kohm, ± 1%, 62.5 mW, 0402 [1005 Metric], Thick Film, General Purpose"
			(at 0 0 90)
			(layer "F.Fab")
			(hide yes)
			(effects
				(font
					(size 1.27 1.27)
					(thickness 0.15)
				)
			)
		)
		(property "Author" "Antmicro"
			(at 219.1375 -41.7125 0)
			(layer "F.Fab")
			(hide yes)
			(effects
				(font
					(size 1 1)
					(thickness 0.15)
				)
			)
		)
		(property "License" "Apache-2.0"
			(at 219.1375 -41.7125 0)
			(layer "F.Fab")
			(hide yes)
			(effects
				(font
					(size 1 1)
					(thickness 0.15)
				)
			)
		)
		(property "MPN" "CR0402-FX-4701GLF"
			(at 219.1375 -41.7125 0)
			(layer "F.Fab")
			(hide yes)
			(effects
				(font
					(size 1 1)
					(thickness 0.15)
				)
			)
		)
		(property "Manufacturer" "Bourns"
			(at 219.1375 -41.7125 0)
			(layer "F.Fab")
			(hide yes)
			(effects
				(font
					(size 1 1)
					(thickness 0.15)
				)
			)
		)
		(property "Tolerance" "1%"
			(at 219.1375 -41.7125 0)
			(layer "F.Fab")
			(hide yes)
			(effects
				(font
					(size 1 1)
					(thickness 0.15)
				)
			)
		)
		(property "Val" "4k7"
			(at 219.1375 -41.7125 0)
			(layer "F.Fab")
			(hide yes)
			(effects
				(font
					(size 1 1)
					(thickness 0.15)
				)
			)
		)
		(sheetname "/Interfaces/")
		(sheetfile "interfaces.kicad_sch")
		(attr smd)
		(fp_rect
			(start -0.925 -0.47)
			(end 0.925 0.47)
			(stroke
				(width 0.05)
				(type default)
			)
			(fill no)
			(layer "F.CrtYd")
		)
		(fp_rect
			(start -0.5 -0.25)
			(end 0.5 0.25)
			(stroke
				(width 0.15)
				(type solid)
			)
			(fill no)
			(layer "F.Fab")
		)
		(pad "1" smd roundrect
			(at -0.48 0 90)
			(size 0.59 0.64)
			(layers "F.Cu" "F.Mask" "F.Paste")
			(roundrect_rratio 0.25)
			(net 299 "Net-(U19-~{RESET})")
			(pintype "passive")
		)
		(pad "2" smd roundrect
			(at 0.48 0 90)
			(size 0.59 0.64)
			(layers "F.Cu" "F.Mask" "F.Paste")
			(roundrect_rratio 0.25)
			(net 240 "/Interfaces/VBUS")
			(pintype "passive")
		)
	)
	(footprint "antmicro-footprints:R_0402_1005Metric"
		(layer "F.Cu")
		(at 130.885 104.775 180)
		(descr "Resistor SMD 0402")
		(tags "resistor SMD 0402")
		(property "Reference" "R196"
			(at 0.785 -0.425 0)
			(layer "F.SilkS")
			(effects
				(font
					(size 0.7 0.7)
					(thickness 0.15)
				)
				(justify right bottom)
			)
		)
		(property "Value" "R_22R_0402"
			(at 0 1.4 0)
			(layer "F.Fab")
			(effects
				(font
					(size 0.7 0.7)
					(thickness 0.15)
				)
				(justify right bottom)
			)
		)
		(property "Datasheet" "https://www.bourns.com/docs/product-datasheets/cr.pdf"
			(at 0 0 180)
			(layer "F.Fab")
			(hide yes)
			(effects
				(font
					(size 1.27 1.27)
					(thickness 0.15)
				)
			)
		)
		(property "Description" "SMD Chip Resistor, 22 ohm, ± 1%, 62.5 mW, 0402 [1005 Metric], Thick Film, General Purpose"
			(at 0 0 180)
			(layer "F.Fab")
			(hide yes)
			(effects
				(font
					(size 1.27 1.27)
					(thickness 0.15)
				)
			)
		)
		(property "Author" "Antmicro"
			(at 261.77 209.55 0)
			(layer "F.Fab")
			(hide yes)
			(effects
				(font
					(size 1 1)
					(thickness 0.15)
				)
			)
		)
		(property "License" "Apache-2.0"
			(at 261.77 209.55 0)
			(layer "F.Fab")
			(hide yes)
			(effects
				(font
					(size 1 1)
					(thickness 0.15)
				)
			)
		)
		(property "MPN" "CR0402-FX-22R0GLF"
			(at 261.77 209.55 0)
			(layer "F.Fab")
			(hide yes)
			(effects
				(font
					(size 1 1)
					(thickness 0.15)
				)
			)
		)
		(property "Manufacturer" "Bourns"
			(at 261.77 209.55 0)
			(layer "F.Fab")
			(hide yes)
			(effects
				(font
					(size 1 1)
					(thickness 0.15)
				)
			)
		)
		(property "Tolerance" "1%"
			(at 261.77 209.55 0)
			(layer "F.Fab")
			(hide yes)
			(effects
				(font
					(size 1 1)
					(thickness 0.15)
				)
			)
		)
		(property "Val" "22R"
			(at 261.77 209.55 0)
			(layer "F.Fab")
			(hide yes)
			(effects
				(font
					(size 1 1)
					(thickness 0.15)
				)
			)
		)
		(sheetname "/Interfaces/")
		(sheetfile "interfaces.kicad_sch")
		(attr smd)
		(fp_rect
			(start -0.925 -0.47)
			(end 0.925 0.47)
			(stroke
				(width 0.05)
				(type default)
			)
			(fill no)
			(layer "F.CrtYd")
		)
		(fp_rect
			(start -0.5 -0.25)
			(end 0.5 0.25)
			(stroke
				(width 0.15)
				(type solid)
			)
			(fill no)
			(layer "F.Fab")
		)
		(pad "1" smd roundrect
			(at -0.48 0 180)
			(size 0.59 0.64)
			(layers "F.Cu" "F.Mask" "F.Paste")
			(roundrect_rratio 0.25)
			(net 401 "Net-(U19-CDBUS1)")
			(pintype "passive")
		)
		(pad "2" smd roundrect
			(at 0.48 0 180)
			(size 0.59 0.64)
			(layers "F.Cu" "F.Mask" "F.Paste")
			(roundrect_rratio 0.25)
			(net 626 "DBG_UART_TX")
			(pintype "passive")
		)
	)
	(footprint "antmicro-footprints:MP_Pad5.5mm_Drill2.9mm"
		(layer "F.Cu")
		(at 65.6 80.105)
		(descr "mounting hole")
		(property "Reference" "MP1"
			(at -3.58 -2.585 0)
			(layer "F.SilkS")
			(effects
				(font
					(size 0.7 0.7)
					(thickness 0.15)
				)
				(justify left bottom)
			)
		)
		(property "Value" "MP_Pad5.5mm_Drill2.9mm"
			(at 0 3.7 0)
			(layer "F.Fab")
			(effects
				(font
					(size 0.7 0.7)
					(thickness 0.15)
				)
				(justify left bottom)
			)
		)
		(property "Description" "PCB mounting point"
			(at 0 0 0)
			(layer "F.Fab")
			(hide yes)
			(effects
				(font
					(size 1.27 1.27)
					(thickness 0.15)
				)
			)
		)
		(property "Author" "Antmicro"
			(at 0 0 0)
			(layer "F.Fab")
			(hide yes)
			(effects
				(font
					(size 1 1)
					(thickness 0.15)
				)
			)
		)
		(property "License" "Apache-2.0"
			(at 0 0 0)
			(layer "F.Fab")
			(hide yes)
			(effects
				(font
					(size 1 1)
					(thickness 0.15)
				)
			)
		)
		(sheetname "/")
		(sheetfile "artix-dc-scm.kicad_sch")
		(attr exclude_from_pos_files exclude_from_bom)
		(fp_circle
			(center 0 0)
			(end 3 0)
			(stroke
				(width 0.05)
				(type default)
			)
			(fill no)
			(layer "F.CrtYd")
		)
		(pad "1" thru_hole circle
			(at 0 0)
			(size 5.5 5.5)
			(drill 2.9)
			(layers "*.Cu" "*.Mask")
			(remove_unused_layers no)
			(net 690 "unconnected-(MP1-Pad1)")
			(pintype "passive+no_connect")
			(solder_paste_margin_ratio -1)
		)
	)
	(footprint "antmicro-footprints:MP_Pad5.5mm_Drill2.9mm"
		(layer "F.Cu")
		(at 144.6 80.105)
		(descr "mounting hole")
		(property "Reference" "MP2"
			(at 0 -2.9 0)
			(layer "F.SilkS")
			(effects
				(font
					(size 0.7 0.7)
					(thickness 0.15)
				)
				(justify left bottom)
			)
		)
		(property "Value" "MP_Pad5.5mm_Drill2.9mm"
			(at 0 3.7 0)
			(layer "F.Fab")
			(effects
				(font
					(size 0.7 0.7)
					(thickness 0.15)
				)
				(justify left bottom)
			)
		)
		(property "Description" "PCB mounting point"
			(at 0 0 0)
			(layer "F.Fab")
			(hide yes)
			(effects
				(font
					(size 1.27 1.27)
					(thickness 0.15)
				)
			)
		)
		(property "Author" "Antmicro"
			(at 0 0 0)
			(layer "F.Fab")
			(hide yes)
			(effects
				(font
					(size 1 1)
					(thickness 0.15)
				)
			)
		)
		(property "License" "Apache-2.0"
			(at 0 0 0)
			(layer "F.Fab")
			(hide yes)
			(effects
				(font
					(size 1 1)
					(thickness 0.15)
				)
			)
		)
		(sheetname "/")
		(sheetfile "artix-dc-scm.kicad_sch")
		(attr exclude_from_pos_files exclude_from_bom)
		(fp_circle
			(center 0 0)
			(end 3 0)
			(stroke
				(width 0.05)
				(type default)
			)
			(fill no)
			(layer "F.CrtYd")
		)
		(pad "1" thru_hole circle
			(at 0 0)
			(size 5.5 5.5)
			(drill 2.9)
			(layers "*.Cu" "*.Mask")
			(remove_unused_layers no)
			(net 691 "unconnected-(MP2-Pad1)")
			(pintype "passive+no_connect")
			(solder_paste_margin_ratio -1)
		)
	)
	(footprint "antmicro-footprints:R_0402_1005Metric"
		(layer "F.Cu")
		(at 130.875 103.775 180)
		(descr "Resistor SMD 0402")
		(tags "resistor SMD 0402")
		(property "Reference" "R195"
			(at 0.785 -0.425 0)
			(layer "F.SilkS")
			(effects
				(font
					(size 0.7 0.7)
					(thickness 0.15)
				)
				(justify right bottom)
			)
		)
		(property "Value" "R_22R_0402"
			(at 0 1.4 0)
			(layer "F.Fab")
			(effects
				(font
					(size 0.7 0.7)
					(thickness 0.15)
				)
				(justify right bottom)
			)
		)
		(property "Datasheet" "https://www.bourns.com/docs/product-datasheets/cr.pdf"
			(at 0 0 180)
			(layer "F.Fab")
			(hide yes)
			(effects
				(font
					(size 1.27 1.27)
					(thickness 0.15)
				)
			)
		)
		(property "Description" "SMD Chip Resistor, 22 ohm, ± 1%, 62.5 mW, 0402 [1005 Metric], Thick Film, General Purpose"
			(at 0 0 180)
			(layer "F.Fab")
			(hide yes)
			(effects
				(font
					(size 1.27 1.27)
					(thickness 0.15)
				)
			)
		)
		(property "Author" "Antmicro"
			(at 261.75 207.55 0)
			(layer "F.Fab")
			(hide yes)
			(effects
				(font
					(size 1 1)
					(thickness 0.15)
				)
			)
		)
		(property "License" "Apache-2.0"
			(at 261.75 207.55 0)
			(layer "F.Fab")
			(hide yes)
			(effects
				(font
					(size 1 1)
					(thickness 0.15)
				)
			)
		)
		(property "MPN" "CR0402-FX-22R0GLF"
			(at 261.75 207.55 0)
			(layer "F.Fab")
			(hide yes)
			(effects
				(font
					(size 1 1)
					(thickness 0.15)
				)
			)
		)
		(property "Manufacturer" "Bourns"
			(at 261.75 207.55 0)
			(layer "F.Fab")
			(hide yes)
			(effects
				(font
					(size 1 1)
					(thickness 0.15)
				)
			)
		)
		(property "Tolerance" "1%"
			(at 261.75 207.55 0)
			(layer "F.Fab")
			(hide yes)
			(effects
				(font
					(size 1 1)
					(thickness 0.15)
				)
			)
		)
		(property "Val" "22R"
			(at 261.75 207.55 0)
			(layer "F.Fab")
			(hide yes)
			(effects
				(font
					(size 1 1)
					(thickness 0.15)
				)
			)
		)
		(sheetname "/Interfaces/")
		(sheetfile "interfaces.kicad_sch")
		(attr smd)
		(fp_rect
			(start -0.925 -0.47)
			(end 0.925 0.47)
			(stroke
				(width 0.05)
				(type default)
			)
			(fill no)
			(layer "F.CrtYd")
		)
		(fp_rect
			(start -0.5 -0.25)
			(end 0.5 0.25)
			(stroke
				(width 0.15)
				(type solid)
			)
			(fill no)
			(layer "F.Fab")
		)
		(pad "1" smd roundrect
			(at -0.48 0 180)
			(size 0.59 0.64)
			(layers "F.Cu" "F.Mask" "F.Paste")
			(roundrect_rratio 0.25)
			(net 400 "Net-(U19-CDBUS0)")
			(pintype "passive")
		)
		(pad "2" smd roundrect
			(at 0.48 0 180)
			(size 0.59 0.64)
			(layers "F.Cu" "F.Mask" "F.Paste")
			(roundrect_rratio 0.25)
			(net 624 "DBG_UART_RX")
			(pintype "passive")
		)
	)
	(footprint "antmicro-footprints:Spacer_Drill3.7mm_H2.5mm_9774025151R"
		(locked yes)
		(layer "F.Cu")
		(at 125.97 81.38)
		(descr "Spacer M=3 h=2.5mm fi=5.1mm")
		(property "Reference" "H1"
			(at 0 -3.2 0)
			(layer "F.SilkS")
			(effects
				(font
					(size 0.7 0.7)
					(thickness 0.15)
				)
				(justify left bottom)
			)
		)
		(property "Value" "Spacer_Drill3.7mm_H2.5mm_9774025151R"
			(at 0 4 0)
			(layer "F.Fab")
			(effects
				(font
					(size 0.7 0.7)
					(thickness 0.15)
				)
				(justify left bottom)
			)
		)
		(property "Datasheet" "https://www.we-online.com/components/products/datasheet/9774025151R.pdf"
			(at 0 0 0)
			(layer "F.Fab")
			(hide yes)
			(effects
				(font
					(size 1.27 1.27)
					(thickness 0.15)
				)
			)
		)
		(property "Description" "Spacer, SMT, Non Stop, Steel, Swage Round, 5.1 mm x 2.5 mm, M2.5 Thread, WA-SMSI Series"
			(at 0 0 0)
			(layer "F.Fab")
			(hide yes)
			(effects
				(font
					(size 1.27 1.27)
					(thickness 0.15)
				)
			)
		)
		(property "Author" "Antmicro"
			(at 0 0 0)
			(layer "F.Fab")
			(hide yes)
			(effects
				(font
					(size 1 1)
					(thickness 0.15)
				)
			)
		)
		(property "License" "Apache-2.0"
			(at 0 0 0)
			(layer "F.Fab")
			(hide yes)
			(effects
				(font
					(size 1 1)
					(thickness 0.15)
				)
			)
		)
		(property "MPN" "9774025151R"
			(at 0 0 0)
			(layer "F.Fab")
			(hide yes)
			(effects
				(font
					(size 1 1)
					(thickness 0.15)
				)
			)
		)
		(property "Manufacturer" "Würth Elektronik"
			(at 0 0 0)
			(layer "F.Fab")
			(hide yes)
			(effects
				(font
					(size 1 1)
					(thickness 0.15)
				)
			)
		)
		(sheetname "/PCIe-connector/")
		(sheetfile "pcie-conn.kicad_sch")
		(solder_paste_margin_ratio -1)
		(attr smd)
		(fp_circle
			(center 0 0)
			(end 3.05 0)
			(stroke
				(width 0.05)
				(type solid)
			)
			(fill no)
			(layer "F.CrtYd")
		)
		(fp_circle
			(center 0 0)
			(end 2.6 0)
			(stroke
				(width 0.15)
				(type solid)
			)
			(fill no)
			(layer "F.Fab")
		)
		(pad "" smd custom
			(at -1.7 -1.7)
			(size 0.62 0.62)
			(layers "F.Paste")
			(thermal_bridge_angle 90)
			(options
				(clearance outline)
				(anchor circle)
			)
			(primitives
				(gr_arc
					(start -0.250195 1.279127)
					(mid 0.285453 0.294389)
					(end 1.266786 -0.24747)
					(width 0.2)
				)
				(gr_arc
					(start -0.34334 1.279127)
					(mid 0.218448 0.232561)
					(end 1.259603 -0.339191)
					(width 0.2)
				)
				(gr_arc
					(start -0.436309 1.279127)
					(mid 0.152481 0.169693)
					(end 1.255279 -0.431435)
					(width 0.2)
				)
				(gr_arc
					(start -0.529126 1.279127)
					(mid 0.087542 0.105784)
					(end 1.253811 -0.524161)
					(width 0.2)
				)
				(gr_arc
					(start -0.621807 1.279127)
					(mid 0.0309 0.033527)
					(end 1.275473 -0.621136)
					(width 0.2)
				)
				(gr_arc
					(start -0.71437 1.279127)
					(mid -0.037758 -0.026651)
					(end 1.263664 -0.711602)
					(width 0.2)
				)
				(gr_arc
					(start -0.806826 1.279127)
					(mid -0.105837 -0.087395)
					(end 1.253435 -0.802342)
					(width 0.2)
				)
				(gr_arc
					(start -0.899187 1.279127)
					(mid -0.165236 -0.156885)
					(end 1.267475 -0.897258)
					(width 0.2)
				)
				(gr_arc
					(start -0.991463 1.279127)
					(mid -0.228522 -0.222449)
					(end 1.270645 -0.990112)
					(width 0.2)
				)
				(gr_arc
					(start -1.083663 1.279127)
					(mid -0.294507 -0.285313)
					(end 1.266278 -1.081674)
					(width 0.2)
				)
				(gr_line
					(start 1.279127 -0.250195)
					(end 1.279127 -1.083663)
					(width 0.2)
				)
				(gr_line
					(start -0.250195 1.279127)
					(end -1.083663 1.279127)
					(width 0.2)
				)
			)
		)
		(pad "" smd custom
			(at -1.7 1.7 90)
			(size 0.62 0.62)
			(layers "F.Paste")
			(thermal_bridge_angle 90)
			(options
				(clearance outline)
				(anchor circle)
			)
			(primitives
				(gr_arc
					(start -0.250195 1.279127)
					(mid 0.285453 0.294389)
					(end 1.266786 -0.24747)
					(width 0.2)
				)
				(gr_arc
					(start -0.34334 1.279127)
					(mid 0.218448 0.232561)
					(end 1.259603 -0.339191)
					(width 0.2)
				)
				(gr_arc
					(start -0.436309 1.279127)
					(mid 0.152481 0.169693)
					(end 1.255279 -0.431435)
					(width 0.2)
				)
				(gr_arc
					(start -0.529126 1.279127)
					(mid 0.087542 0.105784)
					(end 1.253811 -0.524161)
					(width 0.2)
				)
				(gr_arc
					(start -0.621807 1.279127)
					(mid 0.0309 0.033527)
					(end 1.275473 -0.621136)
					(width 0.2)
				)
				(gr_arc
					(start -0.71437 1.279127)
					(mid -0.037758 -0.026651)
					(end 1.263664 -0.711602)
					(width 0.2)
				)
				(gr_arc
					(start -0.806826 1.279127)
					(mid -0.105837 -0.087395)
					(end 1.253435 -0.802342)
					(width 0.2)
				)
				(gr_arc
					(start -0.899187 1.279127)
					(mid -0.165236 -0.156885)
					(end 1.267475 -0.897258)
					(width 0.2)
				)
				(gr_arc
					(start -0.991463 1.279127)
					(mid -0.228522 -0.222449)
					(end 1.270645 -0.990112)
					(width 0.2)
				)
				(gr_arc
					(start -1.083663 1.279127)
					(mid -0.294507 -0.285313)
					(end 1.266278 -1.081674)
					(width 0.2)
				)
				(gr_line
					(start 1.279127 -0.250195)
					(end 1.279127 -1.083663)
					(width 0.2)
				)
				(gr_line
					(start -0.250195 1.279127)
					(end -1.083663 1.279127)
					(width 0.2)
				)
			)
		)
		(pad "" smd custom
			(at 1.7 -1.7 270)
			(size 0.62 0.62)
			(layers "F.Paste")
			(thermal_bridge_angle 90)
			(options
				(clearance outline)
				(anchor circle)
			)
			(primitives
				(gr_arc
					(start -0.250195 1.279127)
					(mid 0.285453 0.294389)
					(end 1.266786 -0.24747)
					(width 0.2)
				)
				(gr_arc
					(start -0.34334 1.279127)
					(mid 0.218448 0.232561)
					(end 1.259603 -0.339191)
					(width 0.2)
				)
				(gr_arc
					(start -0.436309 1.279127)
					(mid 0.152481 0.169693)
					(end 1.255279 -0.431435)
					(width 0.2)
				)
				(gr_arc
					(start -0.529126 1.279127)
					(mid 0.087542 0.105784)
					(end 1.253811 -0.524161)
					(width 0.2)
				)
				(gr_arc
					(start -0.621807 1.279127)
					(mid 0.0309 0.033527)
					(end 1.275473 -0.621136)
					(width 0.2)
				)
				(gr_arc
					(start -0.71437 1.279127)
					(mid -0.037758 -0.026651)
					(end 1.263664 -0.711602)
					(width 0.2)
				)
				(gr_arc
					(start -0.806826 1.279127)
					(mid -0.105837 -0.087395)
					(end 1.253435 -0.802342)
					(width 0.2)
				)
				(gr_arc
					(start -0.899187 1.279127)
					(mid -0.165236 -0.156885)
					(end 1.267475 -0.897258)
					(width 0.2)
				)
				(gr_arc
					(start -0.991463 1.279127)
					(mid -0.228522 -0.222449)
					(end 1.270645 -0.990112)
					(width 0.2)
				)
				(gr_arc
					(start -1.083663 1.279127)
					(mid -0.294507 -0.285313)
					(end 1.266278 -1.081674)
					(width 0.2)
				)
				(gr_line
					(start 1.279127 -0.250195)
					(end 1.279127 -1.083663)
					(width 0.2)
				)
				(gr_line
					(start -0.250195 1.279127)
					(end -1.083663 1.279127)
					(width 0.2)
				)
			)
		)
		(pad "" smd custom
			(at 1.7 1.7 180)
			(size 0.62 0.62)
			(layers "F.Paste")
			(thermal_bridge_angle 90)
			(options
				(clearance outline)
				(anchor circle)
			)
			(primitives
				(gr_arc
					(start -0.250195 1.279127)
					(mid 0.285453 0.294389)
					(end 1.266786 -0.24747)
					(width 0.2)
				)
				(gr_arc
					(start -0.34334 1.279127)
					(mid 0.218448 0.232561)
					(end 1.259603 -0.339191)
					(width 0.2)
				)
				(gr_arc
					(start -0.436309 1.279127)
					(mid 0.152481 0.169693)
					(end 1.255279 -0.431435)
					(width 0.2)
				)
				(gr_arc
					(start -0.529126 1.279127)
					(mid 0.087542 0.105784)
					(end 1.253811 -0.524161)
					(width 0.2)
				)
				(gr_arc
					(start -0.621807 1.279127)
					(mid 0.0309 0.033527)
					(end 1.275473 -0.621136)
					(width 0.2)
				)
				(gr_arc
					(start -0.71437 1.279127)
					(mid -0.037758 -0.026651)
					(end 1.263664 -0.711602)
					(width 0.2)
				)
				(gr_arc
					(start -0.806826 1.279127)
					(mid -0.105837 -0.087395)
					(end 1.253435 -0.802342)
					(width 0.2)
				)
				(gr_arc
					(start -0.899187 1.279127)
					(mid -0.165236 -0.156885)
					(end 1.267475 -0.897258)
					(width 0.2)
				)
				(gr_arc
					(start -0.991463 1.279127)
					(mid -0.228522 -0.222449)
					(end 1.270645 -0.990112)
					(width 0.2)
				)
				(gr_arc
					(start -1.083663 1.279127)
					(mid -0.294507 -0.285313)
					(end 1.266278 -1.081674)
					(width 0.2)
				)
				(gr_line
					(start 1.279127 -0.250195)
					(end 1.279127 -1.083663)
					(width 0.2)
				)
				(gr_line
					(start -0.250195 1.279127)
					(end -1.083663 1.279127)
					(width 0.2)
				)
			)
		)
		(pad "1" thru_hole circle
			(at 0 0)
			(size 6 6)
			(drill 3.7)
			(layers "*.Cu" "*.Mask")
			(remove_unused_layers no)
			(net 692 "unconnected-(H1-Pad1)")
			(pintype "passive+no_connect")
		)
	)
	(footprint "antmicro-footprints:Spacer_Drill3.7mm_H4mm_9774040151R"
		(layer "F.Cu")
		(at 73.82 112.4)
		(descr "Spacer M=3 h=4mm fi=5.1mm")
		(property "Reference" "H2"
			(at 0 -3.2 0)
			(layer "F.SilkS")
			(effects
				(font
					(size 0.7 0.7)
					(thickness 0.15)
				)
				(justify left bottom)
			)
		)
		(property "Value" "Spacer_Drill3.7mm_H4mm_9774040151R"
			(at 0 4 0)
			(layer "F.Fab")
			(effects
				(font
					(size 0.7 0.7)
					(thickness 0.15)
				)
				(justify left bottom)
			)
		)
		(property "Datasheet" "https://www.we-online.com/components/products/datasheet/9774040151R.pdf"
			(at 0 0 0)
			(layer "F.Fab")
			(hide yes)
			(effects
				(font
					(size 1.27 1.27)
					(thickness 0.15)
				)
			)
		)
		(property "Description" "Round Standoff Threaded M2.5x0.45 Steel 0.157\" (4.00mm)"
			(at 0 0 0)
			(layer "F.Fab")
			(hide yes)
			(effects
				(font
					(size 1.27 1.27)
					(thickness 0.15)
				)
			)
		)
		(property "Author" "Antmicro"
			(at 0 0 0)
			(layer "F.Fab")
			(hide yes)
			(effects
				(font
					(size 1 1)
					(thickness 0.15)
				)
			)
		)
		(property "License" "Apache-2.0"
			(at 0 0 0)
			(layer "F.Fab")
			(hide yes)
			(effects
				(font
					(size 1 1)
					(thickness 0.15)
				)
			)
		)
		(property "MPN" "9774040151R"
			(at 0 0 0)
			(layer "F.Fab")
			(hide yes)
			(effects
				(font
					(size 1 1)
					(thickness 0.15)
				)
			)
		)
		(property "Manufacturer" "Würth Elektronik"
			(at 0 0 0)
			(layer "F.Fab")
			(hide yes)
			(effects
				(font
					(size 1 1)
					(thickness 0.15)
				)
			)
		)
		(sheetname "/RoT/")
		(sheetfile "rot.kicad_sch")
		(solder_paste_margin_ratio -1)
		(attr smd)
		(fp_circle
			(center 0 0)
			(end 3.05 0)
			(stroke
				(width 0.05)
				(type solid)
			)
			(fill no)
			(layer "F.CrtYd")
		)
		(fp_circle
			(center 0 0)
			(end 2.6 0)
			(stroke
				(width 0.15)
				(type solid)
			)
			(fill no)
			(layer "F.Fab")
		)
		(pad "" smd custom
			(at -1.7 -1.7)
			(size 0.62 0.62)
			(layers "F.Paste")
			(thermal_bridge_angle 90)
			(options
				(clearance outline)
				(anchor circle)
			)
			(primitives
				(gr_arc
					(start -0.250195 1.279127)
					(mid 0.285453 0.294389)
					(end 1.266786 -0.24747)
					(width 0.2)
				)
				(gr_arc
					(start -0.34334 1.279127)
					(mid 0.218448 0.232561)
					(end 1.259603 -0.339191)
					(width 0.2)
				)
				(gr_arc
					(start -0.436309 1.279127)
					(mid 0.152481 0.169693)
					(end 1.255279 -0.431435)
					(width 0.2)
				)
				(gr_arc
					(start -0.529126 1.279127)
					(mid 0.087542 0.105784)
					(end 1.253811 -0.524161)
					(width 0.2)
				)
				(gr_arc
					(start -0.621807 1.279127)
					(mid 0.0309 0.033527)
					(end 1.275473 -0.621136)
					(width 0.2)
				)
				(gr_arc
					(start -0.71437 1.279127)
					(mid -0.037758 -0.026651)
					(end 1.263664 -0.711602)
					(width 0.2)
				)
				(gr_arc
					(start -0.806826 1.279127)
					(mid -0.105837 -0.087395)
					(end 1.253435 -0.802342)
					(width 0.2)
				)
				(gr_arc
					(start -0.899187 1.279127)
					(mid -0.165236 -0.156885)
					(end 1.267475 -0.897258)
					(width 0.2)
				)
				(gr_arc
					(start -0.991463 1.279127)
					(mid -0.228522 -0.222449)
					(end 1.270645 -0.990112)
					(width 0.2)
				)
				(gr_arc
					(start -1.083663 1.279127)
					(mid -0.294507 -0.285313)
					(end 1.266278 -1.081674)
					(width 0.2)
				)
				(gr_line
					(start 1.279127 -0.250195)
					(end 1.279127 -1.083663)
					(width 0.2)
				)
				(gr_line
					(start -0.250195 1.279127)
					(end -1.083663 1.279127)
					(width 0.2)
				)
			)
		)
		(pad "" smd custom
			(at -1.7 1.7 90)
			(size 0.62 0.62)
			(layers "F.Paste")
			(thermal_bridge_angle 90)
			(options
				(clearance outline)
				(anchor circle)
			)
			(primitives
				(gr_arc
					(start -0.250195 1.279127)
					(mid 0.285453 0.294389)
					(end 1.266786 -0.24747)
					(width 0.2)
				)
				(gr_arc
					(start -0.34334 1.279127)
					(mid 0.218448 0.232561)
					(end 1.259603 -0.339191)
					(width 0.2)
				)
				(gr_arc
					(start -0.436309 1.279127)
					(mid 0.152481 0.169693)
					(end 1.255279 -0.431435)
					(width 0.2)
				)
				(gr_arc
					(start -0.529126 1.279127)
					(mid 0.087542 0.105784)
					(end 1.253811 -0.524161)
					(width 0.2)
				)
				(gr_arc
					(start -0.621807 1.279127)
					(mid 0.0309 0.033527)
					(end 1.275473 -0.621136)
					(width 0.2)
				)
				(gr_arc
					(start -0.71437 1.279127)
					(mid -0.037758 -0.026651)
					(end 1.263664 -0.711602)
					(width 0.2)
				)
				(gr_arc
					(start -0.806826 1.279127)
					(mid -0.105837 -0.087395)
					(end 1.253435 -0.802342)
					(width 0.2)
				)
				(gr_arc
					(start -0.899187 1.279127)
					(mid -0.165236 -0.156885)
					(end 1.267475 -0.897258)
					(width 0.2)
				)
				(gr_arc
					(start -0.991463 1.279127)
					(mid -0.228522 -0.222449)
					(end 1.270645 -0.990112)
					(width 0.2)
				)
				(gr_arc
					(start -1.083663 1.279127)
					(mid -0.294507 -0.285313)
					(end 1.266278 -1.081674)
					(width 0.2)
				)
				(gr_line
					(start 1.279127 -0.250195)
					(end 1.279127 -1.083663)
					(width 0.2)
				)
				(gr_line
					(start -0.250195 1.279127)
					(end -1.083663 1.279127)
					(width 0.2)
				)
			)
		)
		(pad "" smd custom
			(at 1.7 -1.7 270)
			(size 0.62 0.62)
			(layers "F.Paste")
			(thermal_bridge_angle 90)
			(options
				(clearance outline)
				(anchor circle)
			)
			(primitives
				(gr_arc
					(start -0.250195 1.279127)
					(mid 0.285453 0.294389)
					(end 1.266786 -0.24747)
					(width 0.2)
				)
				(gr_arc
					(start -0.34334 1.279127)
					(mid 0.218448 0.232561)
					(end 1.259603 -0.339191)
					(width 0.2)
				)
				(gr_arc
					(start -0.436309 1.279127)
					(mid 0.152481 0.169693)
					(end 1.255279 -0.431435)
					(width 0.2)
				)
				(gr_arc
					(start -0.529126 1.279127)
					(mid 0.087542 0.105784)
					(end 1.253811 -0.524161)
					(width 0.2)
				)
				(gr_arc
					(start -0.621807 1.279127)
					(mid 0.0309 0.033527)
					(end 1.275473 -0.621136)
					(width 0.2)
				)
				(gr_arc
					(start -0.71437 1.279127)
					(mid -0.037758 -0.026651)
					(end 1.263664 -0.711602)
					(width 0.2)
				)
				(gr_arc
					(start -0.806826 1.279127)
					(mid -0.105837 -0.087395)
					(end 1.253435 -0.802342)
					(width 0.2)
				)
				(gr_arc
					(start -0.899187 1.279127)
					(mid -0.165236 -0.156885)
					(end 1.267475 -0.897258)
					(width 0.2)
				)
				(gr_arc
					(start -0.991463 1.279127)
					(mid -0.228522 -0.222449)
					(end 1.270645 -0.990112)
					(width 0.2)
				)
				(gr_arc
					(start -1.083663 1.279127)
					(mid -0.294507 -0.285313)
					(end 1.266278 -1.081674)
					(width 0.2)
				)
				(gr_line
					(start 1.279127 -0.250195)
					(end 1.279127 -1.083663)
					(width 0.2)
				)
				(gr_line
					(start -0.250195 1.279127)
					(end -1.083663 1.279127)
					(width 0.2)
				)
			)
		)
		(pad "" smd custom
			(at 1.7 1.7 180)
			(size 0.62 0.62)
			(layers "F.Paste")
			(thermal_bridge_angle 90)
			(options
				(clearance outline)
				(anchor circle)
			)
			(primitives
				(gr_arc
					(start -0.250195 1.279127)
					(mid 0.285453 0.294389)
					(end 1.266786 -0.24747)
					(width 0.2)
				)
				(gr_arc
					(start -0.34334 1.279127)
					(mid 0.218448 0.232561)
					(end 1.259603 -0.339191)
					(width 0.2)
				)
				(gr_arc
					(start -0.436309 1.279127)
					(mid 0.152481 0.169693)
					(end 1.255279 -0.431435)
					(width 0.2)
				)
				(gr_arc
					(start -0.529126 1.279127)
					(mid 0.087542 0.105784)
					(end 1.253811 -0.524161)
					(width 0.2)
				)
				(gr_arc
					(start -0.621807 1.279127)
					(mid 0.0309 0.033527)
					(end 1.275473 -0.621136)
					(width 0.2)
				)
				(gr_arc
					(start -0.71437 1.279127)
					(mid -0.037758 -0.026651)
					(end 1.263664 -0.711602)
					(width 0.2)
				)
				(gr_arc
					(start -0.806826 1.279127)
					(mid -0.105837 -0.087395)
					(end 1.253435 -0.802342)
					(width 0.2)
				)
				(gr_arc
					(start -0.899187 1.279127)
					(mid -0.165236 -0.156885)
					(end 1.267475 -0.897258)
					(width 0.2)
				)
				(gr_arc
					(start -0.991463 1.279127)
					(mid -0.228522 -0.222449)
					(end 1.270645 -0.990112)
					(width 0.2)
				)
				(gr_arc
					(start -1.083663 1.279127)
					(mid -0.294507 -0.285313)
					(end 1.266278 -1.081674)
					(width 0.2)
				)
				(gr_line
					(start 1.279127 -0.250195)
					(end 1.279127 -1.083663)
					(width 0.2)
				)
				(gr_line
					(start -0.250195 1.279127)
					(end -1.083663 1.279127)
					(width 0.2)
				)
			)
		)
		(pad "1" thru_hole circle
			(at 0 0)
			(size 6 6)
			(drill 3.7)
			(layers "*.Cu" "*.Mask")
			(remove_unused_layers no)
			(net 693 "unconnected-(H2-Pad1)")
			(pintype "passive+no_connect")
		)
	)
	(footprint "antmicro-footprints:BGA-96-48_7.5x13.5mm_Layout9x16_P0.8mm"
		(layer "F.Cu")
		(at 98.175 147.175 90)
		(descr "Based on: https://www.alliancememory.com/wp-content/uploads/AllianceMemory_4G_DDR3L_AS4C256M16D3LC_March2020_Rev1.0.pdf")
		(property "Reference" "U7"
			(at -4 -7.3 90)
			(layer "F.SilkS")
			(effects
				(font
					(size 0.7 0.7)
					(thickness 0.15)
				)
				(justify left bottom)
			)
		)
		(property "Value" "AS4C256M16D3"
			(at -4 7.85 90)
			(layer "F.Fab")
			(effects
				(font
					(size 0.7 0.7)
					(thickness 0.15)
				)
				(justify left bottom)
			)
		)
		(property "Datasheet" "https://www.alliancememory.com/wp-content/uploads/AllianceMemory_4G_DDR3L_AS4C256M16D3LC_March2020_Rev1.0.pdf"
			(at 0 0 90)
			(layer "F.Fab")
			(effects
				(font
					(size 0.7 0.7)
					(thickness 0.15)
				)
				(justify left bottom)
			)
		)
		(property "Description" "SDRAM - DDR3 Memory IC 4Gbit Parallel 800 MHz 20 ns 96-FBGA (9x13)"
			(at 0 0 90)
			(layer "F.Fab")
			(effects
				(font
					(size 0.7 0.7)
					(thickness 0.15)
				)
				(justify left bottom)
			)
		)
		(property "Manufacturer" "Alliance Memory"
			(at 0 0 90)
			(unlocked yes)
			(layer "F.Fab")
			(hide yes)
			(effects
				(font
					(size 1 1)
					(thickness 0.15)
				)
			)
		)
		(property "MPN" "AS4C256M16D3LC-12BCN"
			(at 0 0 90)
			(unlocked yes)
			(layer "F.Fab")
			(hide yes)
			(effects
				(font
					(size 1 1)
					(thickness 0.15)
				)
			)
		)
		(property "Author" "Antmicro"
			(at 0 0 90)
			(unlocked yes)
			(layer "F.Fab")
			(hide yes)
			(effects
				(font
					(size 1 1)
					(thickness 0.15)
				)
			)
		)
		(property "License" "Apache-2.0"
			(at 0 0 90)
			(unlocked yes)
			(layer "F.Fab")
			(hide yes)
			(effects
				(font
					(size 1 1)
					(thickness 0.15)
				)
			)
		)
		(sheetname "/DDR3/")
		(sheetfile "ddr3.kicad_sch")
		(attr smd)
		(fp_line
			(start 3.763 -6.75)
			(end 3.763 6.75)
			(stroke
				(width 0.15)
				(type solid)
			)
			(layer "F.SilkS")
		)
		(fp_line
			(start -3.2 -6.75)
			(end 3.763 -6.75)
			(stroke
				(width 0.15)
				(type solid)
			)
			(layer "F.SilkS")
		)
		(fp_line
			(start -3.763 -6.25)
			(end -3.2 -6.75)
			(stroke
				(width 0.15)
				(type solid)
			)
			(layer "F.SilkS")
		)
		(fp_line
			(start 3.763 6.75)
			(end -3.763 6.75)
			(stroke
				(width 0.15)
				(type solid)
			)
			(layer "F.SilkS")
		)
		(fp_line
			(start -3.763 6.75)
			(end -3.763 -6.25)
			(stroke
				(width 0.15)
				(type solid)
			)
			(layer "F.SilkS")
		)
		(fp_circle
			(center -3.85 -6.75)
			(end -3.8 -6.75)
			(stroke
				(width 0.15)
				(type solid)
			)
			(fill yes)
			(layer "F.SilkS")
		)
		(fp_rect
			(start -4 -7)
			(end 4 7)
			(stroke
				(width 0.05)
				(type solid)
			)
			(fill no)
			(layer "F.CrtYd")
		)
		(fp_line
			(start -3.75 -3.225)
			(end -0.25 -6.75)
			(stroke
				(width 0.15)
				(type solid)
			)
			(layer "F.Fab")
		)
		(fp_rect
			(start -3.75 -6.75)
			(end 3.75 6.75)
			(stroke
				(width 0.15)
				(type solid)
			)
			(fill no)
			(layer "F.Fab")
		)
		(fp_text user "${REFERENCE}"
			(at -4 9.05 90)
			(layer "F.Fab")
			(effects
				(font
					(size 0.7 0.7)
					(thickness 0.15)
				)
				(justify left bottom)
			)
		)
		(fp_text user "Author: Antmicro"
			(at -4 10.25 90)
			(layer "F.Fab")
			(effects
				(font
					(size 0.7 0.7)
					(thickness 0.15)
				)
				(justify left bottom)
			)
		)
		(fp_text user "License: Apache-2.0"
			(at -4 11.45 90)
			(layer "F.Fab")
			(effects
				(font
					(size 0.7 0.7)
					(thickness 0.15)
				)
				(justify left bottom)
			)
		)
		(pad "A1" smd circle
			(at -3.2 -6 180)
			(size 0.41 0.41)
			(layers "F.Cu" "F.Mask" "F.Paste")
			(net 3 "VCC1V35")
			(pinfunction "VDDQ")
			(pintype "power_in")
			(solder_mask_margin 0.03)
		)
		(pad "A2" smd circle
			(at -2.4 -6 180)
			(size 0.41 0.41)
			(layers "F.Cu" "F.Mask" "F.Paste")
			(net 178 "DDR3_DQ13")
			(pinfunction "DQ13")
			(pintype "bidirectional")
			(solder_mask_margin 0.03)
		)
		(pad "A3" smd circle
			(at -1.6 -6 180)
			(size 0.41 0.41)
			(layers "F.Cu" "F.Mask" "F.Paste")
			(net 177 "DDR3_DQ15")
			(pinfunction "DQ15")
			(pintype "bidirectional")
			(solder_mask_margin 0.03)
		)
		(pad "A7" smd circle
			(at 1.6 -6 180)
			(size 0.41 0.41)
			(layers "F.Cu" "F.Mask" "F.Paste")
			(net 182 "DDR3_DQ12")
			(pinfunction "DQ12")
			(pintype "bidirectional")
			(solder_mask_margin 0.03)
		)
		(pad "A8" smd circle
			(at 2.4 -6 180)
			(size 0.41 0.41)
			(layers "F.Cu" "F.Mask" "F.Paste")
			(net 3 "VCC1V35")
			(pinfunction "VDDQ")
			(pintype "passive")
			(solder_mask_margin 0.03)
		)
		(pad "A9" smd circle
			(at 3.2 -6 180)
			(size 0.41 0.41)
			(layers "F.Cu" "F.Mask" "F.Paste")
			(net 1 "GND")
			(pinfunction "VSS")
			(pintype "power_in")
			(solder_mask_margin 0.03)
		)
		(pad "B1" smd circle
			(at -3.2 -5.2 180)
			(size 0.41 0.41)
			(layers "F.Cu" "F.Mask" "F.Paste")
			(net 1 "GND")
			(pinfunction "VSSQ")
			(pintype "power_in")
			(solder_mask_margin 0.03)
		)
		(pad "B2" smd circle
			(at -2.4 -5.2 180)
			(size 0.41 0.41)
			(layers "F.Cu" "F.Mask" "F.Paste")
			(net 3 "VCC1V35")
			(pinfunction "VDD")
			(pintype "power_in")
			(solder_mask_margin 0.03)
		)
		(pad "B3" smd circle
			(at -1.6 -5.2 180)
			(size 0.41 0.41)
			(layers "F.Cu" "F.Mask" "F.Paste")
			(net 1 "GND")
			(pinfunction "VSS")
			(pintype "passive")
			(solder_mask_margin 0.03)
		)
		(pad "B7" smd circle
			(at 1.6 -5.2 180)
			(size 0.41 0.41)
			(layers "F.Cu" "F.Mask" "F.Paste")
			(net 474 "DDR3_DQS1_N")
			(pinfunction "~{UDQS}")
			(pintype "bidirectional")
			(solder_mask_margin 0.03)
		)
		(pad "B8" smd circle
			(at 2.4 -5.2 180)
			(size 0.41 0.41)
			(layers "F.Cu" "F.Mask" "F.Paste")
			(net 179 "DDR3_DQ14")
			(pinfunction "DQ14")
			(pintype "bidirectional")
			(solder_mask_margin 0.03)
		)
		(pad "B9" smd circle
			(at 3.2 -5.2 180)
			(size 0.41 0.41)
			(layers "F.Cu" "F.Mask" "F.Paste")
			(net 1 "GND")
			(pinfunction "VSSQ")
			(pintype "passive")
			(solder_mask_margin 0.03)
		)
		(pad "C1" smd circle
			(at -3.2 -4.4 180)
			(size 0.41 0.41)
			(layers "F.Cu" "F.Mask" "F.Paste")
			(net 3 "VCC1V35")
			(pinfunction "VDDQ")
			(pintype "passive")
			(solder_mask_margin 0.03)
		)
		(pad "C2" smd circle
			(at -2.4 -4.4 180)
			(size 0.41 0.41)
			(layers "F.Cu" "F.Mask" "F.Paste")
			(net 184 "DDR3_DQ11")
			(pinfunction "DQ11")
			(pintype "bidirectional")
			(solder_mask_margin 0.03)
		)
		(pad "C3" smd circle
			(at -1.6 -4.4 180)
			(size 0.41 0.41)
			(layers "F.Cu" "F.Mask" "F.Paste")
			(net 180 "DDR3_DQ9")
			(pinfunction "DQ9")
			(pintype "bidirectional")
			(solder_mask_margin 0.03)
		)
		(pad "C7" smd circle
			(at 1.6 -4.4 180)
			(size 0.41 0.41)
			(layers "F.Cu" "F.Mask" "F.Paste")
			(net 475 "DDR3_DQS1_P")
			(pinfunction "UDQS")
			(pintype "bidirectional")
			(solder_mask_margin 0.03)
		)
		(pad "C8" smd circle
			(at 2.4 -4.4 180)
			(size 0.41 0.41)
			(layers "F.Cu" "F.Mask" "F.Paste")
			(net 183 "DDR3_DQ10")
			(pinfunction "DQ10")
			(pintype "bidirectional")
			(solder_mask_margin 0.03)
		)
		(pad "C9" smd circle
			(at 3.2 -4.4 180)
			(size 0.41 0.41)
			(layers "F.Cu" "F.Mask" "F.Paste")
			(net 3 "VCC1V35")
			(pinfunction "VDDQ")
			(pintype "passive")
			(solder_mask_margin 0.03)
		)
		(pad "D1" smd circle
			(at -3.2 -3.6 180)
			(size 0.41 0.41)
			(layers "F.Cu" "F.Mask" "F.Paste")
			(net 1 "GND")
			(pinfunction "VSSQ")
			(pintype "passive")
			(solder_mask_margin 0.03)
		)
		(pad "D2" smd circle
			(at -2.4 -3.6 180)
			(size 0.41 0.41)
			(layers "F.Cu" "F.Mask" "F.Paste")
			(net 3 "VCC1V35")
			(pinfunction "VDDQ")
			(pintype "passive")
			(solder_mask_margin 0.03)
		)
		(pad "D3" smd circle
			(at -1.6 -3.6 180)
			(size 0.41 0.41)
			(layers "F.Cu" "F.Mask" "F.Paste")
			(net 181 "DDR3_DM1")
			(pinfunction "UDM")
			(pintype "input")
			(solder_mask_margin 0.03)
		)
		(pad "D7" smd circle
			(at 1.6 -3.6 180)
			(size 0.41 0.41)
			(layers "F.Cu" "F.Mask" "F.Paste")
			(net 193 "DDR3_DQ8")
			(pinfunction "DQ8")
			(pintype "bidirectional")
			(solder_mask_margin 0.03)
		)
		(pad "D8" smd circle
			(at 2.4 -3.6 180)
			(size 0.41 0.41)
			(layers "F.Cu" "F.Mask" "F.Paste")
			(net 1 "GND")
			(pinfunction "VSSQ")
			(pintype "passive")
			(solder_mask_margin 0.03)
		)
		(pad "D9" smd circle
			(at 3.2 -3.6 180)
			(size 0.41 0.41)
			(layers "F.Cu" "F.Mask" "F.Paste")
			(net 3 "VCC1V35")
			(pinfunction "VDD")
			(pintype "passive")
			(solder_mask_margin 0.03)
		)
		(pad "E1" smd circle
			(at -3.2 -2.8 180)
			(size 0.41 0.41)
			(layers "F.Cu" "F.Mask" "F.Paste")
			(net 1 "GND")
			(pinfunction "VSS")
			(pintype "passive")
			(solder_mask_margin 0.03)
		)
		(pad "E2" smd circle
			(at -2.4 -2.8 180)
			(size 0.41 0.41)
			(layers "F.Cu" "F.Mask" "F.Paste")
			(net 1 "GND")
			(pinfunction "VSSQ")
			(pintype "passive")
			(solder_mask_margin 0.03)
		)
		(pad "E3" smd circle
			(at -1.6 -2.8 180)
			(size 0.41 0.41)
			(layers "F.Cu" "F.Mask" "F.Paste")
			(net 194 "DDR3_DQ0")
			(pinfunction "DQ0")
			(pintype "bidirectional")
			(solder_mask_margin 0.03)
		)
		(pad "E7" smd circle
			(at 1.6 -2.8 180)
			(size 0.41 0.41)
			(layers "F.Cu" "F.Mask" "F.Paste")
			(net 176 "DDR3_DM0")
			(pinfunction "LDM")
			(pintype "input")
			(solder_mask_margin 0.03)
		)
		(pad "E8" smd circle
			(at 2.4 -2.8 180)
			(size 0.41 0.41)
			(layers "F.Cu" "F.Mask" "F.Paste")
			(net 1 "GND")
			(pinfunction "VSSQ")
			(pintype "passive")
			(solder_mask_margin 0.03)
		)
		(pad "E9" smd circle
			(at 3.2 -2.8 180)
			(size 0.41 0.41)
			(layers "F.Cu" "F.Mask" "F.Paste")
			(net 3 "VCC1V35")
			(pinfunction "VDDQ")
			(pintype "passive")
			(solder_mask_margin 0.03)
		)
		(pad "F1" smd circle
			(at -3.2 -2 180)
			(size 0.41 0.41)
			(layers "F.Cu" "F.Mask" "F.Paste")
			(net 3 "VCC1V35")
			(pinfunction "VDDQ")
			(pintype "passive")
			(solder_mask_margin 0.03)
		)
		(pad "F2" smd circle
			(at -2.4 -2 180)
			(size 0.41 0.41)
			(layers "F.Cu" "F.Mask" "F.Paste")
			(net 187 "DDR3_DQ2")
			(pinfunction "DQ2")
			(pintype "bidirectional")
			(solder_mask_margin 0.03)
		)
		(pad "F3" smd circle
			(at -1.6 -2 180)
			(size 0.41 0.41)
			(layers "F.Cu" "F.Mask" "F.Paste")
			(net 477 "DDR3_DQS0_P")
			(pinfunction "LDQS")
			(pintype "bidirectional")
			(solder_mask_margin 0.03)
		)
		(pad "F7" smd circle
			(at 1.6 -2 180)
			(size 0.41 0.41)
			(layers "F.Cu" "F.Mask" "F.Paste")
			(net 188 "DDR3_DQ1")
			(pinfunction "DQ1")
			(pintype "bidirectional")
			(solder_mask_margin 0.03)
		)
		(pad "F8" smd circle
			(at 2.4 -2 180)
			(size 0.41 0.41)
			(layers "F.Cu" "F.Mask" "F.Paste")
			(net 190 "DDR3_DQ3")
			(pinfunction "DQ3")
			(pintype "bidirectional")
			(solder_mask_margin 0.03)
		)
		(pad "F9" smd circle
			(at 3.2 -2 180)
			(size 0.41 0.41)
			(layers "F.Cu" "F.Mask" "F.Paste")
			(net 1 "GND")
			(pinfunction "VSSQ")
			(pintype "passive")
			(solder_mask_margin 0.03)
		)
		(pad "G1" smd circle
			(at -3.2 -1.2 180)
			(size 0.41 0.41)
			(layers "F.Cu" "F.Mask" "F.Paste")
			(net 1 "GND")
			(pinfunction "VSSQ")
			(pintype "passive")
			(solder_mask_margin 0.03)
		)
		(pad "G2" smd circle
			(at -2.4 -1.2 180)
			(size 0.41 0.41)
			(layers "F.Cu" "F.Mask" "F.Paste")
			(net 192 "DDR3_DQ6")
			(pinfunction "DQ6")
			(pintype "bidirectional")
			(solder_mask_margin 0.03)
		)
		(pad "G3" smd circle
			(at -1.6 -1.2 180)
			(size 0.41 0.41)
			(layers "F.Cu" "F.Mask" "F.Paste")
			(net 476 "DDR3_DQS0_N")
			(pinfunction "~{LDQS}")
			(pintype "bidirectional")
			(solder_mask_margin 0.03)
		)
		(pad "G7" smd circle
			(at 1.6 -1.2 180)
			(size 0.41 0.41)
			(layers "F.Cu" "F.Mask" "F.Paste")
			(net 3 "VCC1V35")
			(pinfunction "VDD")
			(pintype "passive")
			(solder_mask_margin 0.03)
		)
		(pad "G8" smd circle
			(at 2.4 -1.2 180)
			(size 0.41 0.41)
			(layers "F.Cu" "F.Mask" "F.Paste")
			(net 1 "GND")
			(pinfunction "VSS")
			(pintype "passive")
			(solder_mask_margin 0.03)
		)
		(pad "G9" smd circle
			(at 3.2 -1.2 180)
			(size 0.41 0.41)
			(layers "F.Cu" "F.Mask" "F.Paste")
			(net 1 "GND")
			(pinfunction "VSSQ")
			(pintype "passive")
			(solder_mask_margin 0.03)
		)
		(pad "H1" smd circle
			(at -3.2 -0.4 180)
			(size 0.41 0.41)
			(layers "F.Cu" "F.Mask" "F.Paste")
			(net 211 "DDR3_VREF")
			(pinfunction "VREF_DQ")
			(pintype "power_in")
			(solder_mask_margin 0.03)
		)
		(pad "H2" smd circle
			(at -2.4 -0.4 180)
			(size 0.41 0.41)
			(layers "F.Cu" "F.Mask" "F.Paste")
			(net 3 "VCC1V35")
			(pinfunction "VDDQ")
			(pintype "passive")
			(solder_mask_margin 0.03)
		)
		(pad "H3" smd circle
			(at -1.6 -0.4 180)
			(size 0.41 0.41)
			(layers "F.Cu" "F.Mask" "F.Paste")
			(net 189 "DDR3_DQ4")
			(pinfunction "DQ4")
			(pintype "bidirectional")
			(solder_mask_margin 0.03)
		)
		(pad "H7" smd circle
			(at 1.6 -0.4 180)
			(size 0.41 0.41)
			(layers "F.Cu" "F.Mask" "F.Paste")
			(net 185 "DDR3_DQ7")
			(pinfunction "DQ7")
			(pintype "bidirectional")
			(solder_mask_margin 0.03)
		)
		(pad "H8" smd circle
			(at 2.4 -0.4 180)
			(size 0.41 0.41)
			(layers "F.Cu" "F.Mask" "F.Paste")
			(net 186 "DDR3_DQ5")
			(pinfunction "DQ5")
			(pintype "bidirectional")
			(solder_mask_margin 0.03)
		)
		(pad "H9" smd circle
			(at 3.2 -0.4 180)
			(size 0.41 0.41)
			(layers "F.Cu" "F.Mask" "F.Paste")
			(net 3 "VCC1V35")
			(pinfunction "VDDQ")
			(pintype "passive")
			(solder_mask_margin 0.03)
		)
		(pad "J1" smd circle
			(at -3.2 0.4 180)
			(size 0.41 0.41)
			(layers "F.Cu" "F.Mask" "F.Paste")
			(net 698 "unconnected-(U7-NC-PadJ1)")
			(pinfunction "NC")
			(pintype "no_connect")
			(solder_mask_margin 0.03)
		)
		(pad "J2" smd circle
			(at -2.4 0.4 180)
			(size 0.41 0.41)
			(layers "F.Cu" "F.Mask" "F.Paste")
			(net 1 "GND")
			(pinfunction "VSS")
			(pintype "passive")
			(solder_mask_margin 0.03)
		)
		(pad "J3" smd circle
			(at -1.6 0.4 180)
			(size 0.41 0.41)
			(layers "F.Cu" "F.Mask" "F.Paste")
			(net 162 "DDR3_RAS")
			(pinfunction "~{RAS}")
			(pintype "input")
			(solder_mask_margin 0.03)
		)
		(pad "J7" smd circle
			(at 1.6 0.4 180)
			(size 0.41 0.41)
			(layers "F.Cu" "F.Mask" "F.Paste")
			(net 479 "DDR3_CLK_P")
			(pinfunction "CK")
			(pintype "input")
			(solder_mask_margin 0.03)
		)
		(pad "J8" smd circle
			(at 2.4 0.4 180)
			(size 0.41 0.41)
			(layers "F.Cu" "F.Mask" "F.Paste")
			(net 1 "GND")
			(pinfunction "VSS")
			(pintype "passive")
			(solder_mask_margin 0.03)
		)
		(pad "J9" smd circle
			(at 3.2 0.4 180)
			(size 0.41 0.41)
			(layers "F.Cu" "F.Mask" "F.Paste")
			(net 700 "unconnected-(U7-NC-PadJ9)")
			(pinfunction "NC")
			(pintype "no_connect")
			(solder_mask_margin 0.03)
		)
		(pad "K1" smd circle
			(at -3.2 1.2 180)
			(size 0.41 0.41)
			(layers "F.Cu" "F.Mask" "F.Paste")
			(net 161 "DDR3_ODT")
			(pinfunction "ODT")
			(pintype "input")
			(solder_mask_margin 0.03)
		)
		(pad "K2" smd circle
			(at -2.4 1.2 180)
			(size 0.41 0.41)
			(layers "F.Cu" "F.Mask" "F.Paste")
			(net 3 "VCC1V35")
			(pinfunction "VDD")
			(pintype "passive")
			(solder_mask_margin 0.03)
		)
		(pad "K3" smd circle
			(at -1.6 1.2 180)
			(size 0.41 0.41)
			(layers "F.Cu" "F.Mask" "F.Paste")
			(net 166 "DDR3_CAS")
			(pinfunction "~{CAS}")
			(pintype "input")
			(solder_mask_margin 0.03)
		)
		(pad "K7" smd circle
			(at 1.6 1.2 180)
			(size 0.41 0.41)
			(layers "F.Cu" "F.Mask" "F.Paste")
			(net 478 "DDR3_CLK_N")
			(pinfunction "~{CK}")
			(pintype "input")
			(solder_mask_margin 0.03)
		)
		(pad "K8" smd circle
			(at 2.4 1.2 180)
			(size 0.41 0.41)
			(layers "F.Cu" "F.Mask" "F.Paste")
			(net 3 "VCC1V35")
			(pinfunction "VDD")
			(pintype "passive")
			(solder_mask_margin 0.03)
		)
		(pad "K9" smd circle
			(at 3.2 1.2 180)
			(size 0.41 0.41)
			(layers "F.Cu" "F.Mask" "F.Paste")
			(net 160 "DDR3_CKE")
			(pinfunction "CKE")
			(pintype "input")
			(solder_mask_margin 0.03)
		)
		(pad "L1" smd circle
			(at -3.2 2 180)
			(size 0.41 0.41)
			(layers "F.Cu" "F.Mask" "F.Paste")
			(net 699 "unconnected-(U7-NC-PadL1)")
			(pinfunction "NC")
			(pintype "no_connect")
			(solder_mask_margin 0.03)
		)
		(pad "L2" smd circle
			(at -2.4 2 180)
			(size 0.41 0.41)
			(layers "F.Cu" "F.Mask" "F.Paste")
			(net 163 "DDR3_CS")
			(pinfunction "~{CS}")
			(pintype "input")
			(solder_mask_margin 0.03)
		)
		(pad "L3" smd circle
			(at -1.6 2 180)
			(size 0.41 0.41)
			(layers "F.Cu" "F.Mask" "F.Paste")
			(net 153 "DDR3_WE")
			(pinfunction "~{WE}")
			(pintype "input")
			(solder_mask_margin 0.03)
		)
		(pad "L7" smd circle
			(at 1.6 2 180)
			(size 0.41 0.41)
			(layers "F.Cu" "F.Mask" "F.Paste")
			(net 154 "DDR3_A10")
			(pinfunction "A10/AP")
			(pintype "input")
			(solder_mask_margin 0.03)
		)
		(pad "L8" smd circle
			(at 2.4 2 180)
			(size 0.41 0.41)
			(layers "F.Cu" "F.Mask" "F.Paste")
			(net 337 "Net-(U7-ZQ)")
			(pinfunction "ZQ")
			(pintype "passive")
			(solder_mask_margin 0.03)
		)
		(pad "L9" smd circle
			(at 3.2 2 180)
			(size 0.41 0.41)
			(layers "F.Cu" "F.Mask" "F.Paste")
			(net 701 "unconnected-(U7-NC-PadL9)")
			(pinfunction "NC")
			(pintype "no_connect")
			(solder_mask_margin 0.03)
		)
		(pad "M1" smd circle
			(at -3.2 2.8 180)
			(size 0.41 0.41)
			(layers "F.Cu" "F.Mask" "F.Paste")
			(net 1 "GND")
			(pinfunction "VSS")
			(pintype "passive")
			(solder_mask_margin 0.03)
		)
		(pad "M2" smd circle
			(at -2.4 2.8 180)
			(size 0.41 0.41)
			(layers "F.Cu" "F.Mask" "F.Paste")
			(net 164 "DDR3_BA0")
			(pinfunction "BA0")
			(pintype "input")
			(solder_mask_margin 0.03)
		)
		(pad "M3" smd circle
			(at -1.6 2.8 180)
			(size 0.41 0.41)
			(layers "F.Cu" "F.Mask" "F.Paste")
			(net 152 "DDR3_BA2")
			(pinfunction "BA2")
			(pintype "input")
			(solder_mask_margin 0.03)
		)
		(pad "M7" smd circle
			(at 1.6 2.8 180)
			(size 0.41 0.41)
			(layers "F.Cu" "F.Mask" "F.Paste")
			(net 697 "unconnected-(U7-NC-PadM7)")
			(pinfunction "NC")
			(pintype "no_connect")
			(solder_mask_margin 0.03)
		)
		(pad "M8" smd circle
			(at 2.4 2.8 180)
			(size 0.41 0.41)
			(layers "F.Cu" "F.Mask" "F.Paste")
			(net 211 "DDR3_VREF")
			(pinfunction "VREF_CA")
			(pintype "power_in")
			(solder_mask_margin 0.03)
		)
		(pad "M9" smd circle
			(at 3.2 2.8 180)
			(size 0.41 0.41)
			(layers "F.Cu" "F.Mask" "F.Paste")
			(net 1 "GND")
			(pinfunction "VSS")
			(pintype "passive")
			(solder_mask_margin 0.03)
		)
		(pad "N1" smd circle
			(at -3.2 3.6 180)
			(size 0.41 0.41)
			(layers "F.Cu" "F.Mask" "F.Paste")
			(net 3 "VCC1V35")
			(pinfunction "VDD")
			(pintype "passive")
			(solder_mask_margin 0.03)
		)
		(pad "N2" smd circle
			(at -2.4 3.6 180)
			(size 0.41 0.41)
			(layers "F.Cu" "F.Mask" "F.Paste")
			(net 165 "DDR3_A3")
			(pinfunction "A3")
			(pintype "input")
			(solder_mask_margin 0.03)
		)
		(pad "N3" smd circle
			(at -1.6 3.6 180)
			(size 0.41 0.41)
			(layers "F.Cu" "F.Mask" "F.Paste")
			(net 158 "DDR3_A0")
			(pinfunction "A0")
			(pintype "input")
			(solder_mask_margin 0.03)
		)
		(pad "N7" smd circle
			(at 1.6 3.6 180)
			(size 0.41 0.41)
			(layers "F.Cu" "F.Mask" "F.Paste")
			(net 156 "DDR3_A12")
			(pinfunction "A12/~{BC}")
			(pintype "input")
			(solder_mask_margin 0.03)
		)
		(pad "N8" smd circle
			(at 2.4 3.6 180)
			(size 0.41 0.41)
			(layers "F.Cu" "F.Mask" "F.Paste")
			(net 155 "DDR3_BA1")
			(pinfunction "BA1")
			(pintype "input")
			(solder_mask_margin 0.03)
		)
		(pad "N9" smd circle
			(at 3.2 3.6 180)
			(size 0.41 0.41)
			(layers "F.Cu" "F.Mask" "F.Paste")
			(net 3 "VCC1V35")
			(pinfunction "VDD")
			(pintype "passive")
			(solder_mask_margin 0.03)
		)
		(pad "P1" smd circle
			(at -3.2 4.4 180)
			(size 0.41 0.41)
			(layers "F.Cu" "F.Mask" "F.Paste")
			(net 1 "GND")
			(pinfunction "VSS")
			(pintype "passive")
			(solder_mask_margin 0.03)
		)
		(pad "P2" smd circle
			(at -2.4 4.4 180)
			(size 0.41 0.41)
			(layers "F.Cu" "F.Mask" "F.Paste")
			(net 167 "DDR3_A5")
			(pinfunction "A5")
			(pintype "input")
			(solder_mask_margin 0.03)
		)
		(pad "P3" smd circle
			(at -1.6 4.4 180)
			(size 0.41 0.41)
			(layers "F.Cu" "F.Mask" "F.Paste")
			(net 147 "DDR3_A2")
			(pinfunction "A2")
			(pintype "input")
			(solder_mask_margin 0.03)
		)
		(pad "P7" smd circle
			(at 1.6 4.4 180)
			(size 0.41 0.41)
			(layers "F.Cu" "F.Mask" "F.Paste")
			(net 157 "DDR3_A1")
			(pinfunction "A1")
			(pintype "input")
			(solder_mask_margin 0.03)
		)
		(pad "P8" smd circle
			(at 2.4 4.4 180)
			(size 0.41 0.41)
			(layers "F.Cu" "F.Mask" "F.Paste")
			(net 159 "DDR3_A4")
			(pinfunction "A4")
			(pintype "input")
			(solder_mask_margin 0.03)
		)
		(pad "P9" smd circle
			(at 3.2 4.4 180)
			(size 0.41 0.41)
			(layers "F.Cu" "F.Mask" "F.Paste")
			(net 1 "GND")
			(pinfunction "VSS")
			(pintype "passive")
			(solder_mask_margin 0.03)
		)
		(pad "R1" smd circle
			(at -3.2 5.2 180)
			(size 0.41 0.41)
			(layers "F.Cu" "F.Mask" "F.Paste")
			(net 3 "VCC1V35")
			(pinfunction "VDD")
			(pintype "passive")
			(solder_mask_margin 0.03)
		)
		(pad "R2" smd circle
			(at -2.4 5.2 180)
			(size 0.41 0.41)
			(layers "F.Cu" "F.Mask" "F.Paste")
			(net 148 "DDR3_A7")
			(pinfunction "A7")
			(pintype "input")
			(solder_mask_margin 0.03)
		)
		(pad "R3" smd circle
			(at -1.6 5.2 180)
			(size 0.41 0.41)
			(layers "F.Cu" "F.Mask" "F.Paste")
			(net 149 "DDR3_A9")
			(pinfunction "A9")
			(pintype "input")
			(solder_mask_margin 0.03)
		)
		(pad "R7" smd circle
			(at 1.6 5.2 180)
			(size 0.41 0.41)
			(layers "F.Cu" "F.Mask" "F.Paste")
			(net 150 "DDR3_A11")
			(pinfunction "A11")
			(pintype "input")
			(solder_mask_margin 0.03)
		)
		(pad "R8" smd circle
			(at 2.4 5.2 180)
			(size 0.41 0.41)
			(layers "F.Cu" "F.Mask" "F.Paste")
			(net 146 "DDR3_A6")
			(pinfunction "A6")
			(pintype "input")
			(solder_mask_margin 0.03)
		)
		(pad "R9" smd circle
			(at 3.2 5.2 180)
			(size 0.41 0.41)
			(layers "F.Cu" "F.Mask" "F.Paste")
			(net 3 "VCC1V35")
			(pinfunction "VDD")
			(pintype "passive")
			(solder_mask_margin 0.03)
		)
		(pad "T1" smd circle
			(at -3.2 6 180)
			(size 0.41 0.41)
			(layers "F.Cu" "F.Mask" "F.Paste")
			(net 1 "GND")
			(pinfunction "VSS")
			(pintype "passive")
			(solder_mask_margin 0.03)
		)
		(pad "T2" smd circle
			(at -2.4 6 180)
			(size 0.41 0.41)
			(layers "F.Cu" "F.Mask" "F.Paste")
			(net 191 "DDR3_RESET")
			(pinfunction "~{RESET}")
			(pintype "input")
			(solder_mask_margin 0.03)
		)
		(pad "T3" smd circle
			(at -1.6 6 180)
			(size 0.41 0.41)
			(layers "F.Cu" "F.Mask" "F.Paste")
			(net 151 "DDR3_A13")
			(pinfunction "A13")
			(pintype "input")
			(solder_mask_margin 0.03)
		)
		(pad "T7" smd circle
			(at 1.6 6 180)
			(size 0.41 0.41)
			(layers "F.Cu" "F.Mask" "F.Paste")
			(net 144 "DDR3_A14")
			(pinfunction "A14")
			(pintype "input")
			(solder_mask_margin 0.03)
		)
		(pad "T8" smd circle
			(at 2.4 6 180)
			(size 0.41 0.41)
			(layers "F.Cu" "F.Mask" "F.Paste")
			(net 145 "DDR3_A8")
			(pinfunction "A8")
			(pintype "input")
			(solder_mask_margin 0.03)
		)
		(pad "T9" smd circle
			(at 3.2 6 180)
			(size 0.41 0.41)
			(layers "F.Cu" "F.Mask" "F.Paste")
			(net 1 "GND")
			(pinfunction "VSS")
			(pintype "passive")
			(solder_mask_margin 0.03)
		)
	)
	(footprint "antmicro-footprints:C_1210_3225Metric"
		(layer "B.Cu")
		(at 85 133.6 90)
		(descr "Capacitor SMD 1210")
		(tags "capacitor SMD 1210")
		(property "Reference" "C92"
			(at 2.1 -1.1 180)
			(layer "B.SilkS")
			(effects
				(font
					(size 0.7 0.7)
					(thickness 0.15)
				)
				(justify right bottom mirror)
			)
		)
		(property "Value" "C_47u_1210"
			(at 0 -2.749 90)
			(layer "B.Fab")
			(effects
				(font
					(size 0.7 0.7)
					(thickness 0.15)
				)
				(justify right bottom mirror)
			)
		)
		(property "Datasheet" "https://www.kemet.com/en/us/capacitors/product/C1210C476K8RACTU.html"
			(at 0 0 90)
			(layer "F.Fab")
			(hide yes)
			(effects
				(font
					(size 1.27 1.27)
					(thickness 0.15)
				)
			)
		)
		(property "Description" "SMD Multilayer Ceramic Capacitor, 47 µF, 10 V, 1210 [3225 Metric], ± 10%, X7R, C Series KEMET"
			(at 0 0 90)
			(layer "F.Fab")
			(hide yes)
			(effects
				(font
					(size 1.27 1.27)
					(thickness 0.15)
				)
			)
		)
		(property "Author" "Antmicro"
			(at 218.6 48.6 0)
			(layer "B.Fab")
			(hide yes)
			(effects
				(font
					(size 1 1)
					(thickness 0.15)
				)
				(justify mirror)
			)
		)
		(property "Dielectric" ""
			(at 218.6 48.6 0)
			(layer "B.Fab")
			(hide yes)
			(effects
				(font
					(size 1 1)
					(thickness 0.15)
				)
				(justify mirror)
			)
		)
		(property "License" "Apache-2.0"
			(at 218.6 48.6 0)
			(layer "B.Fab")
			(hide yes)
			(effects
				(font
					(size 1 1)
					(thickness 0.15)
				)
				(justify mirror)
			)
		)
		(property "MPN" "C1210C476K8RACTU"
			(at 218.6 48.6 0)
			(layer "B.Fab")
			(hide yes)
			(effects
				(font
					(size 1 1)
					(thickness 0.15)
				)
				(justify mirror)
			)
		)
		(property "Manufacturer" "KEMET"
			(at 218.6 48.6 0)
			(layer "B.Fab")
			(hide yes)
			(effects
				(font
					(size 1 1)
					(thickness 0.15)
				)
				(justify mirror)
			)
		)
		(property "Public" "False"
			(at 218.6 48.6 0)
			(layer "B.Fab")
			(hide yes)
			(effects
				(font
					(size 1 1)
					(thickness 0.15)
				)
				(justify mirror)
			)
		)
		(property "Val" "47u"
			(at 218.6 48.6 0)
			(layer "B.Fab")
			(hide yes)
			(effects
				(font
					(size 1 1)
					(thickness 0.15)
				)
				(justify mirror)
			)
		)
		(property "Voltage" ""
			(at 218.6 48.6 0)
			(layer "B.Fab")
			(hide yes)
			(effects
				(font
					(size 1 1)
					(thickness 0.15)
				)
				(justify mirror)
			)
		)
		(property "DNP" ""
			(at 0 0 90)
			(unlocked yes)
			(layer "B.Fab")
			(hide yes)
			(effects
				(font
					(size 1 1)
					(thickness 0.15)
				)
				(justify mirror)
			)
		)
		(sheetname "/FPGA banks 13-16/")
		(sheetfile "fpga-banks-13-16.kicad_sch")
		(attr smd)
		(fp_line
			(start -0.3 -1.39)
			(end 0.3 -1.39)
			(stroke
				(width 0.15)
				(type solid)
			)
			(layer "B.SilkS")
		)
		(fp_line
			(start -0.3 1.39)
			(end 0.3 1.39)
			(stroke
				(width 0.15)
				(type solid)
			)
			(layer "B.SilkS")
		)
		(fp_rect
			(start -2.1 1.75)
			(end 2.1 -1.75)
			(stroke
				(width 0.05)
				(type solid)
			)
			(fill no)
			(layer "B.CrtYd")
		)
		(fp_rect
			(start -1.6 1.25)
			(end 1.6 -1.25)
			(stroke
				(width 0.15)
				(type solid)
			)
			(fill no)
			(layer "B.Fab")
		)
		(pad "1" smd rect
			(at -1.145 0 90)
			(size 1.52 3.05)
			(layers "B.Cu" "B.Mask" "B.Paste")
			(net 1 "GND")
			(pintype "passive")
		)
		(pad "2" smd rect
			(at 1.145 0 90)
			(size 1.52 3.05)
			(layers "B.Cu" "B.Mask" "B.Paste")
			(net 2 "VCC3V3")
			(pintype "passive")
		)
	)
	(footprint "antmicro-footprints:C_1210_3225Metric"
		(layer "B.Cu")
		(at 112.8 98.5 180)
		(descr "Capacitor SMD 1210")
		(tags "capacitor SMD 1210")
		(property "Reference" "C95"
			(at -2.9 1.1 90)
			(layer "B.SilkS")
			(effects
				(font
					(size 0.7 0.7)
					(thickness 0.15)
				)
				(justify left bottom mirror)
			)
		)
		(property "Value" "C_47u_1210"
			(at 0 -2.749 0)
			(layer "B.Fab")
			(effects
				(font
					(size 0.7 0.7)
					(thickness 0.15)
				)
				(justify left bottom mirror)
			)
		)
		(property "Datasheet" "https://www.kemet.com/en/us/capacitors/product/C1210C476K8RACTU.html"
			(at 0 0 180)
			(layer "F.Fab")
			(hide yes)
			(effects
				(font
					(size 1.27 1.27)
					(thickness 0.15)
				)
			)
		)
		(property "Description" "SMD Multilayer Ceramic Capacitor, 47 µF, 10 V, 1210 [3225 Metric], ± 10%, X7R, C Series KEMET"
			(at 0 0 180)
			(layer "F.Fab")
			(hide yes)
			(effects
				(font
					(size 1.27 1.27)
					(thickness 0.15)
				)
			)
		)
		(property "Author" "Antmicro"
			(at 225.6 197 0)
			(layer "B.Fab")
			(hide yes)
			(effects
				(font
					(size 1 1)
					(thickness 0.15)
				)
				(justify mirror)
			)
		)
		(property "Dielectric" ""
			(at 225.6 197 0)
			(layer "B.Fab")
			(hide yes)
			(effects
				(font
					(size 1 1)
					(thickness 0.15)
				)
				(justify mirror)
			)
		)
		(property "License" "Apache-2.0"
			(at 225.6 197 0)
			(layer "B.Fab")
			(hide yes)
			(effects
				(font
					(size 1 1)
					(thickness 0.15)
				)
				(justify mirror)
			)
		)
		(property "MPN" "C1210C476K8RACTU"
			(at 225.6 197 0)
			(layer "B.Fab")
			(hide yes)
			(effects
				(font
					(size 1 1)
					(thickness 0.15)
				)
				(justify mirror)
			)
		)
		(property "Manufacturer" "KEMET"
			(at 225.6 197 0)
			(layer "B.Fab")
			(hide yes)
			(effects
				(font
					(size 1 1)
					(thickness 0.15)
				)
				(justify mirror)
			)
		)
		(property "Public" "False"
			(at 225.6 197 0)
			(layer "B.Fab")
			(hide yes)
			(effects
				(font
					(size 1 1)
					(thickness 0.15)
				)
				(justify mirror)
			)
		)
		(property "Val" "47u"
			(at 225.6 197 0)
			(layer "B.Fab")
			(hide yes)
			(effects
				(font
					(size 1 1)
					(thickness 0.15)
				)
				(justify mirror)
			)
		)
		(property "Voltage" ""
			(at 225.6 197 0)
			(layer "B.Fab")
			(hide yes)
			(effects
				(font
					(size 1 1)
					(thickness 0.15)
				)
				(justify mirror)
			)
		)
		(sheetname "/FPGA banks 13-16/")
		(sheetfile "fpga-banks-13-16.kicad_sch")
		(attr smd)
		(fp_line
			(start -0.3 1.39)
			(end 0.3 1.39)
			(stroke
				(width 0.15)
				(type solid)
			)
			(layer "B.SilkS")
		)
		(fp_line
			(start -0.3 -1.39)
			(end 0.3 -1.39)
			(stroke
				(width 0.15)
				(type solid)
			)
			(layer "B.SilkS")
		)
		(fp_rect
			(start -2.1 1.75)
			(end 2.1 -1.75)
			(stroke
				(width 0.05)
				(type solid)
			)
			(fill no)
			(layer "B.CrtYd")
		)
		(fp_rect
			(start -1.6 1.25)
			(end 1.6 -1.25)
			(stroke
				(width 0.15)
				(type solid)
			)
			(fill no)
			(layer "B.Fab")
		)
		(pad "1" smd rect
			(at -1.145 0 180)
			(size 1.52 3.05)
			(layers "B.Cu" "B.Mask" "B.Paste")
			(net 1 "GND")
			(pintype "passive")
		)
		(pad "2" smd rect
			(at 1.145 0 180)
			(size 1.52 3.05)
			(layers "B.Cu" "B.Mask" "B.Paste")
			(net 2 "VCC3V3")
			(pintype "passive")
		)
	)
	(footprint "antmicro-footprints:C_1210_3225Metric"
		(layer "B.Cu")
		(at 90.5 148.9)
		(descr "Capacitor SMD 1210")
		(tags "capacitor SMD 1210")
		(property "Reference" "C96"
			(at -1.1 -1.8 0)
			(layer "B.SilkS")
			(effects
				(font
					(size 0.7 0.7)
					(thickness 0.15)
				)
				(justify right bottom mirror)
			)
		)
		(property "Value" "C_47u_1210"
			(at 0 -2.749 0)
			(layer "B.Fab")
			(effects
				(font
					(size 0.7 0.7)
					(thickness 0.15)
				)
				(justify right bottom mirror)
			)
		)
		(property "Datasheet" "https://www.kemet.com/en/us/capacitors/product/C1210C476K8RACTU.html"
			(at 0 0 0)
			(layer "F.Fab")
			(hide yes)
			(effects
				(font
					(size 1.27 1.27)
					(thickness 0.15)
				)
			)
		)
		(property "Description" "SMD Multilayer Ceramic Capacitor, 47 µF, 10 V, 1210 [3225 Metric], ± 10%, X7R, C Series KEMET"
			(at 0 0 0)
			(layer "F.Fab")
			(hide yes)
			(effects
				(font
					(size 1.27 1.27)
					(thickness 0.15)
				)
			)
		)
		(property "Author" "Antmicro"
			(at 0 0 0)
			(layer "B.Fab")
			(hide yes)
			(effects
				(font
					(size 1 1)
					(thickness 0.15)
				)
				(justify mirror)
			)
		)
		(property "Dielectric" ""
			(at 0 0 0)
			(layer "B.Fab")
			(hide yes)
			(effects
				(font
					(size 1 1)
					(thickness 0.15)
				)
				(justify mirror)
			)
		)
		(property "License" "Apache-2.0"
			(at 0 0 0)
			(layer "B.Fab")
			(hide yes)
			(effects
				(font
					(size 1 1)
					(thickness 0.15)
				)
				(justify mirror)
			)
		)
		(property "MPN" "C1210C476K8RACTU"
			(at 0 0 0)
			(layer "B.Fab")
			(hide yes)
			(effects
				(font
					(size 1 1)
					(thickness 0.15)
				)
				(justify mirror)
			)
		)
		(property "Manufacturer" "KEMET"
			(at 0 0 0)
			(layer "B.Fab")
			(hide yes)
			(effects
				(font
					(size 1 1)
					(thickness 0.15)
				)
				(justify mirror)
			)
		)
		(property "Public" "False"
			(at 0 0 0)
			(layer "B.Fab")
			(hide yes)
			(effects
				(font
					(size 1 1)
					(thickness 0.15)
				)
				(justify mirror)
			)
		)
		(property "Val" "47u"
			(at 0 0 0)
			(layer "B.Fab")
			(hide yes)
			(effects
				(font
					(size 1 1)
					(thickness 0.15)
				)
				(justify mirror)
			)
		)
		(property "Voltage" ""
			(at 0 0 0)
			(layer "B.Fab")
			(hide yes)
			(effects
				(font
					(size 1 1)
					(thickness 0.15)
				)
				(justify mirror)
			)
		)
		(sheetname "/FPGA banks 34-35 & CFG/")
		(sheetfile "fpga-banks-34-25-cfg.kicad_sch")
		(attr smd)
		(fp_line
			(start -0.3 -1.39)
			(end 0.3 -1.39)
			(stroke
				(width 0.15)
				(type solid)
			)
			(layer "B.SilkS")
		)
		(fp_line
			(start -0.3 1.39)
			(end 0.3 1.39)
			(stroke
				(width 0.15)
				(type solid)
			)
			(layer "B.SilkS")
		)
		(fp_rect
			(start -2.1 1.75)
			(end 2.1 -1.75)
			(stroke
				(width 0.05)
				(type solid)
			)
			(fill no)
			(layer "B.CrtYd")
		)
		(fp_rect
			(start -1.6 1.25)
			(end 1.6 -1.25)
			(stroke
				(width 0.15)
				(type solid)
			)
			(fill no)
			(layer "B.Fab")
		)
		(pad "1" smd rect
			(at -1.145 0)
			(size 1.52 3.05)
			(layers "B.Cu" "B.Mask" "B.Paste")
			(net 1 "GND")
			(pintype "passive")
		)
		(pad "2" smd rect
			(at 1.145 0)
			(size 1.52 3.05)
			(layers "B.Cu" "B.Mask" "B.Paste")
			(net 3 "VCC1V35")
			(pintype "passive")
		)
	)
	(footprint "antmicro-footprints:C_0603_1608Metric"
		(layer "B.Cu")
		(at 91.3 119.3 90)
		(descr "Capacitor SMD 0603")
		(tags "capacitor 0603")
		(property "Reference" "C97"
			(at -0.7 -0.6 90)
			(layer "B.SilkS")
			(effects
				(font
					(size 0.7 0.7)
					(thickness 0.15)
				)
				(justify right bottom mirror)
			)
		)
		(property "Value" "C_4u7_0603"
			(at 0 -1.6 90)
			(layer "B.Fab")
			(effects
				(font
					(size 0.7 0.7)
					(thickness 0.15)
				)
				(justify right bottom mirror)
			)
		)
		(property "Datasheet" "https://product.tdk.com/en/search/capacitor/ceramic/mlcc/info?part_no=C1608X5R1V475M080AC"
			(at 0 0 90)
			(layer "F.Fab")
			(hide yes)
			(effects
				(font
					(size 1.27 1.27)
					(thickness 0.15)
				)
			)
		)
		(property "Description" "SMD Multilayer Ceramic Capacitor, 4.7 µF, 35 V, 0603 [1608 Metric], ± 20%, X5R, C"
			(at 0 0 90)
			(layer "F.Fab")
			(hide yes)
			(effects
				(font
					(size 1.27 1.27)
					(thickness 0.15)
				)
			)
		)
		(property "Author" "Antmicro"
			(at 210.6 28 0)
			(layer "B.Fab")
			(hide yes)
			(effects
				(font
					(size 1 1)
					(thickness 0.15)
				)
				(justify mirror)
			)
		)
		(property "Dielectric" ""
			(at 210.6 28 0)
			(layer "B.Fab")
			(hide yes)
			(effects
				(font
					(size 1 1)
					(thickness 0.15)
				)
				(justify mirror)
			)
		)
		(property "License" "Apache-2.0"
			(at 210.6 28 0)
			(layer "B.Fab")
			(hide yes)
			(effects
				(font
					(size 1 1)
					(thickness 0.15)
				)
				(justify mirror)
			)
		)
		(property "MPN" "C1608X5R1V475M080AC"
			(at 210.6 28 0)
			(layer "B.Fab")
			(hide yes)
			(effects
				(font
					(size 1 1)
					(thickness 0.15)
				)
				(justify mirror)
			)
		)
		(property "Manufacturer" "TDK"
			(at 210.6 28 0)
			(layer "B.Fab")
			(hide yes)
			(effects
				(font
					(size 1 1)
					(thickness 0.15)
				)
				(justify mirror)
			)
		)
		(property "Val" "4u7"
			(at 210.6 28 0)
			(layer "B.Fab")
			(hide yes)
			(effects
				(font
					(size 1 1)
					(thickness 0.15)
				)
				(justify mirror)
			)
		)
		(property "Voltage" ""
			(at 210.6 28 0)
			(layer "B.Fab")
			(hide yes)
			(effects
				(font
					(size 1 1)
					(thickness 0.15)
				)
				(justify mirror)
			)
		)
		(sheetname "/FPGA banks 34-35 & CFG/")
		(sheetfile "fpga-banks-34-25-cfg.kicad_sch")
		(attr smd)
		(fp_line
			(start -0.15 -0.4)
			(end 0.15 -0.4)
			(stroke
				(width 0.15)
				(type solid)
			)
			(layer "B.SilkS")
		)
		(fp_line
			(start -0.15 0.4)
			(end 0.15 0.4)
			(stroke
				(width 0.15)
				(type solid)
			)
			(layer "B.SilkS")
		)
		(fp_rect
			(start -1.25 0.65)
			(end 1.25 -0.65)
			(stroke
				(width 0.05)
				(type solid)
			)
			(fill no)
			(layer "B.CrtYd")
		)
		(fp_rect
			(start -0.8 0.4)
			(end 0.8 -0.4)
			(stroke
				(width 0.15)
				(type solid)
			)
			(fill no)
			(layer "B.Fab")
		)
		(pad "1" smd roundrect
			(at -0.7 0 90)
			(size 0.8 1)
			(layers "B.Cu" "B.Mask" "B.Paste")
			(roundrect_rratio 0.2)
			(net 1 "GND")
			(pintype "passive")
		)
		(pad "2" smd roundrect
			(at 0.7 0 90)
			(size 0.8 1)
			(layers "B.Cu" "B.Mask" "B.Paste")
			(roundrect_rratio 0.2)
			(net 2 "VCC3V3")
			(pintype "passive")
		)
	)
	(footprint "antmicro-footprints:C_0603_1608Metric"
		(layer "B.Cu")
		(at 92.8 133.6 90)
		(descr "Capacitor SMD 0603")
		(tags "capacitor 0603")
		(property "Reference" "C98"
			(at -3.2 0.3 90)
			(layer "B.SilkS")
			(effects
				(font
					(size 0.7 0.7)
					(thickness 0.15)
				)
				(justify right bottom mirror)
			)
		)
		(property "Value" "C_4u7_0603"
			(at 0 -1.6 90)
			(layer "B.Fab")
			(effects
				(font
					(size 0.7 0.7)
					(thickness 0.15)
				)
				(justify right bottom mirror)
			)
		)
		(property "Datasheet" "https://product.tdk.com/en/search/capacitor/ceramic/mlcc/info?part_no=C1608X5R1V475M080AC"
			(at 0 0 90)
			(layer "F.Fab")
			(hide yes)
			(effects
				(font
					(size 1.27 1.27)
					(thickness 0.15)
				)
			)
		)
		(property "Description" "SMD Multilayer Ceramic Capacitor, 4.7 µF, 35 V, 0603 [1608 Metric], ± 20%, X5R, C"
			(at 0 0 90)
			(layer "F.Fab")
			(hide yes)
			(effects
				(font
					(size 1.27 1.27)
					(thickness 0.15)
				)
			)
		)
		(property "Author" "Antmicro"
			(at 226.4 40.8 0)
			(layer "B.Fab")
			(hide yes)
			(effects
				(font
					(size 1 1)
					(thickness 0.15)
				)
				(justify mirror)
			)
		)
		(property "Dielectric" ""
			(at 226.4 40.8 0)
			(layer "B.Fab")
			(hide yes)
			(effects
				(font
					(size 1 1)
					(thickness 0.15)
				)
				(justify mirror)
			)
		)
		(property "License" "Apache-2.0"
			(at 226.4 40.8 0)
			(layer "B.Fab")
			(hide yes)
			(effects
				(font
					(size 1 1)
					(thickness 0.15)
				)
				(justify mirror)
			)
		)
		(property "MPN" "C1608X5R1V475M080AC"
			(at 226.4 40.8 0)
			(layer "B.Fab")
			(hide yes)
			(effects
				(font
					(size 1 1)
					(thickness 0.15)
				)
				(justify mirror)
			)
		)
		(property "Manufacturer" "TDK"
			(at 226.4 40.8 0)
			(layer "B.Fab")
			(hide yes)
			(effects
				(font
					(size 1 1)
					(thickness 0.15)
				)
				(justify mirror)
			)
		)
		(property "Val" "4u7"
			(at 226.4 40.8 0)
			(layer "B.Fab")
			(hide yes)
			(effects
				(font
					(size 1 1)
					(thickness 0.15)
				)
				(justify mirror)
			)
		)
		(property "Voltage" ""
			(at 226.4 40.8 0)
			(layer "B.Fab")
			(hide yes)
			(effects
				(font
					(size 1 1)
					(thickness 0.15)
				)
				(justify mirror)
			)
		)
		(property "DNP" ""
			(at 0 0 90)
			(unlocked yes)
			(layer "B.Fab")
			(hide yes)
			(effects
				(font
					(size 1 1)
					(thickness 0.15)
				)
				(justify mirror)
			)
		)
		(sheetname "/FPGA banks 13-16/")
		(sheetfile "fpga-banks-13-16.kicad_sch")
		(attr smd)
		(fp_line
			(start -0.15 -0.4)
			(end 0.15 -0.4)
			(stroke
				(width 0.15)
				(type solid)
			)
			(layer "B.SilkS")
		)
		(fp_line
			(start -0.15 0.4)
			(end 0.15 0.4)
			(stroke
				(width 0.15)
				(type solid)
			)
			(layer "B.SilkS")
		)
		(fp_rect
			(start -1.25 0.65)
			(end 1.25 -0.65)
			(stroke
				(width 0.05)
				(type solid)
			)
			(fill no)
			(layer "B.CrtYd")
		)
		(fp_rect
			(start -0.8 0.4)
			(end 0.8 -0.4)
			(stroke
				(width 0.15)
				(type solid)
			)
			(fill no)
			(layer "B.Fab")
		)
		(pad "1" smd roundrect
			(at -0.7 0 90)
			(size 0.8 1)
			(layers "B.Cu" "B.Mask" "B.Paste")
			(roundrect_rratio 0.2)
			(net 1 "GND")
			(pintype "passive")
		)
		(pad "2" smd roundrect
			(at 0.7 0 90)
			(size 0.8 1)
			(layers "B.Cu" "B.Mask" "B.Paste")
			(roundrect_rratio 0.2)
			(net 2 "VCC3V3")
			(pintype "passive")
		)
	)
	(footprint "antmicro-footprints:C_0603_1608Metric"
		(layer "B.Cu")
		(at 114.4 131.4 180)
		(descr "Capacitor SMD 0603")
		(tags "capacitor 0603")
		(property "Reference" "C100"
			(at 1 -0.4 0)
			(layer "B.SilkS")
			(effects
				(font
					(size 0.7 0.7)
					(thickness 0.15)
				)
				(justify left bottom mirror)
			)
		)
		(property "Value" "C_4u7_0603"
			(at 0 -1.6 0)
			(layer "B.Fab")
			(effects
				(font
					(size 0.7 0.7)
					(thickness 0.15)
				)
				(justify left bottom mirror)
			)
		)
		(property "Datasheet" "https://product.tdk.com/en/search/capacitor/ceramic/mlcc/info?part_no=C1608X5R1V475M080AC"
			(at 0 0 180)
			(layer "F.Fab")
			(hide yes)
			(effects
				(font
					(size 1.27 1.27)
					(thickness 0.15)
				)
			)
		)
		(property "Description" "SMD Multilayer Ceramic Capacitor, 4.7 µF, 35 V, 0603 [1608 Metric], ± 20%, X5R, C"
			(at 0 0 180)
			(layer "F.Fab")
			(hide yes)
			(effects
				(font
					(size 1.27 1.27)
					(thickness 0.15)
				)
			)
		)
		(property "Author" "Antmicro"
			(at 228.8 262.8 0)
			(layer "B.Fab")
			(hide yes)
			(effects
				(font
					(size 1 1)
					(thickness 0.15)
				)
				(justify mirror)
			)
		)
		(property "Dielectric" ""
			(at 228.8 262.8 0)
			(layer "B.Fab")
			(hide yes)
			(effects
				(font
					(size 1 1)
					(thickness 0.15)
				)
				(justify mirror)
			)
		)
		(property "License" "Apache-2.0"
			(at 228.8 262.8 0)
			(layer "B.Fab")
			(hide yes)
			(effects
				(font
					(size 1 1)
					(thickness 0.15)
				)
				(justify mirror)
			)
		)
		(property "MPN" "C1608X5R1V475M080AC"
			(at 228.8 262.8 0)
			(layer "B.Fab")
			(hide yes)
			(effects
				(font
					(size 1 1)
					(thickness 0.15)
				)
				(justify mirror)
			)
		)
		(property "Manufacturer" "TDK"
			(at 228.8 262.8 0)
			(layer "B.Fab")
			(hide yes)
			(effects
				(font
					(size 1 1)
					(thickness 0.15)
				)
				(justify mirror)
			)
		)
		(property "Val" "4u7"
			(at 228.8 262.8 0)
			(layer "B.Fab")
			(hide yes)
			(effects
				(font
					(size 1 1)
					(thickness 0.15)
				)
				(justify mirror)
			)
		)
		(property "Voltage" ""
			(at 228.8 262.8 0)
			(layer "B.Fab")
			(hide yes)
			(effects
				(font
					(size 1 1)
					(thickness 0.15)
				)
				(justify mirror)
			)
		)
		(property "DNP" ""
			(at 0 0 180)
			(unlocked yes)
			(layer "B.Fab")
			(hide yes)
			(effects
				(font
					(size 1 1)
					(thickness 0.15)
				)
				(justify mirror)
			)
		)
		(sheetname "/FPGA banks 13-16/")
		(sheetfile "fpga-banks-13-16.kicad_sch")
		(attr smd)
		(fp_line
			(start -0.15 0.4)
			(end 0.15 0.4)
			(stroke
				(width 0.15)
				(type solid)
			)
			(layer "B.SilkS")
		)
		(fp_line
			(start -0.15 -0.4)
			(end 0.15 -0.4)
			(stroke
				(width 0.15)
				(type solid)
			)
			(layer "B.SilkS")
		)
		(fp_rect
			(start -1.25 0.65)
			(end 1.25 -0.65)
			(stroke
				(width 0.05)
				(type solid)
			)
			(fill no)
			(layer "B.CrtYd")
		)
		(fp_rect
			(start -0.8 0.4)
			(end 0.8 -0.4)
			(stroke
				(width 0.15)
				(type solid)
			)
			(fill no)
			(layer "B.Fab")
		)
		(pad "1" smd roundrect
			(at -0.7 0 180)
			(size 0.8 1)
			(layers "B.Cu" "B.Mask" "B.Paste")
			(roundrect_rratio 0.2)
			(net 1 "GND")
			(pintype "passive")
		)
		(pad "2" smd roundrect
			(at 0.7 0 180)
			(size 0.8 1)
			(layers "B.Cu" "B.Mask" "B.Paste")
			(roundrect_rratio 0.2)
			(net 2 "VCC3V3")
			(pintype "passive")
		)
	)
	(footprint "antmicro-footprints:C_0603_1608Metric"
		(layer "B.Cu")
		(at 90.5 151.5)
		(descr "Capacitor SMD 0603")
		(tags "capacitor 0603")
		(property "Reference" "C102"
			(at -3.9 0.4 0)
			(layer "B.SilkS")
			(effects
				(font
					(size 0.7 0.7)
					(thickness 0.15)
				)
				(justify right bottom mirror)
			)
		)
		(property "Value" "C_4u7_0603"
			(at 0 -1.6 0)
			(layer "B.Fab")
			(effects
				(font
					(size 0.7 0.7)
					(thickness 0.15)
				)
				(justify right bottom mirror)
			)
		)
		(property "Datasheet" "https://product.tdk.com/en/search/capacitor/ceramic/mlcc/info?part_no=C1608X5R1V475M080AC"
			(at 0 0 0)
			(layer "F.Fab")
			(hide yes)
			(effects
				(font
					(size 1.27 1.27)
					(thickness 0.15)
				)
			)
		)
		(property "Description" "SMD Multilayer Ceramic Capacitor, 4.7 µF, 35 V, 0603 [1608 Metric], ± 20%, X5R, C"
			(at 0 0 0)
			(layer "F.Fab")
			(hide yes)
			(effects
				(font
					(size 1.27 1.27)
					(thickness 0.15)
				)
			)
		)
		(property "Author" "Antmicro"
			(at 0 0 0)
			(layer "B.Fab")
			(hide yes)
			(effects
				(font
					(size 1 1)
					(thickness 0.15)
				)
				(justify mirror)
			)
		)
		(property "Dielectric" ""
			(at 0 0 0)
			(layer "B.Fab")
			(hide yes)
			(effects
				(font
					(size 1 1)
					(thickness 0.15)
				)
				(justify mirror)
			)
		)
		(property "License" "Apache-2.0"
			(at 0 0 0)
			(layer "B.Fab")
			(hide yes)
			(effects
				(font
					(size 1 1)
					(thickness 0.15)
				)
				(justify mirror)
			)
		)
		(property "MPN" "C1608X5R1V475M080AC"
			(at 0 0 0)
			(layer "B.Fab")
			(hide yes)
			(effects
				(font
					(size 1 1)
					(thickness 0.15)
				)
				(justify mirror)
			)
		)
		(property "Manufacturer" "TDK"
			(at 0 0 0)
			(layer "B.Fab")
			(hide yes)
			(effects
				(font
					(size 1 1)
					(thickness 0.15)
				)
				(justify mirror)
			)
		)
		(property "Val" "4u7"
			(at 0 0 0)
			(layer "B.Fab")
			(hide yes)
			(effects
				(font
					(size 1 1)
					(thickness 0.15)
				)
				(justify mirror)
			)
		)
		(property "Voltage" ""
			(at 0 0 0)
			(layer "B.Fab")
			(hide yes)
			(effects
				(font
					(size 1 1)
					(thickness 0.15)
				)
				(justify mirror)
			)
		)
		(sheetname "/FPGA banks 34-35 & CFG/")
		(sheetfile "fpga-banks-34-25-cfg.kicad_sch")
		(attr smd)
		(fp_line
			(start -0.15 -0.4)
			(end 0.15 -0.4)
			(stroke
				(width 0.15)
				(type solid)
			)
			(layer "B.SilkS")
		)
		(fp_line
			(start -0.15 0.4)
			(end 0.15 0.4)
			(stroke
				(width 0.15)
				(type solid)
			)
			(layer "B.SilkS")
		)
		(fp_rect
			(start -1.25 0.65)
			(end 1.25 -0.65)
			(stroke
				(width 0.05)
				(type solid)
			)
			(fill no)
			(layer "B.CrtYd")
		)
		(fp_rect
			(start -0.8 0.4)
			(end 0.8 -0.4)
			(stroke
				(width 0.15)
				(type solid)
			)
			(fill no)
			(layer "B.Fab")
		)
		(pad "1" smd roundrect
			(at -0.7 0)
			(size 0.8 1)
			(layers "B.Cu" "B.Mask" "B.Paste")
			(roundrect_rratio 0.2)
			(net 1 "GND")
			(pintype "passive")
		)
		(pad "2" smd roundrect
			(at 0.7 0)
			(size 0.8 1)
			(layers "B.Cu" "B.Mask" "B.Paste")
			(roundrect_rratio 0.2)
			(net 3 "VCC1V35")
			(pintype "passive")
		)
	)
	(footprint "antmicro-footprints:C_0603_1608Metric"
		(layer "B.Cu")
		(at 91.3 133.6 90)
		(descr "Capacitor SMD 0603")
		(tags "capacitor 0603")
		(property "Reference" "C104"
			(at -3.9 0.3 90)
			(layer "B.SilkS")
			(effects
				(font
					(size 0.7 0.7)
					(thickness 0.15)
				)
				(justify right bottom mirror)
			)
		)
		(property "Value" "C_4u7_0603"
			(at 0 -1.6 90)
			(layer "B.Fab")
			(effects
				(font
					(size 0.7 0.7)
					(thickness 0.15)
				)
				(justify right bottom mirror)
			)
		)
		(property "Datasheet" "https://product.tdk.com/en/search/capacitor/ceramic/mlcc/info?part_no=C1608X5R1V475M080AC"
			(at 0 0 90)
			(layer "F.Fab")
			(hide yes)
			(effects
				(font
					(size 1.27 1.27)
					(thickness 0.15)
				)
			)
		)
		(property "Description" "SMD Multilayer Ceramic Capacitor, 4.7 µF, 35 V, 0603 [1608 Metric], ± 20%, X5R, C"
			(at 0 0 90)
			(layer "F.Fab")
			(hide yes)
			(effects
				(font
					(size 1.27 1.27)
					(thickness 0.15)
				)
			)
		)
		(property "Author" "Antmicro"
			(at 224.9 42.3 0)
			(layer "B.Fab")
			(hide yes)
			(effects
				(font
					(size 1 1)
					(thickness 0.15)
				)
				(justify mirror)
			)
		)
		(property "Dielectric" ""
			(at 224.9 42.3 0)
			(layer "B.Fab")
			(hide yes)
			(effects
				(font
					(size 1 1)
					(thickness 0.15)
				)
				(justify mirror)
			)
		)
		(property "License" "Apache-2.0"
			(at 224.9 42.3 0)
			(layer "B.Fab")
			(hide yes)
			(effects
				(font
					(size 1 1)
					(thickness 0.15)
				)
				(justify mirror)
			)
		)
		(property "MPN" "C1608X5R1V475M080AC"
			(at 224.9 42.3 0)
			(layer "B.Fab")
			(hide yes)
			(effects
				(font
					(size 1 1)
					(thickness 0.15)
				)
				(justify mirror)
			)
		)
		(property "Manufacturer" "TDK"
			(at 224.9 42.3 0)
			(layer "B.Fab")
			(hide yes)
			(effects
				(font
					(size 1 1)
					(thickness 0.15)
				)
				(justify mirror)
			)
		)
		(property "Val" "4u7"
			(at 224.9 42.3 0)
			(layer "B.Fab")
			(hide yes)
			(effects
				(font
					(size 1 1)
					(thickness 0.15)
				)
				(justify mirror)
			)
		)
		(property "Voltage" ""
			(at 224.9 42.3 0)
			(layer "B.Fab")
			(hide yes)
			(effects
				(font
					(size 1 1)
					(thickness 0.15)
				)
				(justify mirror)
			)
		)
		(property "DNP" ""
			(at 0 0 90)
			(unlocked yes)
			(layer "B.Fab")
			(hide yes)
			(effects
				(font
					(size 1 1)
					(thickness 0.15)
				)
				(justify mirror)
			)
		)
		(sheetname "/FPGA banks 13-16/")
		(sheetfile "fpga-banks-13-16.kicad_sch")
		(attr smd)
		(fp_line
			(start -0.15 -0.4)
			(end 0.15 -0.4)
			(stroke
				(width 0.15)
				(type solid)
			)
			(layer "B.SilkS")
		)
		(fp_line
			(start -0.15 0.4)
			(end 0.15 0.4)
			(stroke
				(width 0.15)
				(type solid)
			)
			(layer "B.SilkS")
		)
		(fp_rect
			(start -1.25 0.65)
			(end 1.25 -0.65)
			(stroke
				(width 0.05)
				(type solid)
			)
			(fill no)
			(layer "B.CrtYd")
		)
		(fp_rect
			(start -0.8 0.4)
			(end 0.8 -0.4)
			(stroke
				(width 0.15)
				(type solid)
			)
			(fill no)
			(layer "B.Fab")
		)
		(pad "1" smd roundrect
			(at -0.7 0 90)
			(size 0.8 1)
			(layers "B.Cu" "B.Mask" "B.Paste")
			(roundrect_rratio 0.2)
			(net 1 "GND")
			(pintype "passive")
		)
		(pad "2" smd roundrect
			(at 0.7 0 90)
			(size 0.8 1)
			(layers "B.Cu" "B.Mask" "B.Paste")
			(roundrect_rratio 0.2)
			(net 2 "VCC3V3")
			(pintype "passive")
		)
	)
	(footprint "antmicro-footprints:C_0603_1608Metric"
		(layer "B.Cu")
		(at 112.6 106.5 180)
		(descr "Capacitor SMD 0603")
		(tags "capacitor 0603")
		(property "Reference" "C105"
			(at -3.9 -0.3 0)
			(layer "B.SilkS")
			(effects
				(font
					(size 0.7 0.7)
					(thickness 0.15)
				)
				(justify left bottom mirror)
			)
		)
		(property "Value" "C_4u7_0603"
			(at 0 -1.6 0)
			(layer "B.Fab")
			(effects
				(font
					(size 0.7 0.7)
					(thickness 0.15)
				)
				(justify left bottom mirror)
			)
		)
		(property "Datasheet" "https://product.tdk.com/en/search/capacitor/ceramic/mlcc/info?part_no=C1608X5R1V475M080AC"
			(at 0 0 180)
			(layer "F.Fab")
			(hide yes)
			(effects
				(font
					(size 1.27 1.27)
					(thickness 0.15)
				)
			)
		)
		(property "Description" "SMD Multilayer Ceramic Capacitor, 4.7 µF, 35 V, 0603 [1608 Metric], ± 20%, X5R, C"
			(at 0 0 180)
			(layer "F.Fab")
			(hide yes)
			(effects
				(font
					(size 1.27 1.27)
					(thickness 0.15)
				)
			)
		)
		(property "Author" "Antmicro"
			(at 225.2 213 0)
			(layer "B.Fab")
			(hide yes)
			(effects
				(font
					(size 1 1)
					(thickness 0.15)
				)
				(justify mirror)
			)
		)
		(property "Dielectric" ""
			(at 225.2 213 0)
			(layer "B.Fab")
			(hide yes)
			(effects
				(font
					(size 1 1)
					(thickness 0.15)
				)
				(justify mirror)
			)
		)
		(property "License" "Apache-2.0"
			(at 225.2 213 0)
			(layer "B.Fab")
			(hide yes)
			(effects
				(font
					(size 1 1)
					(thickness 0.15)
				)
				(justify mirror)
			)
		)
		(property "MPN" "C1608X5R1V475M080AC"
			(at 225.2 213 0)
			(layer "B.Fab")
			(hide yes)
			(effects
				(font
					(size 1 1)
					(thickness 0.15)
				)
				(justify mirror)
			)
		)
		(property "Manufacturer" "TDK"
			(at 225.2 213 0)
			(layer "B.Fab")
			(hide yes)
			(effects
				(font
					(size 1 1)
					(thickness 0.15)
				)
				(justify mirror)
			)
		)
		(property "Val" "4u7"
			(at 225.2 213 0)
			(layer "B.Fab")
			(hide yes)
			(effects
				(font
					(size 1 1)
					(thickness 0.15)
				)
				(justify mirror)
			)
		)
		(property "Voltage" ""
			(at 225.2 213 0)
			(layer "B.Fab")
			(hide yes)
			(effects
				(font
					(size 1 1)
					(thickness 0.15)
				)
				(justify mirror)
			)
		)
		(sheetname "/FPGA banks 13-16/")
		(sheetfile "fpga-banks-13-16.kicad_sch")
		(attr smd)
		(fp_line
			(start -0.15 0.4)
			(end 0.15 0.4)
			(stroke
				(width 0.15)
				(type solid)
			)
			(layer "B.SilkS")
		)
		(fp_line
			(start -0.15 -0.4)
			(end 0.15 -0.4)
			(stroke
				(width 0.15)
				(type solid)
			)
			(layer "B.SilkS")
		)
		(fp_rect
			(start -1.25 0.65)
			(end 1.25 -0.65)
			(stroke
				(width 0.05)
				(type solid)
			)
			(fill no)
			(layer "B.CrtYd")
		)
		(fp_rect
			(start -0.8 0.4)
			(end 0.8 -0.4)
			(stroke
				(width 0.15)
				(type solid)
			)
			(fill no)
			(layer "B.Fab")
		)
		(pad "1" smd roundrect
			(at -0.7 0 180)
			(size 0.8 1)
			(layers "B.Cu" "B.Mask" "B.Paste")
			(roundrect_rratio 0.2)
			(net 1 "GND")
			(pintype "passive")
		)
		(pad "2" smd roundrect
			(at 0.7 0 180)
			(size 0.8 1)
			(layers "B.Cu" "B.Mask" "B.Paste")
			(roundrect_rratio 0.2)
			(net 2 "VCC3V3")
			(pintype "passive")
		)
	)
	(footprint "antmicro-footprints:C_0603_1608Metric"
		(layer "B.Cu")
		(at 114.4 129.8 180)
		(descr "Capacitor SMD 0603")
		(tags "capacitor 0603")
		(property "Reference" "C106"
			(at 1 -0.4 0)
			(layer "B.SilkS")
			(effects
				(font
					(size 0.7 0.7)
					(thickness 0.15)
				)
				(justify left bottom mirror)
			)
		)
		(property "Value" "C_4u7_0603"
			(at 0 -1.6 0)
			(layer "B.Fab")
			(effects
				(font
					(size 0.7 0.7)
					(thickness 0.15)
				)
				(justify left bottom mirror)
			)
		)
		(property "Datasheet" "https://product.tdk.com/en/search/capacitor/ceramic/mlcc/info?part_no=C1608X5R1V475M080AC"
			(at 0 0 180)
			(layer "F.Fab")
			(hide yes)
			(effects
				(font
					(size 1.27 1.27)
					(thickness 0.15)
				)
			)
		)
		(property "Description" "SMD Multilayer Ceramic Capacitor, 4.7 µF, 35 V, 0603 [1608 Metric], ± 20%, X5R, C"
			(at 0 0 180)
			(layer "F.Fab")
			(hide yes)
			(effects
				(font
					(size 1.27 1.27)
					(thickness 0.15)
				)
			)
		)
		(property "Author" "Antmicro"
			(at 228.8 259.6 0)
			(layer "B.Fab")
			(hide yes)
			(effects
				(font
					(size 1 1)
					(thickness 0.15)
				)
				(justify mirror)
			)
		)
		(property "Dielectric" ""
			(at 228.8 259.6 0)
			(layer "B.Fab")
			(hide yes)
			(effects
				(font
					(size 1 1)
					(thickness 0.15)
				)
				(justify mirror)
			)
		)
		(property "License" "Apache-2.0"
			(at 228.8 259.6 0)
			(layer "B.Fab")
			(hide yes)
			(effects
				(font
					(size 1 1)
					(thickness 0.15)
				)
				(justify mirror)
			)
		)
		(property "MPN" "C1608X5R1V475M080AC"
			(at 228.8 259.6 0)
			(layer "B.Fab")
			(hide yes)
			(effects
				(font
					(size 1 1)
					(thickness 0.15)
				)
				(justify mirror)
			)
		)
		(property "Manufacturer" "TDK"
			(at 228.8 259.6 0)
			(layer "B.Fab")
			(hide yes)
			(effects
				(font
					(size 1 1)
					(thickness 0.15)
				)
				(justify mirror)
			)
		)
		(property "Val" "4u7"
			(at 228.8 259.6 0)
			(layer "B.Fab")
			(hide yes)
			(effects
				(font
					(size 1 1)
					(thickness 0.15)
				)
				(justify mirror)
			)
		)
		(property "Voltage" ""
			(at 228.8 259.6 0)
			(layer "B.Fab")
			(hide yes)
			(effects
				(font
					(size 1 1)
					(thickness 0.15)
				)
				(justify mirror)
			)
		)
		(property "DNP" ""
			(at 0 0 180)
			(unlocked yes)
			(layer "B.Fab")
			(hide yes)
			(effects
				(font
					(size 1 1)
					(thickness 0.15)
				)
				(justify mirror)
			)
		)
		(sheetname "/FPGA banks 13-16/")
		(sheetfile "fpga-banks-13-16.kicad_sch")
		(attr smd)
		(fp_line
			(start -0.15 0.4)
			(end 0.15 0.4)
			(stroke
				(width 0.15)
				(type solid)
			)
			(layer "B.SilkS")
		)
		(fp_line
			(start -0.15 -0.4)
			(end 0.15 -0.4)
			(stroke
				(width 0.15)
				(type solid)
			)
			(layer "B.SilkS")
		)
		(fp_rect
			(start -1.25 0.65)
			(end 1.25 -0.65)
			(stroke
				(width 0.05)
				(type solid)
			)
			(fill no)
			(layer "B.CrtYd")
		)
		(fp_rect
			(start -0.8 0.4)
			(end 0.8 -0.4)
			(stroke
				(width 0.15)
				(type solid)
			)
			(fill no)
			(layer "B.Fab")
		)
		(pad "1" smd roundrect
			(at -0.7 0 180)
			(size 0.8 1)
			(layers "B.Cu" "B.Mask" "B.Paste")
			(roundrect_rratio 0.2)
			(net 1 "GND")
			(pintype "passive")
		)
		(pad "2" smd roundrect
			(at 0.7 0 180)
			(size 0.8 1)
			(layers "B.Cu" "B.Mask" "B.Paste")
			(roundrect_rratio 0.2)
			(net 2 "VCC3V3")
			(pintype "passive")
		)
	)
	(footprint "antmicro-footprints:C_0603_1608Metric"
		(layer "B.Cu")
		(at 90.5 153)
		(descr "Capacitor SMD 0603")
		(tags "capacitor 0603")
		(property "Reference" "C108"
			(at -3.9 0.4 0)
			(layer "B.SilkS")
			(effects
				(font
					(size 0.7 0.7)
					(thickness 0.15)
				)
				(justify right bottom mirror)
			)
		)
		(property "Value" "C_4u7_0603"
			(at 0 -1.6 0)
			(layer "B.Fab")
			(effects
				(font
					(size 0.7 0.7)
					(thickness 0.15)
				)
				(justify right bottom mirror)
			)
		)
		(property "Datasheet" "https://product.tdk.com/en/search/capacitor/ceramic/mlcc/info?part_no=C1608X5R1V475M080AC"
			(at 0 0 0)
			(layer "F.Fab")
			(hide yes)
			(effects
				(font
					(size 1.27 1.27)
					(thickness 0.15)
				)
			)
		)
		(property "Description" "SMD Multilayer Ceramic Capacitor, 4.7 µF, 35 V, 0603 [1608 Metric], ± 20%, X5R, C"
			(at 0 0 0)
			(layer "F.Fab")
			(hide yes)
			(effects
				(font
					(size 1.27 1.27)
					(thickness 0.15)
				)
			)
		)
		(property "Author" "Antmicro"
			(at 0 0 0)
			(layer "B.Fab")
			(hide yes)
			(effects
				(font
					(size 1 1)
					(thickness 0.15)
				)
				(justify mirror)
			)
		)
		(property "Dielectric" ""
			(at 0 0 0)
			(layer "B.Fab")
			(hide yes)
			(effects
				(font
					(size 1 1)
					(thickness 0.15)
				)
				(justify mirror)
			)
		)
		(property "License" "Apache-2.0"
			(at 0 0 0)
			(layer "B.Fab")
			(hide yes)
			(effects
				(font
					(size 1 1)
					(thickness 0.15)
				)
				(justify mirror)
			)
		)
		(property "MPN" "C1608X5R1V475M080AC"
			(at 0 0 0)
			(layer "B.Fab")
			(hide yes)
			(effects
				(font
					(size 1 1)
					(thickness 0.15)
				)
				(justify mirror)
			)
		)
		(property "Manufacturer" "TDK"
			(at 0 0 0)
			(layer "B.Fab")
			(hide yes)
			(effects
				(font
					(size 1 1)
					(thickness 0.15)
				)
				(justify mirror)
			)
		)
		(property "Val" "4u7"
			(at 0 0 0)
			(layer "B.Fab")
			(hide yes)
			(effects
				(font
					(size 1 1)
					(thickness 0.15)
				)
				(justify mirror)
			)
		)
		(property "Voltage" ""
			(at 0 0 0)
			(layer "B.Fab")
			(hide yes)
			(effects
				(font
					(size 1 1)
					(thickness 0.15)
				)
				(justify mirror)
			)
		)
		(property "DNP" ""
			(at 0 0 0)
			(unlocked yes)
			(layer "B.Fab")
			(hide yes)
			(effects
				(font
					(size 1 1)
					(thickness 0.15)
				)
				(justify mirror)
			)
		)
		(sheetname "/FPGA banks 34-35 & CFG/")
		(sheetfile "fpga-banks-34-25-cfg.kicad_sch")
		(attr smd)
		(fp_line
			(start -0.15 -0.4)
			(end 0.15 -0.4)
			(stroke
				(width 0.15)
				(type solid)
			)
			(layer "B.SilkS")
		)
		(fp_line
			(start -0.15 0.4)
			(end 0.15 0.4)
			(stroke
				(width 0.15)
				(type solid)
			)
			(layer "B.SilkS")
		)
		(fp_rect
			(start -1.25 0.65)
			(end 1.25 -0.65)
			(stroke
				(width 0.05)
				(type solid)
			)
			(fill no)
			(layer "B.CrtYd")
		)
		(fp_rect
			(start -0.8 0.4)
			(end 0.8 -0.4)
			(stroke
				(width 0.15)
				(type solid)
			)
			(fill no)
			(layer "B.Fab")
		)
		(pad "1" smd roundrect
			(at -0.7 0)
			(size 0.8 1)
			(layers "B.Cu" "B.Mask" "B.Paste")
			(roundrect_rratio 0.2)
			(net 1 "GND")
			(pintype "passive")
		)
		(pad "2" smd roundrect
			(at 0.7 0)
			(size 0.8 1)
			(layers "B.Cu" "B.Mask" "B.Paste")
			(roundrect_rratio 0.2)
			(net 3 "VCC1V35")
			(pintype "passive")
		)
	)
	(footprint "antmicro-footprints:C_1210_3225Metric"
		(layer "B.Cu")
		(at 92.8 99.5 180)
		(descr "Capacitor SMD 1210")
		(tags "capacitor SMD 1210")
		(property "Reference" "C133"
			(at 5.4 0.6 0)
			(layer "B.SilkS")
			(effects
				(font
					(size 0.7 0.7)
					(thickness 0.15)
				)
				(justify left bottom mirror)
			)
		)
		(property "Value" "C_47u_1210"
			(at 0 -2.749 0)
			(layer "B.Fab")
			(effects
				(font
					(size 0.7 0.7)
					(thickness 0.15)
				)
				(justify left bottom mirror)
			)
		)
		(property "Datasheet" "https://www.kemet.com/en/us/capacitors/product/C1210C476K8RACTU.html"
			(at 0 0 180)
			(layer "F.Fab")
			(hide yes)
			(effects
				(font
					(size 1.27 1.27)
					(thickness 0.15)
				)
			)
		)
		(property "Description" "SMD Multilayer Ceramic Capacitor, 47 µF, 10 V, 1210 [3225 Metric], ± 10%, X7R, C Series KEMET"
			(at 0 0 180)
			(layer "F.Fab")
			(hide yes)
			(effects
				(font
					(size 1.27 1.27)
					(thickness 0.15)
				)
			)
		)
		(property "Author" "Antmicro"
			(at 185.6 199 0)
			(layer "B.Fab")
			(hide yes)
			(effects
				(font
					(size 1 1)
					(thickness 0.15)
				)
				(justify mirror)
			)
		)
		(property "Dielectric" ""
			(at 185.6 199 0)
			(layer "B.Fab")
			(hide yes)
			(effects
				(font
					(size 1 1)
					(thickness 0.15)
				)
				(justify mirror)
			)
		)
		(property "License" "Apache-2.0"
			(at 185.6 199 0)
			(layer "B.Fab")
			(hide yes)
			(effects
				(font
					(size 1 1)
					(thickness 0.15)
				)
				(justify mirror)
			)
		)
		(property "MPN" "C1210C476K8RACTU"
			(at 185.6 199 0)
			(layer "B.Fab")
			(hide yes)
			(effects
				(font
					(size 1 1)
					(thickness 0.15)
				)
				(justify mirror)
			)
		)
		(property "Manufacturer" "KEMET"
			(at 185.6 199 0)
			(layer "B.Fab")
			(hide yes)
			(effects
				(font
					(size 1 1)
					(thickness 0.15)
				)
				(justify mirror)
			)
		)
		(property "Public" "False"
			(at 185.6 199 0)
			(layer "B.Fab")
			(hide yes)
			(effects
				(font
					(size 1 1)
					(thickness 0.15)
				)
				(justify mirror)
			)
		)
		(property "Val" "47u"
			(at 185.6 199 0)
			(layer "B.Fab")
			(hide yes)
			(effects
				(font
					(size 1 1)
					(thickness 0.15)
				)
				(justify mirror)
			)
		)
		(property "Voltage" ""
			(at 185.6 199 0)
			(layer "B.Fab")
			(hide yes)
			(effects
				(font
					(size 1 1)
					(thickness 0.15)
				)
				(justify mirror)
			)
		)
		(sheetname "/FPGA power supply/")
		(sheetfile "fpga-power-supply.kicad_sch")
		(attr smd)
		(fp_line
			(start -0.3 1.39)
			(end 0.3 1.39)
			(stroke
				(width 0.15)
				(type solid)
			)
			(layer "B.SilkS")
		)
		(fp_line
			(start -0.3 -1.39)
			(end 0.3 -1.39)
			(stroke
				(width 0.15)
				(type solid)
			)
			(layer "B.SilkS")
		)
		(fp_rect
			(start -2.1 1.75)
			(end 2.1 -1.75)
			(stroke
				(width 0.05)
				(type solid)
			)
			(fill no)
			(layer "B.CrtYd")
		)
		(fp_rect
			(start -1.6 1.25)
			(end 1.6 -1.25)
			(stroke
				(width 0.15)
				(type solid)
			)
			(fill no)
			(layer "B.Fab")
		)
		(pad "1" smd rect
			(at -1.145 0 180)
			(size 1.52 3.05)
			(layers "B.Cu" "B.Mask" "B.Paste")
			(net 1 "GND")
			(pintype "passive")
		)
		(pad "2" smd rect
			(at 1.145 0 180)
			(size 1.52 3.05)
			(layers "B.Cu" "B.Mask" "B.Paste")
			(net 5 "VCC1V8")
			(pintype "passive")
		)
	)
	(footprint "antmicro-footprints:C_0603_1608Metric"
		(layer "B.Cu")
		(at 92.8 96.9 180)
		(descr "Capacitor SMD 0603")
		(tags "capacitor 0603")
		(property "Reference" "C137"
			(at 5.4 -0.2 0)
			(layer "B.SilkS")
			(effects
				(font
					(size 0.7 0.7)
					(thickness 0.15)
				)
				(justify left bottom mirror)
			)
		)
		(property "Value" "C_4u7_0603"
			(at 0 -1.6 0)
			(layer "B.Fab")
			(effects
				(font
					(size 0.7 0.7)
					(thickness 0.15)
				)
				(justify left bottom mirror)
			)
		)
		(property "Datasheet" "https://product.tdk.com/en/search/capacitor/ceramic/mlcc/info?part_no=C1608X5R1V475M080AC"
			(at 0 0 180)
			(layer "F.Fab")
			(hide yes)
			(effects
				(font
					(size 1.27 1.27)
					(thickness 0.15)
				)
			)
		)
		(property "Description" "SMD Multilayer Ceramic Capacitor, 4.7 µF, 35 V, 0603 [1608 Metric], ± 20%, X5R, C"
			(at 0 0 180)
			(layer "F.Fab")
			(hide yes)
			(effects
				(font
					(size 1.27 1.27)
					(thickness 0.15)
				)
			)
		)
		(property "Author" "Antmicro"
			(at 185.6 193.8 0)
			(layer "B.Fab")
			(hide yes)
			(effects
				(font
					(size 1 1)
					(thickness 0.15)
				)
				(justify mirror)
			)
		)
		(property "Dielectric" ""
			(at 185.6 193.8 0)
			(layer "B.Fab")
			(hide yes)
			(effects
				(font
					(size 1 1)
					(thickness 0.15)
				)
				(justify mirror)
			)
		)
		(property "License" "Apache-2.0"
			(at 185.6 193.8 0)
			(layer "B.Fab")
			(hide yes)
			(effects
				(font
					(size 1 1)
					(thickness 0.15)
				)
				(justify mirror)
			)
		)
		(property "MPN" "C1608X5R1V475M080AC"
			(at 185.6 193.8 0)
			(layer "B.Fab")
			(hide yes)
			(effects
				(font
					(size 1 1)
					(thickness 0.15)
				)
				(justify mirror)
			)
		)
		(property "Manufacturer" "TDK"
			(at 185.6 193.8 0)
			(layer "B.Fab")
			(hide yes)
			(effects
				(font
					(size 1 1)
					(thickness 0.15)
				)
				(justify mirror)
			)
		)
		(property "Val" "4u7"
			(at 185.6 193.8 0)
			(layer "B.Fab")
			(hide yes)
			(effects
				(font
					(size 1 1)
					(thickness 0.15)
				)
				(justify mirror)
			)
		)
		(property "Voltage" ""
			(at 185.6 193.8 0)
			(layer "B.Fab")
			(hide yes)
			(effects
				(font
					(size 1 1)
					(thickness 0.15)
				)
				(justify mirror)
			)
		)
		(sheetname "/FPGA power supply/")
		(sheetfile "fpga-power-supply.kicad_sch")
		(attr smd)
		(fp_line
			(start -0.15 0.4)
			(end 0.15 0.4)
			(stroke
				(width 0.15)
				(type solid)
			)
			(layer "B.SilkS")
		)
		(fp_line
			(start -0.15 -0.4)
			(end 0.15 -0.4)
			(stroke
				(width 0.15)
				(type solid)
			)
			(layer "B.SilkS")
		)
		(fp_rect
			(start -1.25 0.65)
			(end 1.25 -0.65)
			(stroke
				(width 0.05)
				(type solid)
			)
			(fill no)
			(layer "B.CrtYd")
		)
		(fp_rect
			(start -0.8 0.4)
			(end 0.8 -0.4)
			(stroke
				(width 0.15)
				(type solid)
			)
			(fill no)
			(layer "B.Fab")
		)
		(pad "1" smd roundrect
			(at -0.7 0 180)
			(size 0.8 1)
			(layers "B.Cu" "B.Mask" "B.Paste")
			(roundrect_rratio 0.2)
			(net 1 "GND")
			(pintype "passive")
		)
		(pad "2" smd roundrect
			(at 0.7 0 180)
			(size 0.8 1)
			(layers "B.Cu" "B.Mask" "B.Paste")
			(roundrect_rratio 0.2)
			(net 5 "VCC1V8")
			(pintype "passive")
		)
	)
	(footprint "antmicro-footprints:C_1210_3225Metric"
		(layer "B.Cu")
		(at 76.399 84.5)
		(descr "Capacitor SMD 1210")
		(tags "capacitor SMD 1210")
		(property "Reference" "C145"
			(at -1.399 -1.9 0)
			(layer "B.SilkS")
			(effects
				(font
					(size 0.7 0.7)
					(thickness 0.15)
				)
				(justify right bottom mirror)
			)
		)
		(property "Value" "C_100u_1210"
			(at 0 -2.749 0)
			(layer "B.Fab")
			(effects
				(font
					(size 0.7 0.7)
					(thickness 0.15)
				)
				(justify right bottom mirror)
			)
		)
		(property "Datasheet" "https://product.samsungsem.com/mlcc/CL32A107MQVNNN.do"
			(at 0 0 0)
			(layer "F.Fab")
			(hide yes)
			(effects
				(font
					(size 1.27 1.27)
					(thickness 0.15)
				)
			)
		)
		(property "Description" "SMD Multilayer Ceramic Capacitor, 100 µF, 6.3 V, 1210 [3225 Metric], ± 20%, X5R, CL"
			(at 0 0 0)
			(layer "F.Fab")
			(hide yes)
			(effects
				(font
					(size 1.27 1.27)
					(thickness 0.15)
				)
			)
		)
		(property "Author" "Antmicro"
			(at 0 0 0)
			(layer "B.Fab")
			(hide yes)
			(effects
				(font
					(size 1 1)
					(thickness 0.15)
				)
				(justify mirror)
			)
		)
		(property "Dielectric" ""
			(at 0 0 0)
			(layer "B.Fab")
			(hide yes)
			(effects
				(font
					(size 1 1)
					(thickness 0.15)
				)
				(justify mirror)
			)
		)
		(property "License" "Apache-2.0"
			(at 0 0 0)
			(layer "B.Fab")
			(hide yes)
			(effects
				(font
					(size 1 1)
					(thickness 0.15)
				)
				(justify mirror)
			)
		)
		(property "MPN" "CL32A107MQVNNNE"
			(at 0 0 0)
			(layer "B.Fab")
			(hide yes)
			(effects
				(font
					(size 1 1)
					(thickness 0.15)
				)
				(justify mirror)
			)
		)
		(property "Manufacturer" "Samsung Electro-Mechanics"
			(at 0 0 0)
			(layer "B.Fab")
			(hide yes)
			(effects
				(font
					(size 1 1)
					(thickness 0.15)
				)
				(justify mirror)
			)
		)
		(property "Public" "False"
			(at 0 0 0)
			(layer "B.Fab")
			(hide yes)
			(effects
				(font
					(size 1 1)
					(thickness 0.15)
				)
				(justify mirror)
			)
		)
		(property "Val" "100u"
			(at 0 0 0)
			(layer "B.Fab")
			(hide yes)
			(effects
				(font
					(size 1 1)
					(thickness 0.15)
				)
				(justify mirror)
			)
		)
		(property "Voltage" ""
			(at 0 0 0)
			(layer "B.Fab")
			(hide yes)
			(effects
				(font
					(size 1 1)
					(thickness 0.15)
				)
				(justify mirror)
			)
		)
		(property "DNP" ""
			(at 0 0 0)
			(unlocked yes)
			(layer "B.Fab")
			(hide yes)
			(effects
				(font
					(size 1 1)
					(thickness 0.15)
				)
				(justify mirror)
			)
		)
		(sheetname "/FPGA power supply/")
		(sheetfile "fpga-power-supply.kicad_sch")
		(attr smd)
		(fp_line
			(start -0.3 -1.39)
			(end 0.3 -1.39)
			(stroke
				(width 0.15)
				(type solid)
			)
			(layer "B.SilkS")
		)
		(fp_line
			(start -0.3 1.39)
			(end 0.3 1.39)
			(stroke
				(width 0.15)
				(type solid)
			)
			(layer "B.SilkS")
		)
		(fp_rect
			(start -2.1 1.75)
			(end 2.1 -1.75)
			(stroke
				(width 0.05)
				(type solid)
			)
			(fill no)
			(layer "B.CrtYd")
		)
		(fp_rect
			(start -1.6 1.25)
			(end 1.6 -1.25)
			(stroke
				(width 0.15)
				(type solid)
			)
			(fill no)
			(layer "B.Fab")
		)
		(pad "1" smd rect
			(at -1.145 0)
			(size 1.52 3.05)
			(layers "B.Cu" "B.Mask" "B.Paste")
			(net 1 "GND")
			(pintype "passive")
		)
		(pad "2" smd rect
			(at 1.145 0)
			(size 1.52 3.05)
			(layers "B.Cu" "B.Mask" "B.Paste")
			(net 6 "VCC1V0")
			(pintype "passive")
		)
	)
	(footprint "antmicro-footprints:R_0402_1005Metric"
		(layer "B.Cu")
		(at 81.986 80.3)
		(descr "Resistor SMD 0402")
		(tags "resistor SMD 0402")
		(property "Reference" "R61"
			(at -1.086 -0.558 0)
			(layer "B.SilkS")
			(effects
				(font
					(size 0.7 0.7)
					(thickness 0.15)
				)
				(justify right bottom mirror)
			)
		)
		(property "Value" "R_10k_0402"
			(at 0 -1.4 0)
			(layer "B.Fab")
			(effects
				(font
					(size 0.7 0.7)
					(thickness 0.15)
				)
				(justify right bottom mirror)
			)
		)
		(property "Datasheet" "https://www.bourns.com/docs/product-datasheets/cr.pdf"
			(at 0 0 0)
			(layer "F.Fab")
			(hide yes)
			(effects
				(font
					(size 1.27 1.27)
					(thickness 0.15)
				)
			)
		)
		(property "Description" "SMD Chip Resistor, 10 kohm, ± 1%, 62.5 mW, 0402 [1005 Metric], Thick Film, General Purpose"
			(at 0 0 0)
			(layer "F.Fab")
			(hide yes)
			(effects
				(font
					(size 1.27 1.27)
					(thickness 0.15)
				)
			)
		)
		(property "Author" "Antmicro"
			(at 0 0 0)
			(layer "B.Fab")
			(hide yes)
			(effects
				(font
					(size 1 1)
					(thickness 0.15)
				)
				(justify mirror)
			)
		)
		(property "License" "Apache-2.0"
			(at 0 0 0)
			(layer "B.Fab")
			(hide yes)
			(effects
				(font
					(size 1 1)
					(thickness 0.15)
				)
				(justify mirror)
			)
		)
		(property "MPN" "CR0402-FX-1002GLF"
			(at 0 0 0)
			(layer "B.Fab")
			(hide yes)
			(effects
				(font
					(size 1 1)
					(thickness 0.15)
				)
				(justify mirror)
			)
		)
		(property "Manufacturer" "Bourns"
			(at 0 0 0)
			(layer "B.Fab")
			(hide yes)
			(effects
				(font
					(size 1 1)
					(thickness 0.15)
				)
				(justify mirror)
			)
		)
		(property "Tolerance" "1%"
			(at 0 0 0)
			(layer "B.Fab")
			(hide yes)
			(effects
				(font
					(size 1 1)
					(thickness 0.15)
				)
				(justify mirror)
			)
		)
		(property "Val" "10k"
			(at 0 0 0)
			(layer "B.Fab")
			(hide yes)
			(effects
				(font
					(size 1 1)
					(thickness 0.15)
				)
				(justify mirror)
			)
		)
		(sheetname "/Power supply/")
		(sheetfile "power-supply.kicad_sch")
		(attr smd)
		(fp_rect
			(start -0.925 0.47)
			(end 0.925 -0.47)
			(stroke
				(width 0.05)
				(type default)
			)
			(fill no)
			(layer "B.CrtYd")
		)
		(fp_rect
			(start -0.5 0.25)
			(end 0.5 -0.25)
			(stroke
				(width 0.15)
				(type solid)
			)
			(fill no)
			(layer "B.Fab")
		)
		(pad "1" smd roundrect
			(at -0.48 0)
			(size 0.59 0.64)
			(layers "B.Cu" "B.Mask" "B.Paste")
			(roundrect_rratio 0.25)
			(net 2 "VCC3V3")
			(pintype "passive")
		)
		(pad "2" smd roundrect
			(at 0.48 0)
			(size 0.59 0.64)
			(layers "B.Cu" "B.Mask" "B.Paste")
			(roundrect_rratio 0.25)
			(net 538 "1V0_PG")
			(pintype "passive")
		)
	)
	(footprint "antmicro-footprints:R_0402_1005Metric"
		(layer "B.Cu")
		(at 81.875 94.9)
		(descr "Resistor SMD 0402")
		(tags "resistor SMD 0402")
		(property "Reference" "R91"
			(at -1.086 -0.558 0)
			(layer "B.SilkS")
			(effects
				(font
					(size 0.7 0.7)
					(thickness 0.15)
				)
				(justify right bottom mirror)
			)
		)
		(property "Value" "R_10k_0402"
			(at 0 -1.4 0)
			(layer "B.Fab")
			(effects
				(font
					(size 0.7 0.7)
					(thickness 0.15)
				)
				(justify right bottom mirror)
			)
		)
		(property "Datasheet" "https://www.bourns.com/docs/product-datasheets/cr.pdf"
			(at 0 0 0)
			(layer "F.Fab")
			(hide yes)
			(effects
				(font
					(size 1.27 1.27)
					(thickness 0.15)
				)
			)
		)
		(property "Description" "SMD Chip Resistor, 10 kohm, ± 1%, 62.5 mW, 0402 [1005 Metric], Thick Film, General Purpose"
			(at 0 0 0)
			(layer "F.Fab")
			(hide yes)
			(effects
				(font
					(size 1.27 1.27)
					(thickness 0.15)
				)
			)
		)
		(property "Author" "Antmicro"
			(at 0 0 0)
			(layer "B.Fab")
			(hide yes)
			(effects
				(font
					(size 1 1)
					(thickness 0.15)
				)
				(justify mirror)
			)
		)
		(property "License" "Apache-2.0"
			(at 0 0 0)
			(layer "B.Fab")
			(hide yes)
			(effects
				(font
					(size 1 1)
					(thickness 0.15)
				)
				(justify mirror)
			)
		)
		(property "MPN" "CR0402-FX-1002GLF"
			(at 0 0 0)
			(layer "B.Fab")
			(hide yes)
			(effects
				(font
					(size 1 1)
					(thickness 0.15)
				)
				(justify mirror)
			)
		)
		(property "Manufacturer" "Bourns"
			(at 0 0 0)
			(layer "B.Fab")
			(hide yes)
			(effects
				(font
					(size 1 1)
					(thickness 0.15)
				)
				(justify mirror)
			)
		)
		(property "Tolerance" "1%"
			(at 0 0 0)
			(layer "B.Fab")
			(hide yes)
			(effects
				(font
					(size 1 1)
					(thickness 0.15)
				)
				(justify mirror)
			)
		)
		(property "Val" "10k"
			(at 0 0 0)
			(layer "B.Fab")
			(hide yes)
			(effects
				(font
					(size 1 1)
					(thickness 0.15)
				)
				(justify mirror)
			)
		)
		(sheetname "/Power supply/")
		(sheetfile "power-supply.kicad_sch")
		(attr smd)
		(fp_rect
			(start -0.925 0.47)
			(end 0.925 -0.47)
			(stroke
				(width 0.05)
				(type default)
			)
			(fill no)
			(layer "B.CrtYd")
		)
		(fp_rect
			(start -0.5 0.25)
			(end 0.5 -0.25)
			(stroke
				(width 0.15)
				(type solid)
			)
			(fill no)
			(layer "B.Fab")
		)
		(pad "1" smd roundrect
			(at -0.48 0)
			(size 0.59 0.64)
			(layers "B.Cu" "B.Mask" "B.Paste")
			(roundrect_rratio 0.25)
			(net 4 "VCC5V0")
			(pintype "passive")
		)
		(pad "2" smd roundrect
			(at 0.48 0)
			(size 0.59 0.64)
			(layers "B.Cu" "B.Mask" "B.Paste")
			(roundrect_rratio 0.25)
			(net 292 "/Power supply/1V8_PG")
			(pintype "passive")
		)
	)
	(footprint "antmicro-footprints:R_0402_1005Metric"
		(layer "B.Cu")
		(at 81.986 87.5)
		(descr "Resistor SMD 0402")
		(tags "resistor SMD 0402")
		(property "Reference" "R92"
			(at -1.086 -0.558 0)
			(layer "B.SilkS")
			(effects
				(font
					(size 0.7 0.7)
					(thickness 0.15)
				)
				(justify right bottom mirror)
			)
		)
		(property "Value" "R_10k_0402"
			(at 0 -1.4 0)
			(layer "B.Fab")
			(effects
				(font
					(size 0.7 0.7)
					(thickness 0.15)
				)
				(justify right bottom mirror)
			)
		)
		(property "Datasheet" "https://www.bourns.com/docs/product-datasheets/cr.pdf"
			(at 0 0 0)
			(layer "F.Fab")
			(hide yes)
			(effects
				(font
					(size 1.27 1.27)
					(thickness 0.15)
				)
			)
		)
		(property "Description" "SMD Chip Resistor, 10 kohm, ± 1%, 62.5 mW, 0402 [1005 Metric], Thick Film, General Purpose"
			(at 0 0 0)
			(layer "F.Fab")
			(hide yes)
			(effects
				(font
					(size 1.27 1.27)
					(thickness 0.15)
				)
			)
		)
		(property "Author" "Antmicro"
			(at 0 0 0)
			(layer "B.Fab")
			(hide yes)
			(effects
				(font
					(size 1 1)
					(thickness 0.15)
				)
				(justify mirror)
			)
		)
		(property "License" "Apache-2.0"
			(at 0 0 0)
			(layer "B.Fab")
			(hide yes)
			(effects
				(font
					(size 1 1)
					(thickness 0.15)
				)
				(justify mirror)
			)
		)
		(property "MPN" "CR0402-FX-1002GLF"
			(at 0 0 0)
			(layer "B.Fab")
			(hide yes)
			(effects
				(font
					(size 1 1)
					(thickness 0.15)
				)
				(justify mirror)
			)
		)
		(property "Manufacturer" "Bourns"
			(at 0 0 0)
			(layer "B.Fab")
			(hide yes)
			(effects
				(font
					(size 1 1)
					(thickness 0.15)
				)
				(justify mirror)
			)
		)
		(property "Tolerance" "1%"
			(at 0 0 0)
			(layer "B.Fab")
			(hide yes)
			(effects
				(font
					(size 1 1)
					(thickness 0.15)
				)
				(justify mirror)
			)
		)
		(property "Val" "10k"
			(at 0 0 0)
			(layer "B.Fab")
			(hide yes)
			(effects
				(font
					(size 1 1)
					(thickness 0.15)
				)
				(justify mirror)
			)
		)
		(sheetname "/Power supply/")
		(sheetfile "power-supply.kicad_sch")
		(attr smd)
		(fp_rect
			(start -0.925 0.47)
			(end 0.925 -0.47)
			(stroke
				(width 0.05)
				(type default)
			)
			(fill no)
			(layer "B.CrtYd")
		)
		(fp_rect
			(start -0.5 0.25)
			(end 0.5 -0.25)
			(stroke
				(width 0.15)
				(type solid)
			)
			(fill no)
			(layer "B.Fab")
		)
		(pad "1" smd roundrect
			(at -0.48 0)
			(size 0.59 0.64)
			(layers "B.Cu" "B.Mask" "B.Paste")
			(roundrect_rratio 0.25)
			(net 4 "VCC5V0")
			(pintype "passive")
		)
		(pad "2" smd roundrect
			(at 0.48 0)
			(size 0.59 0.64)
			(layers "B.Cu" "B.Mask" "B.Paste")
			(roundrect_rratio 0.25)
			(net 293 "/Power supply/1V35_PG")
			(pintype "passive")
		)
	)
	(footprint "antmicro-footprints:R_0402_1005Metric"
		(layer "B.Cu")
		(at 81.963 102.2)
		(descr "Resistor SMD 0402")
		(tags "resistor SMD 0402")
		(property "Reference" "R93"
			(at -1.086 -0.558 0)
			(layer "B.SilkS")
			(effects
				(font
					(size 0.7 0.7)
					(thickness 0.15)
				)
				(justify right bottom mirror)
			)
		)
		(property "Value" "R_10k_0402"
			(at 0 -1.4 0)
			(layer "B.Fab")
			(effects
				(font
					(size 0.7 0.7)
					(thickness 0.15)
				)
				(justify right bottom mirror)
			)
		)
		(property "Datasheet" "https://www.bourns.com/docs/product-datasheets/cr.pdf"
			(at 0 0 0)
			(layer "F.Fab")
			(hide yes)
			(effects
				(font
					(size 1.27 1.27)
					(thickness 0.15)
				)
			)
		)
		(property "Description" "SMD Chip Resistor, 10 kohm, ± 1%, 62.5 mW, 0402 [1005 Metric], Thick Film, General Purpose"
			(at 0 0 0)
			(layer "F.Fab")
			(hide yes)
			(effects
				(font
					(size 1.27 1.27)
					(thickness 0.15)
				)
			)
		)
		(property "Author" "Antmicro"
			(at 0 0 0)
			(layer "B.Fab")
			(hide yes)
			(effects
				(font
					(size 1 1)
					(thickness 0.15)
				)
				(justify mirror)
			)
		)
		(property "License" "Apache-2.0"
			(at 0 0 0)
			(layer "B.Fab")
			(hide yes)
			(effects
				(font
					(size 1 1)
					(thickness 0.15)
				)
				(justify mirror)
			)
		)
		(property "MPN" "CR0402-FX-1002GLF"
			(at 0 0 0)
			(layer "B.Fab")
			(hide yes)
			(effects
				(font
					(size 1 1)
					(thickness 0.15)
				)
				(justify mirror)
			)
		)
		(property "Manufacturer" "Bourns"
			(at 0 0 0)
			(layer "B.Fab")
			(hide yes)
			(effects
				(font
					(size 1 1)
					(thickness 0.15)
				)
				(justify mirror)
			)
		)
		(property "Tolerance" "1%"
			(at 0 0 0)
			(layer "B.Fab")
			(hide yes)
			(effects
				(font
					(size 1 1)
					(thickness 0.15)
				)
				(justify mirror)
			)
		)
		(property "Val" "10k"
			(at 0 0 0)
			(layer "B.Fab")
			(hide yes)
			(effects
				(font
					(size 1 1)
					(thickness 0.15)
				)
				(justify mirror)
			)
		)
		(sheetname "/Power supply/")
		(sheetfile "power-supply.kicad_sch")
		(attr smd)
		(fp_rect
			(start -0.925 0.47)
			(end 0.925 -0.47)
			(stroke
				(width 0.05)
				(type default)
			)
			(fill no)
			(layer "B.CrtYd")
		)
		(fp_rect
			(start -0.5 0.25)
			(end 0.5 -0.25)
			(stroke
				(width 0.15)
				(type solid)
			)
			(fill no)
			(layer "B.Fab")
		)
		(pad "1" smd roundrect
			(at -0.48 0)
			(size 0.59 0.64)
			(layers "B.Cu" "B.Mask" "B.Paste")
			(roundrect_rratio 0.25)
			(net 4 "VCC5V0")
			(pintype "passive")
		)
		(pad "2" smd roundrect
			(at 0.48 0)
			(size 0.59 0.64)
			(layers "B.Cu" "B.Mask" "B.Paste")
			(roundrect_rratio 0.25)
			(net 294 "/Power supply/2V5_PG")
			(pintype "passive")
		)
	)
	(footprint "antmicro-footprints:C_1210_3225Metric"
		(layer "B.Cu")
		(at 114.4 137.9 180)
		(descr "Capacitor SMD 1210")
		(tags "capacitor SMD 1210")
		(property "Reference" "C178"
			(at 2.2 1.5 270)
			(layer "B.SilkS")
			(effects
				(font
					(size 0.7 0.7)
					(thickness 0.15)
				)
				(justify left bottom mirror)
			)
		)
		(property "Value" "C_47u_1210"
			(at 0 -2.749 0)
			(layer "B.Fab")
			(effects
				(font
					(size 0.7 0.7)
					(thickness 0.15)
				)
				(justify left bottom mirror)
			)
		)
		(property "Datasheet" "https://www.kemet.com/en/us/capacitors/product/C1210C476K8RACTU.html"
			(at 0 0 180)
			(layer "F.Fab")
			(hide yes)
			(effects
				(font
					(size 1.27 1.27)
					(thickness 0.15)
				)
			)
		)
		(property "Description" "SMD Multilayer Ceramic Capacitor, 47 µF, 10 V, 1210 [3225 Metric], ± 10%, X7R, C Series KEMET"
			(at 0 0 180)
			(layer "F.Fab")
			(hide yes)
			(effects
				(font
					(size 1.27 1.27)
					(thickness 0.15)
				)
			)
		)
		(property "Author" "Antmicro"
			(at 228.8 275.8 0)
			(layer "B.Fab")
			(hide yes)
			(effects
				(font
					(size 1 1)
					(thickness 0.15)
				)
				(justify mirror)
			)
		)
		(property "Dielectric" ""
			(at 228.8 275.8 0)
			(layer "B.Fab")
			(hide yes)
			(effects
				(font
					(size 1 1)
					(thickness 0.15)
				)
				(justify mirror)
			)
		)
		(property "License" "Apache-2.0"
			(at 228.8 275.8 0)
			(layer "B.Fab")
			(hide yes)
			(effects
				(font
					(size 1 1)
					(thickness 0.15)
				)
				(justify mirror)
			)
		)
		(property "MPN" "C1210C476K8RACTU"
			(at 228.8 275.8 0)
			(layer "B.Fab")
			(hide yes)
			(effects
				(font
					(size 1 1)
					(thickness 0.15)
				)
				(justify mirror)
			)
		)
		(property "Manufacturer" "KEMET"
			(at 228.8 275.8 0)
			(layer "B.Fab")
			(hide yes)
			(effects
				(font
					(size 1 1)
					(thickness 0.15)
				)
				(justify mirror)
			)
		)
		(property "Public" "False"
			(at 228.8 275.8 0)
			(layer "B.Fab")
			(hide yes)
			(effects
				(font
					(size 1 1)
					(thickness 0.15)
				)
				(justify mirror)
			)
		)
		(property "Val" "47u"
			(at 228.8 275.8 0)
			(layer "B.Fab")
			(hide yes)
			(effects
				(font
					(size 1 1)
					(thickness 0.15)
				)
				(justify mirror)
			)
		)
		(property "Voltage" ""
			(at 228.8 275.8 0)
			(layer "B.Fab")
			(hide yes)
			(effects
				(font
					(size 1 1)
					(thickness 0.15)
				)
				(justify mirror)
			)
		)
		(sheetname "/FPGA banks 34-35 & CFG/")
		(sheetfile "fpga-banks-34-25-cfg.kicad_sch")
		(attr smd)
		(fp_line
			(start -0.3 1.39)
			(end 0.3 1.39)
			(stroke
				(width 0.15)
				(type solid)
			)
			(layer "B.SilkS")
		)
		(fp_line
			(start -0.3 -1.39)
			(end 0.3 -1.39)
			(stroke
				(width 0.15)
				(type solid)
			)
			(layer "B.SilkS")
		)
		(fp_rect
			(start -2.1 1.75)
			(end 2.1 -1.75)
			(stroke
				(width 0.05)
				(type solid)
			)
			(fill no)
			(layer "B.CrtYd")
		)
		(fp_rect
			(start -1.6 1.25)
			(end 1.6 -1.25)
			(stroke
				(width 0.15)
				(type solid)
			)
			(fill no)
			(layer "B.Fab")
		)
		(pad "1" smd rect
			(at -1.145 0 180)
			(size 1.52 3.05)
			(layers "B.Cu" "B.Mask" "B.Paste")
			(net 1 "GND")
			(pintype "passive")
		)
		(pad "2" smd rect
			(at 1.145 0 180)
			(size 1.52 3.05)
			(layers "B.Cu" "B.Mask" "B.Paste")
			(net 2 "VCC3V3")
			(pintype "passive")
		)
	)
	(footprint "antmicro-footprints:R_0402_1005Metric"
		(layer "B.Cu")
		(at 73.575 155.775)
		(descr "Resistor SMD 0402")
		(tags "resistor SMD 0402")
		(property "Reference" "R86"
			(at -1.175 -0.575 0)
			(layer "B.SilkS")
			(effects
				(font
					(size 0.7 0.7)
					(thickness 0.15)
				)
				(justify right bottom mirror)
			)
		)
		(property "Value" "R_100R_0402"
			(at 0 -1.4 0)
			(layer "B.Fab")
			(effects
				(font
					(size 0.7 0.7)
					(thickness 0.15)
				)
				(justify right bottom mirror)
			)
		)
		(property "Datasheet" "https://www.bourns.com/docs/product-datasheets/cr.pdf"
			(at 0 0 0)
			(layer "F.Fab")
			(hide yes)
			(effects
				(font
					(size 1.27 1.27)
					(thickness 0.15)
				)
			)
		)
		(property "Description" "SMD Chip Resistor, 100 ohm, ± 1%, 62.5 mW, 0402 [1005 Metric], Thick Film, General Purpose"
			(at 0 0 0)
			(layer "F.Fab")
			(hide yes)
			(effects
				(font
					(size 1.27 1.27)
					(thickness 0.15)
				)
			)
		)
		(property "Author" "Antmicro"
			(at 0 0 0)
			(layer "B.Fab")
			(hide yes)
			(effects
				(font
					(size 1 1)
					(thickness 0.15)
				)
				(justify mirror)
			)
		)
		(property "License" "Apache-2.0"
			(at 0 0 0)
			(layer "B.Fab")
			(hide yes)
			(effects
				(font
					(size 1 1)
					(thickness 0.15)
				)
				(justify mirror)
			)
		)
		(property "MPN" "CR0402-FX-1000GLF"
			(at 0 0 0)
			(layer "B.Fab")
			(hide yes)
			(effects
				(font
					(size 1 1)
					(thickness 0.15)
				)
				(justify mirror)
			)
		)
		(property "Manufacturer" "Bourns"
			(at 0 0 0)
			(layer "B.Fab")
			(hide yes)
			(effects
				(font
					(size 1 1)
					(thickness 0.15)
				)
				(justify mirror)
			)
		)
		(property "Tolerance" "1%"
			(at 0 0 0)
			(layer "B.Fab")
			(hide yes)
			(effects
				(font
					(size 1 1)
					(thickness 0.15)
				)
				(justify mirror)
			)
		)
		(property "Val" "100R"
			(at 0 0 0)
			(layer "B.Fab")
			(hide yes)
			(effects
				(font
					(size 1 1)
					(thickness 0.15)
				)
				(justify mirror)
			)
		)
		(property "DNP" ""
			(at 0 0 0)
			(unlocked yes)
			(layer "B.Fab")
			(hide yes)
			(effects
				(font
					(size 1 1)
					(thickness 0.15)
				)
				(justify mirror)
			)
		)
		(sheetname "/FPGA banks 34-35 & CFG/")
		(sheetfile "fpga-banks-34-25-cfg.kicad_sch")
		(attr smd)
		(fp_rect
			(start -0.925 0.47)
			(end 0.925 -0.47)
			(stroke
				(width 0.05)
				(type default)
			)
			(fill no)
			(layer "B.CrtYd")
		)
		(fp_rect
			(start -0.5 0.25)
			(end 0.5 -0.25)
			(stroke
				(width 0.15)
				(type solid)
			)
			(fill no)
			(layer "B.Fab")
		)
		(pad "1" smd roundrect
			(at -0.48 0)
			(size 0.59 0.64)
			(layers "B.Cu" "B.Mask" "B.Paste")
			(roundrect_rratio 0.25)
			(net 2 "VCC3V3")
			(pintype "passive")
		)
		(pad "2" smd roundrect
			(at 0.48 0)
			(size 0.59 0.64)
			(layers "B.Cu" "B.Mask" "B.Paste")
			(roundrect_rratio 0.25)
			(net 320 "ROT_QSPI_SCK")
			(pintype "passive")
		)
	)
	(footprint "antmicro-footprints:R_0402_1005Metric"
		(layer "B.Cu")
		(at 75.075 155.275 90)
		(descr "Resistor SMD 0402")
		(tags "resistor SMD 0402")
		(property "Reference" "R87"
			(at 0.775 0.425 90)
			(layer "B.SilkS")
			(effects
				(font
					(size 0.7 0.7)
					(thickness 0.15)
				)
				(justify right bottom mirror)
			)
		)
		(property "Value" "R_100R_0402"
			(at 0 -1.4 90)
			(layer "B.Fab")
			(effects
				(font
					(size 0.7 0.7)
					(thickness 0.15)
				)
				(justify right bottom mirror)
			)
		)
		(property "Datasheet" "https://www.bourns.com/docs/product-datasheets/cr.pdf"
			(at 0 0 90)
			(layer "F.Fab")
			(hide yes)
			(effects
				(font
					(size 1.27 1.27)
					(thickness 0.15)
				)
			)
		)
		(property "Description" "SMD Chip Resistor, 100 ohm, ± 1%, 62.5 mW, 0402 [1005 Metric], Thick Film, General Purpose"
			(at 0 0 90)
			(layer "F.Fab")
			(hide yes)
			(effects
				(font
					(size 1.27 1.27)
					(thickness 0.15)
				)
			)
		)
		(property "Author" "Antmicro"
			(at 230.35 80.2 0)
			(layer "B.Fab")
			(hide yes)
			(effects
				(font
					(size 1 1)
					(thickness 0.15)
				)
				(justify mirror)
			)
		)
		(property "License" "Apache-2.0"
			(at 230.35 80.2 0)
			(layer "B.Fab")
			(hide yes)
			(effects
				(font
					(size 1 1)
					(thickness 0.15)
				)
				(justify mirror)
			)
		)
		(property "MPN" "CR0402-FX-1000GLF"
			(at 230.35 80.2 0)
			(layer "B.Fab")
			(hide yes)
			(effects
				(font
					(size 1 1)
					(thickness 0.15)
				)
				(justify mirror)
			)
		)
		(property "Manufacturer" "Bourns"
			(at 230.35 80.2 0)
			(layer "B.Fab")
			(hide yes)
			(effects
				(font
					(size 1 1)
					(thickness 0.15)
				)
				(justify mirror)
			)
		)
		(property "Tolerance" "1%"
			(at 230.35 80.2 0)
			(layer "B.Fab")
			(hide yes)
			(effects
				(font
					(size 1 1)
					(thickness 0.15)
				)
				(justify mirror)
			)
		)
		(property "Val" "100R"
			(at 230.35 80.2 0)
			(layer "B.Fab")
			(hide yes)
			(effects
				(font
					(size 1 1)
					(thickness 0.15)
				)
				(justify mirror)
			)
		)
		(property "DNP" ""
			(at 0 0 90)
			(unlocked yes)
			(layer "B.Fab")
			(hide yes)
			(effects
				(font
					(size 1 1)
					(thickness 0.15)
				)
				(justify mirror)
			)
		)
		(sheetname "/FPGA banks 34-35 & CFG/")
		(sheetfile "fpga-banks-34-25-cfg.kicad_sch")
		(attr smd)
		(fp_rect
			(start -0.925 0.47)
			(end 0.925 -0.47)
			(stroke
				(width 0.05)
				(type default)
			)
			(fill no)
			(layer "B.CrtYd")
		)
		(fp_rect
			(start -0.5 0.25)
			(end 0.5 -0.25)
			(stroke
				(width 0.15)
				(type solid)
			)
			(fill no)
			(layer "B.Fab")
		)
		(pad "1" smd roundrect
			(at -0.48 0 90)
			(size 0.59 0.64)
			(layers "B.Cu" "B.Mask" "B.Paste")
			(roundrect_rratio 0.25)
			(net 320 "ROT_QSPI_SCK")
			(pintype "passive")
		)
		(pad "2" smd roundrect
			(at 0.48 0 90)
			(size 0.59 0.64)
			(layers "B.Cu" "B.Mask" "B.Paste")
			(roundrect_rratio 0.25)
			(net 1 "GND")
			(pintype "passive")
		)
	)
	(footprint "antmicro-footprints:R_0402_1005Metric"
		(layer "B.Cu")
		(at 91.975 157.875 180)
		(descr "Resistor SMD 0402")
		(tags "resistor SMD 0402")
		(property "Reference" "R89"
			(at 0.775 -0.325 0)
			(layer "B.SilkS")
			(effects
				(font
					(size 0.7 0.7)
					(thickness 0.15)
				)
				(justify left bottom mirror)
			)
		)
		(property "Value" "R_4k7_0402"
			(at 0 -1.4 0)
			(layer "B.Fab")
			(effects
				(font
					(size 0.7 0.7)
					(thickness 0.15)
				)
				(justify left bottom mirror)
			)
		)
		(property "Datasheet" "https://www.bourns.com/docs/product-datasheets/cr.pdf"
			(at 0 0 180)
			(layer "F.Fab")
			(hide yes)
			(effects
				(font
					(size 1.27 1.27)
					(thickness 0.15)
				)
			)
		)
		(property "Description" "SMD Chip Resistor, 4.7 kohm, ± 1%, 62.5 mW, 0402 [1005 Metric], Thick Film, General Purpose"
			(at 0 0 180)
			(layer "F.Fab")
			(hide yes)
			(effects
				(font
					(size 1.27 1.27)
					(thickness 0.15)
				)
			)
		)
		(property "Author" "Antmicro"
			(at 183.95 315.75 0)
			(layer "B.Fab")
			(hide yes)
			(effects
				(font
					(size 1 1)
					(thickness 0.15)
				)
				(justify mirror)
			)
		)
		(property "License" "Apache-2.0"
			(at 183.95 315.75 0)
			(layer "B.Fab")
			(hide yes)
			(effects
				(font
					(size 1 1)
					(thickness 0.15)
				)
				(justify mirror)
			)
		)
		(property "MPN" "CR0402-FX-4701GLF"
			(at 183.95 315.75 0)
			(layer "B.Fab")
			(hide yes)
			(effects
				(font
					(size 1 1)
					(thickness 0.15)
				)
				(justify mirror)
			)
		)
		(property "Manufacturer" "Bourns"
			(at 183.95 315.75 0)
			(layer "B.Fab")
			(hide yes)
			(effects
				(font
					(size 1 1)
					(thickness 0.15)
				)
				(justify mirror)
			)
		)
		(property "Tolerance" "1%"
			(at 183.95 315.75 0)
			(layer "B.Fab")
			(hide yes)
			(effects
				(font
					(size 1 1)
					(thickness 0.15)
				)
				(justify mirror)
			)
		)
		(property "Val" "4k7"
			(at 183.95 315.75 0)
			(layer "B.Fab")
			(hide yes)
			(effects
				(font
					(size 1 1)
					(thickness 0.15)
				)
				(justify mirror)
			)
		)
		(sheetname "/FPGA banks 34-35 & CFG/")
		(sheetfile "fpga-banks-34-25-cfg.kicad_sch")
		(attr smd)
		(fp_rect
			(start -0.925 0.47)
			(end 0.925 -0.47)
			(stroke
				(width 0.05)
				(type default)
			)
			(fill no)
			(layer "B.CrtYd")
		)
		(fp_rect
			(start -0.5 0.25)
			(end 0.5 -0.25)
			(stroke
				(width 0.15)
				(type solid)
			)
			(fill no)
			(layer "B.Fab")
		)
		(pad "1" smd roundrect
			(at -0.48 0 180)
			(size 0.59 0.64)
			(layers "B.Cu" "B.Mask" "B.Paste")
			(roundrect_rratio 0.25)
			(net 2 "VCC3V3")
			(pintype "passive")
		)
		(pad "2" smd roundrect
			(at 0.48 0 180)
			(size 0.59 0.64)
			(layers "B.Cu" "B.Mask" "B.Paste")
			(roundrect_rratio 0.25)
			(net 221 "PROGRAM")
			(pintype "passive")
		)
	)
	(footprint "antmicro-footprints:R_0402_1005Metric"
		(layer "B.Cu")
		(at 91.975 159.875 180)
		(descr "Resistor SMD 0402")
		(tags "resistor SMD 0402")
		(property "Reference" "R90"
			(at 0.775 -0.325 0)
			(layer "B.SilkS")
			(effects
				(font
					(size 0.7 0.7)
					(thickness 0.15)
				)
				(justify left bottom mirror)
			)
		)
		(property "Value" "R_4k7_0402"
			(at 0 -1.4 0)
			(layer "B.Fab")
			(effects
				(font
					(size 0.7 0.7)
					(thickness 0.15)
				)
				(justify left bottom mirror)
			)
		)
		(property "Datasheet" "https://www.bourns.com/docs/product-datasheets/cr.pdf"
			(at 0 0 180)
			(layer "F.Fab")
			(hide yes)
			(effects
				(font
					(size 1.27 1.27)
					(thickness 0.15)
				)
			)
		)
		(property "Description" "SMD Chip Resistor, 4.7 kohm, ± 1%, 62.5 mW, 0402 [1005 Metric], Thick Film, General Purpose"
			(at 0 0 180)
			(layer "F.Fab")
			(hide yes)
			(effects
				(font
					(size 1.27 1.27)
					(thickness 0.15)
				)
			)
		)
		(property "Author" "Antmicro"
			(at 183.95 319.75 0)
			(layer "B.Fab")
			(hide yes)
			(effects
				(font
					(size 1 1)
					(thickness 0.15)
				)
				(justify mirror)
			)
		)
		(property "License" "Apache-2.0"
			(at 183.95 319.75 0)
			(layer "B.Fab")
			(hide yes)
			(effects
				(font
					(size 1 1)
					(thickness 0.15)
				)
				(justify mirror)
			)
		)
		(property "MPN" "CR0402-FX-4701GLF"
			(at 183.95 319.75 0)
			(layer "B.Fab")
			(hide yes)
			(effects
				(font
					(size 1 1)
					(thickness 0.15)
				)
				(justify mirror)
			)
		)
		(property "Manufacturer" "Bourns"
			(at 183.95 319.75 0)
			(layer "B.Fab")
			(hide yes)
			(effects
				(font
					(size 1 1)
					(thickness 0.15)
				)
				(justify mirror)
			)
		)
		(property "Tolerance" "1%"
			(at 183.95 319.75 0)
			(layer "B.Fab")
			(hide yes)
			(effects
				(font
					(size 1 1)
					(thickness 0.15)
				)
				(justify mirror)
			)
		)
		(property "Val" "4k7"
			(at 183.95 319.75 0)
			(layer "B.Fab")
			(hide yes)
			(effects
				(font
					(size 1 1)
					(thickness 0.15)
				)
				(justify mirror)
			)
		)
		(sheetname "/FPGA banks 34-35 & CFG/")
		(sheetfile "fpga-banks-34-25-cfg.kicad_sch")
		(attr smd)
		(fp_rect
			(start -0.925 0.47)
			(end 0.925 -0.47)
			(stroke
				(width 0.05)
				(type default)
			)
			(fill no)
			(layer "B.CrtYd")
		)
		(fp_rect
			(start -0.5 0.25)
			(end 0.5 -0.25)
			(stroke
				(width 0.15)
				(type solid)
			)
			(fill no)
			(layer "B.Fab")
		)
		(pad "1" smd roundrect
			(at -0.48 0 180)
			(size 0.59 0.64)
			(layers "B.Cu" "B.Mask" "B.Paste")
			(roundrect_rratio 0.25)
			(net 2 "VCC3V3")
			(pintype "passive")
		)
		(pad "2" smd roundrect
			(at 0.48 0 180)
			(size 0.59 0.64)
			(layers "B.Cu" "B.Mask" "B.Paste")
			(roundrect_rratio 0.25)
			(net 222 "INIT")
			(pintype "passive")
		)
	)
	(footprint "antmicro-footprints:C_0402_1005Metric"
		(layer "B.Cu")
		(at 96.075 150.675 90)
		(descr "Capacitor SMD 0402")
		(tags "capacitor SMD 0402")
		(property "Reference" "C43"
			(at -2.925 0.425 90)
			(layer "B.SilkS")
			(effects
				(font
					(size 0.7 0.7)
					(thickness 0.15)
				)
				(justify right bottom mirror)
			)
		)
		(property "Value" "C_10u_0402"
			(at 0 -1.4 90)
			(layer "B.Fab")
			(effects
				(font
					(size 0.7 0.7)
					(thickness 0.15)
				)
				(justify right bottom mirror)
			)
		)
		(property "Datasheet" "https://www.yageo.com/en/Chart/Download/pdf/CC0402MRX5R5BB106"
			(at 0 0 90)
			(layer "F.Fab")
			(hide yes)
			(effects
				(font
					(size 1.27 1.27)
					(thickness 0.15)
				)
			)
		)
		(property "Description" "SMD Multilayer Ceramic Capacitor, 10 µF, 6.3 V, 0402 [1005 Metric], ± 20%, X5R, CC Series"
			(at 0 0 90)
			(layer "F.Fab")
			(hide yes)
			(effects
				(font
					(size 1.27 1.27)
					(thickness 0.15)
				)
			)
		)
		(property "Author" "Antmicro"
			(at 246.75 54.6 0)
			(layer "B.Fab")
			(hide yes)
			(effects
				(font
					(size 1 1)
					(thickness 0.15)
				)
				(justify mirror)
			)
		)
		(property "Dielectric" ""
			(at 246.75 54.6 0)
			(layer "B.Fab")
			(hide yes)
			(effects
				(font
					(size 1 1)
					(thickness 0.15)
				)
				(justify mirror)
			)
		)
		(property "License" "Apache-2.0"
			(at 246.75 54.6 0)
			(layer "B.Fab")
			(hide yes)
			(effects
				(font
					(size 1 1)
					(thickness 0.15)
				)
				(justify mirror)
			)
		)
		(property "MPN" "CC0402MRX5R5BB106"
			(at 246.75 54.6 0)
			(layer "B.Fab")
			(hide yes)
			(effects
				(font
					(size 1 1)
					(thickness 0.15)
				)
				(justify mirror)
			)
		)
		(property "Manufacturer" "YAGEO"
			(at 246.75 54.6 0)
			(layer "B.Fab")
			(hide yes)
			(effects
				(font
					(size 1 1)
					(thickness 0.15)
				)
				(justify mirror)
			)
		)
		(property "Val" "10u"
			(at 246.75 54.6 0)
			(layer "B.Fab")
			(hide yes)
			(effects
				(font
					(size 1 1)
					(thickness 0.15)
				)
				(justify mirror)
			)
		)
		(property "Voltage" ""
			(at 246.75 54.6 0)
			(layer "B.Fab")
			(hide yes)
			(effects
				(font
					(size 1 1)
					(thickness 0.15)
				)
				(justify mirror)
			)
		)
		(sheetname "/DDR3/")
		(sheetfile "ddr3.kicad_sch")
		(attr smd)
		(fp_rect
			(start -0.925 0.47)
			(end 0.925 -0.47)
			(stroke
				(width 0.05)
				(type default)
			)
			(fill no)
			(layer "B.CrtYd")
		)
		(fp_line
			(start 0.504 -0.248)
			(end -0.494 -0.248)
			(stroke
				(width 0.15)
				(type solid)
			)
			(layer "B.Fab")
		)
		(fp_line
			(start -0.494 -0.248)
			(end -0.494 0.25)
			(stroke
				(width 0.15)
				(type solid)
			)
			(layer "B.Fab")
		)
		(fp_line
			(start 0.504 0.25)
			(end 0.504 -0.248)
			(stroke
				(width 0.15)
				(type solid)
			)
			(layer "B.Fab")
		)
		(fp_line
			(start -0.494 0.25)
			(end 0.504 0.25)
			(stroke
				(width 0.15)
				(type solid)
			)
			(layer "B.Fab")
		)
		(pad "1" smd roundrect
			(at -0.48 0 90)
			(size 0.59 0.64)
			(layers "B.Cu" "B.Mask" "B.Paste")
			(roundrect_rratio 0.25)
			(net 1 "GND")
			(pintype "passive")
		)
		(pad "2" smd roundrect
			(at 0.48 0 90)
			(size 0.59 0.64)
			(layers "B.Cu" "B.Mask" "B.Paste")
			(roundrect_rratio 0.25)
			(net 143 "/DDR3/DDR3_VTT")
			(pintype "passive")
		)
	)
	(footprint "antmicro-footprints:C_1210_3225Metric"
		(layer "B.Cu")
		(at 88.7 133.6 90)
		(descr "Capacitor SMD 1210")
		(tags "capacitor SMD 1210")
		(property "Reference" "C91"
			(at 2.1 -1.2 180)
			(layer "B.SilkS")
			(effects
				(font
					(size 0.7 0.7)
					(thickness 0.15)
				)
				(justify right bottom mirror)
			)
		)
		(property "Value" "C_47u_1210"
			(at 0 -2.749 90)
			(layer "B.Fab")
			(effects
				(font
					(size 0.7 0.7)
					(thickness 0.15)
				)
				(justify right bottom mirror)
			)
		)
		(property "Datasheet" "https://www.kemet.com/en/us/capacitors/product/C1210C476K8RACTU.html"
			(at 0 0 90)
			(layer "F.Fab")
			(hide yes)
			(effects
				(font
					(size 1.27 1.27)
					(thickness 0.15)
				)
			)
		)
		(property "Description" "SMD Multilayer Ceramic Capacitor, 47 µF, 10 V, 1210 [3225 Metric], ± 10%, X7R, C Series KEMET"
			(at 0 0 90)
			(layer "F.Fab")
			(hide yes)
			(effects
				(font
					(size 1.27 1.27)
					(thickness 0.15)
				)
			)
		)
		(property "Author" "Antmicro"
			(at 222.3 44.9 0)
			(layer "B.Fab")
			(hide yes)
			(effects
				(font
					(size 1 1)
					(thickness 0.15)
				)
				(justify mirror)
			)
		)
		(property "Dielectric" ""
			(at 222.3 44.9 0)
			(layer "B.Fab")
			(hide yes)
			(effects
				(font
					(size 1 1)
					(thickness 0.15)
				)
				(justify mirror)
			)
		)
		(property "License" "Apache-2.0"
			(at 222.3 44.9 0)
			(layer "B.Fab")
			(hide yes)
			(effects
				(font
					(size 1 1)
					(thickness 0.15)
				)
				(justify mirror)
			)
		)
		(property "MPN" "C1210C476K8RACTU"
			(at 222.3 44.9 0)
			(layer "B.Fab")
			(hide yes)
			(effects
				(font
					(size 1 1)
					(thickness 0.15)
				)
				(justify mirror)
			)
		)
		(property "Manufacturer" "KEMET"
			(at 222.3 44.9 0)
			(layer "B.Fab")
			(hide yes)
			(effects
				(font
					(size 1 1)
					(thickness 0.15)
				)
				(justify mirror)
			)
		)
		(property "Public" "False"
			(at 222.3 44.9 0)
			(layer "B.Fab")
			(hide yes)
			(effects
				(font
					(size 1 1)
					(thickness 0.15)
				)
				(justify mirror)
			)
		)
		(property "Val" "47u"
			(at 222.3 44.9 0)
			(layer "B.Fab")
			(hide yes)
			(effects
				(font
					(size 1 1)
					(thickness 0.15)
				)
				(justify mirror)
			)
		)
		(property "Voltage" ""
			(at 222.3 44.9 0)
			(layer "B.Fab")
			(hide yes)
			(effects
				(font
					(size 1 1)
					(thickness 0.15)
				)
				(justify mirror)
			)
		)
		(sheetname "/FPGA banks 34-35 & CFG/")
		(sheetfile "fpga-banks-34-25-cfg.kicad_sch")
		(attr smd)
		(fp_line
			(start -0.3 -1.39)
			(end 0.3 -1.39)
			(stroke
				(width 0.15)
				(type solid)
			)
			(layer "B.SilkS")
		)
		(fp_line
			(start -0.3 1.39)
			(end 0.3 1.39)
			(stroke
				(width 0.15)
				(type solid)
			)
			(layer "B.SilkS")
		)
		(fp_rect
			(start -2.1 1.75)
			(end 2.1 -1.75)
			(stroke
				(width 0.05)
				(type solid)
			)
			(fill no)
			(layer "B.CrtYd")
		)
		(fp_rect
			(start -1.6 1.25)
			(end 1.6 -1.25)
			(stroke
				(width 0.15)
				(type solid)
			)
			(fill no)
			(layer "B.Fab")
		)
		(pad "1" smd rect
			(at -1.145 0 90)
			(size 1.52 3.05)
			(layers "B.Cu" "B.Mask" "B.Paste")
			(net 1 "GND")
			(pintype "passive")
		)
		(pad "2" smd rect
			(at 1.145 0 90)
			(size 1.52 3.05)
			(layers "B.Cu" "B.Mask" "B.Paste")
			(net 2 "VCC3V3")
			(pintype "passive")
		)
	)
	(footprint "antmicro-footprints:C_1210_3225Metric"
		(layer "B.Cu")
		(at 114.4 134.1 180)
		(descr "Capacitor SMD 1210")
		(tags "capacitor SMD 1210")
		(property "Reference" "C94"
			(at 2.2 1.1 270)
			(layer "B.SilkS")
			(effects
				(font
					(size 0.7 0.7)
					(thickness 0.15)
				)
				(justify left bottom mirror)
			)
		)
		(property "Value" "C_47u_1210"
			(at 0 -2.749 0)
			(layer "B.Fab")
			(effects
				(font
					(size 0.7 0.7)
					(thickness 0.15)
				)
				(justify left bottom mirror)
			)
		)
		(property "Datasheet" "https://www.kemet.com/en/us/capacitors/product/C1210C476K8RACTU.html"
			(at 0 0 180)
			(layer "F.Fab")
			(hide yes)
			(effects
				(font
					(size 1.27 1.27)
					(thickness 0.15)
				)
			)
		)
		(property "Description" "SMD Multilayer Ceramic Capacitor, 47 µF, 10 V, 1210 [3225 Metric], ± 10%, X7R, C Series KEMET"
			(at 0 0 180)
			(layer "F.Fab")
			(hide yes)
			(effects
				(font
					(size 1.27 1.27)
					(thickness 0.15)
				)
			)
		)
		(property "Author" "Antmicro"
			(at 228.8 268.2 0)
			(layer "B.Fab")
			(hide yes)
			(effects
				(font
					(size 1 1)
					(thickness 0.15)
				)
				(justify mirror)
			)
		)
		(property "Dielectric" ""
			(at 228.8 268.2 0)
			(layer "B.Fab")
			(hide yes)
			(effects
				(font
					(size 1 1)
					(thickness 0.15)
				)
				(justify mirror)
			)
		)
		(property "License" "Apache-2.0"
			(at 228.8 268.2 0)
			(layer "B.Fab")
			(hide yes)
			(effects
				(font
					(size 1 1)
					(thickness 0.15)
				)
				(justify mirror)
			)
		)
		(property "MPN" "C1210C476K8RACTU"
			(at 228.8 268.2 0)
			(layer "B.Fab")
			(hide yes)
			(effects
				(font
					(size 1 1)
					(thickness 0.15)
				)
				(justify mirror)
			)
		)
		(property "Manufacturer" "KEMET"
			(at 228.8 268.2 0)
			(layer "B.Fab")
			(hide yes)
			(effects
				(font
					(size 1 1)
					(thickness 0.15)
				)
				(justify mirror)
			)
		)
		(property "Public" "False"
			(at 228.8 268.2 0)
			(layer "B.Fab")
			(hide yes)
			(effects
				(font
					(size 1 1)
					(thickness 0.15)
				)
				(justify mirror)
			)
		)
		(property "Val" "47u"
			(at 228.8 268.2 0)
			(layer "B.Fab")
			(hide yes)
			(effects
				(font
					(size 1 1)
					(thickness 0.15)
				)
				(justify mirror)
			)
		)
		(property "Voltage" ""
			(at 228.8 268.2 0)
			(layer "B.Fab")
			(hide yes)
			(effects
				(font
					(size 1 1)
					(thickness 0.15)
				)
				(justify mirror)
			)
		)
		(sheetname "/FPGA banks 13-16/")
		(sheetfile "fpga-banks-13-16.kicad_sch")
		(attr smd)
		(fp_line
			(start -0.3 1.39)
			(end 0.3 1.39)
			(stroke
				(width 0.15)
				(type solid)
			)
			(layer "B.SilkS")
		)
		(fp_line
			(start -0.3 -1.39)
			(end 0.3 -1.39)
			(stroke
				(width 0.15)
				(type solid)
			)
			(layer "B.SilkS")
		)
		(fp_rect
			(start -2.1 1.75)
			(end 2.1 -1.75)
			(stroke
				(width 0.05)
				(type solid)
			)
			(fill no)
			(layer "B.CrtYd")
		)
		(fp_rect
			(start -1.6 1.25)
			(end 1.6 -1.25)
			(stroke
				(width 0.15)
				(type solid)
			)
			(fill no)
			(layer "B.Fab")
		)
		(pad "1" smd rect
			(at -1.145 0 180)
			(size 1.52 3.05)
			(layers "B.Cu" "B.Mask" "B.Paste")
			(net 1 "GND")
			(pintype "passive")
		)
		(pad "2" smd rect
			(at 1.145 0 180)
			(size 1.52 3.05)
			(layers "B.Cu" "B.Mask" "B.Paste")
			(net 2 "VCC3V3")
			(pintype "passive")
		)
	)
	(footprint "antmicro-footprints:C_0603_1608Metric"
		(layer "B.Cu")
		(at 93.6 119.1)
		(descr "Capacitor SMD 0603")
		(tags "capacitor 0603")
		(property "Reference" "C156"
			(at -1.6 -1.8 0)
			(layer "B.SilkS")
			(effects
				(font
					(size 0.7 0.7)
					(thickness 0.15)
				)
				(justify right bottom mirror)
			)
		)
		(property "Value" "C_4u7_0603"
			(at 0 -1.6 0)
			(layer "B.Fab")
			(effects
				(font
					(size 0.7 0.7)
					(thickness 0.15)
				)
				(justify right bottom mirror)
			)
		)
		(property "Datasheet" "https://product.tdk.com/en/search/capacitor/ceramic/mlcc/info?part_no=C1608X5R1V475M080AC"
			(at 0 0 0)
			(layer "F.Fab")
			(hide yes)
			(effects
				(font
					(size 1.27 1.27)
					(thickness 0.15)
				)
			)
		)
		(property "Description" "SMD Multilayer Ceramic Capacitor, 4.7 µF, 35 V, 0603 [1608 Metric], ± 20%, X5R, C"
			(at 0 0 0)
			(layer "F.Fab")
			(hide yes)
			(effects
				(font
					(size 1.27 1.27)
					(thickness 0.15)
				)
			)
		)
		(property "Author" "Antmicro"
			(at 0 0 0)
			(layer "B.Fab")
			(hide yes)
			(effects
				(font
					(size 1 1)
					(thickness 0.15)
				)
				(justify mirror)
			)
		)
		(property "Dielectric" ""
			(at 0 0 0)
			(layer "B.Fab")
			(hide yes)
			(effects
				(font
					(size 1 1)
					(thickness 0.15)
				)
				(justify mirror)
			)
		)
		(property "License" "Apache-2.0"
			(at 0 0 0)
			(layer "B.Fab")
			(hide yes)
			(effects
				(font
					(size 1 1)
					(thickness 0.15)
				)
				(justify mirror)
			)
		)
		(property "MPN" "C1608X5R1V475M080AC"
			(at 0 0 0)
			(layer "B.Fab")
			(hide yes)
			(effects
				(font
					(size 1 1)
					(thickness 0.15)
				)
				(justify mirror)
			)
		)
		(property "Manufacturer" "TDK"
			(at 0 0 0)
			(layer "B.Fab")
			(hide yes)
			(effects
				(font
					(size 1 1)
					(thickness 0.15)
				)
				(justify mirror)
			)
		)
		(property "Val" "4u7"
			(at 0 0 0)
			(layer "B.Fab")
			(hide yes)
			(effects
				(font
					(size 1 1)
					(thickness 0.15)
				)
				(justify mirror)
			)
		)
		(property "Voltage" ""
			(at 0 0 0)
			(layer "B.Fab")
			(hide yes)
			(effects
				(font
					(size 1 1)
					(thickness 0.15)
				)
				(justify mirror)
			)
		)
		(property "DNP" ""
			(at 0 0 0)
			(unlocked yes)
			(layer "B.Fab")
			(hide yes)
			(effects
				(font
					(size 1 1)
					(thickness 0.15)
				)
				(justify mirror)
			)
		)
		(sheetname "/FPGA power supply/")
		(sheetfile "fpga-power-supply.kicad_sch")
		(attr smd)
		(fp_line
			(start -0.15 -0.4)
			(end 0.15 -0.4)
			(stroke
				(width 0.15)
				(type solid)
			)
			(layer "B.SilkS")
		)
		(fp_line
			(start -0.15 0.4)
			(end 0.15 0.4)
			(stroke
				(width 0.15)
				(type solid)
			)
			(layer "B.SilkS")
		)
		(fp_rect
			(start -1.25 0.65)
			(end 1.25 -0.65)
			(stroke
				(width 0.05)
				(type solid)
			)
			(fill no)
			(layer "B.CrtYd")
		)
		(fp_rect
			(start -0.8 0.4)
			(end 0.8 -0.4)
			(stroke
				(width 0.15)
				(type solid)
			)
			(fill no)
			(layer "B.Fab")
		)
		(pad "1" smd roundrect
			(at -0.7 0)
			(size 0.8 1)
			(layers "B.Cu" "B.Mask" "B.Paste")
			(roundrect_rratio 0.2)
			(net 1 "GND")
			(pintype "passive")
		)
		(pad "2" smd roundrect
			(at 0.7 0)
			(size 0.8 1)
			(layers "B.Cu" "B.Mask" "B.Paste")
			(roundrect_rratio 0.2)
			(net 6 "VCC1V0")
			(pintype "passive")
		)
	)
	(footprint "antmicro-footprints:C_0603_1608Metric"
		(layer "B.Cu")
		(at 96.319 107.177 180)
		(descr "Capacitor SMD 0603")
		(tags "capacitor 0603")
		(property "Reference" "C164"
			(at 1.019 0.177 0)
			(layer "B.SilkS")
			(effects
				(font
					(size 0.7 0.7)
					(thickness 0.15)
				)
				(justify left bottom mirror)
			)
		)
		(property "Value" "C_4u7_0603"
			(at 0 -1.6 0)
			(layer "B.Fab")
			(effects
				(font
					(size 0.7 0.7)
					(thickness 0.15)
				)
				(justify left bottom mirror)
			)
		)
		(property "Datasheet" "https://product.tdk.com/en/search/capacitor/ceramic/mlcc/info?part_no=C1608X5R1V475M080AC"
			(at 0 0 180)
			(layer "F.Fab")
			(hide yes)
			(effects
				(font
					(size 1.27 1.27)
					(thickness 0.15)
				)
			)
		)
		(property "Description" "SMD Multilayer Ceramic Capacitor, 4.7 µF, 35 V, 0603 [1608 Metric], ± 20%, X5R, C"
			(at 0 0 180)
			(layer "F.Fab")
			(hide yes)
			(effects
				(font
					(size 1.27 1.27)
					(thickness 0.15)
				)
			)
		)
		(property "Author" "Antmicro"
			(at 192.638 214.354 0)
			(layer "B.Fab")
			(hide yes)
			(effects
				(font
					(size 1 1)
					(thickness 0.15)
				)
				(justify mirror)
			)
		)
		(property "Dielectric" ""
			(at 192.638 214.354 0)
			(layer "B.Fab")
			(hide yes)
			(effects
				(font
					(size 1 1)
					(thickness 0.15)
				)
				(justify mirror)
			)
		)
		(property "License" "Apache-2.0"
			(at 192.638 214.354 0)
			(layer "B.Fab")
			(hide yes)
			(effects
				(font
					(size 1 1)
					(thickness 0.15)
				)
				(justify mirror)
			)
		)
		(property "MPN" "C1608X5R1V475M080AC"
			(at 192.638 214.354 0)
			(layer "B.Fab")
			(hide yes)
			(effects
				(font
					(size 1 1)
					(thickness 0.15)
				)
				(justify mirror)
			)
		)
		(property "Manufacturer" "TDK"
			(at 192.638 214.354 0)
			(layer "B.Fab")
			(hide yes)
			(effects
				(font
					(size 1 1)
					(thickness 0.15)
				)
				(justify mirror)
			)
		)
		(property "Val" "4u7"
			(at 192.638 214.354 0)
			(layer "B.Fab")
			(hide yes)
			(effects
				(font
					(size 1 1)
					(thickness 0.15)
				)
				(justify mirror)
			)
		)
		(property "Voltage" ""
			(at 192.638 214.354 0)
			(layer "B.Fab")
			(hide yes)
			(effects
				(font
					(size 1 1)
					(thickness 0.15)
				)
				(justify mirror)
			)
		)
		(property "DNP" ""
			(at 0 0 180)
			(unlocked yes)
			(layer "B.Fab")
			(hide yes)
			(effects
				(font
					(size 1 1)
					(thickness 0.15)
				)
				(justify mirror)
			)
		)
		(sheetname "/FPGA power supply/")
		(sheetfile "fpga-power-supply.kicad_sch")
		(attr smd)
		(fp_line
			(start -0.15 0.4)
			(end 0.15 0.4)
			(stroke
				(width 0.15)
				(type solid)
			)
			(layer "B.SilkS")
		)
		(fp_line
			(start -0.15 -0.4)
			(end 0.15 -0.4)
			(stroke
				(width 0.15)
				(type solid)
			)
			(layer "B.SilkS")
		)
		(fp_rect
			(start -1.25 0.65)
			(end 1.25 -0.65)
			(stroke
				(width 0.05)
				(type solid)
			)
			(fill no)
			(layer "B.CrtYd")
		)
		(fp_rect
			(start -0.8 0.4)
			(end 0.8 -0.4)
			(stroke
				(width 0.15)
				(type solid)
			)
			(fill no)
			(layer "B.Fab")
		)
		(pad "1" smd roundrect
			(at -0.7 0 180)
			(size 0.8 1)
			(layers "B.Cu" "B.Mask" "B.Paste")
			(roundrect_rratio 0.2)
			(net 1 "GND")
			(pintype "passive")
		)
		(pad "2" smd roundrect
			(at 0.7 0 180)
			(size 0.8 1)
			(layers "B.Cu" "B.Mask" "B.Paste")
			(roundrect_rratio 0.2)
			(net 6 "VCC1V0")
			(pintype "passive")
		)
	)
	(footprint "antmicro-footprints:C_0603_1608Metric"
		(layer "B.Cu")
		(at 96.369 105.677 180)
		(descr "Capacitor SMD 0603")
		(tags "capacitor 0603")
		(property "Reference" "C158"
			(at 1.009 -0.223 0)
			(layer "B.SilkS")
			(effects
				(font
					(size 0.7 0.7)
					(thickness 0.15)
				)
				(justify left bottom mirror)
			)
		)
		(property "Value" "C_4u7_0603"
			(at 0 -1.6 0)
			(layer "B.Fab")
			(effects
				(font
					(size 0.7 0.7)
					(thickness 0.15)
				)
				(justify left bottom mirror)
			)
		)
		(property "Datasheet" "https://product.tdk.com/en/search/capacitor/ceramic/mlcc/info?part_no=C1608X5R1V475M080AC"
			(at 0 0 180)
			(layer "F.Fab")
			(hide yes)
			(effects
				(font
					(size 1.27 1.27)
					(thickness 0.15)
				)
			)
		)
		(property "Description" "SMD Multilayer Ceramic Capacitor, 4.7 µF, 35 V, 0603 [1608 Metric], ± 20%, X5R, C"
			(at 0 0 180)
			(layer "F.Fab")
			(hide yes)
			(effects
				(font
					(size 1.27 1.27)
					(thickness 0.15)
				)
			)
		)
		(property "Author" "Antmicro"
			(at 192.738 211.354 0)
			(layer "B.Fab")
			(hide yes)
			(effects
				(font
					(size 1 1)
					(thickness 0.15)
				)
				(justify mirror)
			)
		)
		(property "Dielectric" ""
			(at 192.738 211.354 0)
			(layer "B.Fab")
			(hide yes)
			(effects
				(font
					(size 1 1)
					(thickness 0.15)
				)
				(justify mirror)
			)
		)
		(property "License" "Apache-2.0"
			(at 192.738 211.354 0)
			(layer "B.Fab")
			(hide yes)
			(effects
				(font
					(size 1 1)
					(thickness 0.15)
				)
				(justify mirror)
			)
		)
		(property "MPN" "C1608X5R1V475M080AC"
			(at 192.738 211.354 0)
			(layer "B.Fab")
			(hide yes)
			(effects
				(font
					(size 1 1)
					(thickness 0.15)
				)
				(justify mirror)
			)
		)
		(property "Manufacturer" "TDK"
			(at 192.738 211.354 0)
			(layer "B.Fab")
			(hide yes)
			(effects
				(font
					(size 1 1)
					(thickness 0.15)
				)
				(justify mirror)
			)
		)
		(property "Val" "4u7"
			(at 192.738 211.354 0)
			(layer "B.Fab")
			(hide yes)
			(effects
				(font
					(size 1 1)
					(thickness 0.15)
				)
				(justify mirror)
			)
		)
		(property "Voltage" ""
			(at 192.738 211.354 0)
			(layer "B.Fab")
			(hide yes)
			(effects
				(font
					(size 1 1)
					(thickness 0.15)
				)
				(justify mirror)
			)
		)
		(property "DNP" ""
			(at 0 0 180)
			(unlocked yes)
			(layer "B.Fab")
			(hide yes)
			(effects
				(font
					(size 1 1)
					(thickness 0.15)
				)
				(justify mirror)
			)
		)
		(sheetname "/FPGA power supply/")
		(sheetfile "fpga-power-supply.kicad_sch")
		(attr smd)
		(fp_line
			(start -0.15 0.4)
			(end 0.15 0.4)
			(stroke
				(width 0.15)
				(type solid)
			)
			(layer "B.SilkS")
		)
		(fp_line
			(start -0.15 -0.4)
			(end 0.15 -0.4)
			(stroke
				(width 0.15)
				(type solid)
			)
			(layer "B.SilkS")
		)
		(fp_rect
			(start -1.25 0.65)
			(end 1.25 -0.65)
			(stroke
				(width 0.05)
				(type solid)
			)
			(fill no)
			(layer "B.CrtYd")
		)
		(fp_rect
			(start -0.8 0.4)
			(end 0.8 -0.4)
			(stroke
				(width 0.15)
				(type solid)
			)
			(fill no)
			(layer "B.Fab")
		)
		(pad "1" smd roundrect
			(at -0.7 0 180)
			(size 0.8 1)
			(layers "B.Cu" "B.Mask" "B.Paste")
			(roundrect_rratio 0.2)
			(net 1 "GND")
			(pintype "passive")
		)
		(pad "2" smd roundrect
			(at 0.7 0 180)
			(size 0.8 1)
			(layers "B.Cu" "B.Mask" "B.Paste")
			(roundrect_rratio 0.2)
			(net 6 "VCC1V0")
			(pintype "passive")
		)
	)
	(footprint "antmicro-footprints:C_0603_1608Metric"
		(layer "B.Cu")
		(at 96.309 108.677 180)
		(descr "Capacitor SMD 0603")
		(tags "capacitor 0603")
		(property "Reference" "C160"
			(at 1.009 0.577 0)
			(layer "B.SilkS")
			(effects
				(font
					(size 0.7 0.7)
					(thickness 0.15)
				)
				(justify left bottom mirror)
			)
		)
		(property "Value" "C_4u7_0603"
			(at 0 -1.6 0)
			(layer "B.Fab")
			(effects
				(font
					(size 0.7 0.7)
					(thickness 0.15)
				)
				(justify left bottom mirror)
			)
		)
		(property "Datasheet" "https://product.tdk.com/en/search/capacitor/ceramic/mlcc/info?part_no=C1608X5R1V475M080AC"
			(at 0 0 180)
			(layer "F.Fab")
			(hide yes)
			(effects
				(font
					(size 1.27 1.27)
					(thickness 0.15)
				)
			)
		)
		(property "Description" "SMD Multilayer Ceramic Capacitor, 4.7 µF, 35 V, 0603 [1608 Metric], ± 20%, X5R, C"
			(at 0 0 180)
			(layer "F.Fab")
			(hide yes)
			(effects
				(font
					(size 1.27 1.27)
					(thickness 0.15)
				)
			)
		)
		(property "Author" "Antmicro"
			(at 192.618 217.354 0)
			(layer "B.Fab")
			(hide yes)
			(effects
				(font
					(size 1 1)
					(thickness 0.15)
				)
				(justify mirror)
			)
		)
		(property "Dielectric" ""
			(at 192.618 217.354 0)
			(layer "B.Fab")
			(hide yes)
			(effects
				(font
					(size 1 1)
					(thickness 0.15)
				)
				(justify mirror)
			)
		)
		(property "License" "Apache-2.0"
			(at 192.618 217.354 0)
			(layer "B.Fab")
			(hide yes)
			(effects
				(font
					(size 1 1)
					(thickness 0.15)
				)
				(justify mirror)
			)
		)
		(property "MPN" "C1608X5R1V475M080AC"
			(at 192.618 217.354 0)
			(layer "B.Fab")
			(hide yes)
			(effects
				(font
					(size 1 1)
					(thickness 0.15)
				)
				(justify mirror)
			)
		)
		(property "Manufacturer" "TDK"
			(at 192.618 217.354 0)
			(layer "B.Fab")
			(hide yes)
			(effects
				(font
					(size 1 1)
					(thickness 0.15)
				)
				(justify mirror)
			)
		)
		(property "Val" "4u7"
			(at 192.618 217.354 0)
			(layer "B.Fab")
			(hide yes)
			(effects
				(font
					(size 1 1)
					(thickness 0.15)
				)
				(justify mirror)
			)
		)
		(property "Voltage" ""
			(at 192.618 217.354 0)
			(layer "B.Fab")
			(hide yes)
			(effects
				(font
					(size 1 1)
					(thickness 0.15)
				)
				(justify mirror)
			)
		)
		(property "DNP" ""
			(at 0 0 180)
			(unlocked yes)
			(layer "B.Fab")
			(hide yes)
			(effects
				(font
					(size 1 1)
					(thickness 0.15)
				)
				(justify mirror)
			)
		)
		(sheetname "/FPGA power supply/")
		(sheetfile "fpga-power-supply.kicad_sch")
		(attr smd)
		(fp_line
			(start -0.15 0.4)
			(end 0.15 0.4)
			(stroke
				(width 0.15)
				(type solid)
			)
			(layer "B.SilkS")
		)
		(fp_line
			(start -0.15 -0.4)
			(end 0.15 -0.4)
			(stroke
				(width 0.15)
				(type solid)
			)
			(layer "B.SilkS")
		)
		(fp_rect
			(start -1.25 0.65)
			(end 1.25 -0.65)
			(stroke
				(width 0.05)
				(type solid)
			)
			(fill no)
			(layer "B.CrtYd")
		)
		(fp_rect
			(start -0.8 0.4)
			(end 0.8 -0.4)
			(stroke
				(width 0.15)
				(type solid)
			)
			(fill no)
			(layer "B.Fab")
		)
		(pad "1" smd roundrect
			(at -0.7 0 180)
			(size 0.8 1)
			(layers "B.Cu" "B.Mask" "B.Paste")
			(roundrect_rratio 0.2)
			(net 1 "GND")
			(pintype "passive")
		)
		(pad "2" smd roundrect
			(at 0.7 0 180)
			(size 0.8 1)
			(layers "B.Cu" "B.Mask" "B.Paste")
			(roundrect_rratio 0.2)
			(net 6 "VCC1V0")
			(pintype "passive")
		)
	)
	(footprint "antmicro-footprints:C_0603_1608Metric"
		(layer "B.Cu")
		(at 112.6 104.8 180)
		(descr "Capacitor SMD 0603")
		(tags "capacitor 0603")
		(property "Reference" "C99"
			(at -3.3 -0.351 0)
			(layer "B.SilkS")
			(effects
				(font
					(size 0.7 0.7)
					(thickness 0.15)
				)
				(justify left bottom mirror)
			)
		)
		(property "Value" "C_4u7_0603"
			(at 0 -1.6 0)
			(layer "B.Fab")
			(effects
				(font
					(size 0.7 0.7)
					(thickness 0.15)
				)
				(justify left bottom mirror)
			)
		)
		(property "Datasheet" "https://product.tdk.com/en/search/capacitor/ceramic/mlcc/info?part_no=C1608X5R1V475M080AC"
			(at 0 0 180)
			(layer "F.Fab")
			(hide yes)
			(effects
				(font
					(size 1.27 1.27)
					(thickness 0.15)
				)
			)
		)
		(property "Description" "SMD Multilayer Ceramic Capacitor, 4.7 µF, 35 V, 0603 [1608 Metric], ± 20%, X5R, C"
			(at 0 0 180)
			(layer "F.Fab")
			(hide yes)
			(effects
				(font
					(size 1.27 1.27)
					(thickness 0.15)
				)
			)
		)
		(property "Author" "Antmicro"
			(at 225.2 209.6 0)
			(layer "B.Fab")
			(hide yes)
			(effects
				(font
					(size 1 1)
					(thickness 0.15)
				)
				(justify mirror)
			)
		)
		(property "Dielectric" ""
			(at 225.2 209.6 0)
			(layer "B.Fab")
			(hide yes)
			(effects
				(font
					(size 1 1)
					(thickness 0.15)
				)
				(justify mirror)
			)
		)
		(property "License" "Apache-2.0"
			(at 225.2 209.6 0)
			(layer "B.Fab")
			(hide yes)
			(effects
				(font
					(size 1 1)
					(thickness 0.15)
				)
				(justify mirror)
			)
		)
		(property "MPN" "C1608X5R1V475M080AC"
			(at 225.2 209.6 0)
			(layer "B.Fab")
			(hide yes)
			(effects
				(font
					(size 1 1)
					(thickness 0.15)
				)
				(justify mirror)
			)
		)
		(property "Manufacturer" "TDK"
			(at 225.2 209.6 0)
			(layer "B.Fab")
			(hide yes)
			(effects
				(font
					(size 1 1)
					(thickness 0.15)
				)
				(justify mirror)
			)
		)
		(property "Val" "4u7"
			(at 225.2 209.6 0)
			(layer "B.Fab")
			(hide yes)
			(effects
				(font
					(size 1 1)
					(thickness 0.15)
				)
				(justify mirror)
			)
		)
		(property "Voltage" ""
			(at 225.2 209.6 0)
			(layer "B.Fab")
			(hide yes)
			(effects
				(font
					(size 1 1)
					(thickness 0.15)
				)
				(justify mirror)
			)
		)
		(sheetname "/FPGA banks 13-16/")
		(sheetfile "fpga-banks-13-16.kicad_sch")
		(attr smd)
		(fp_line
			(start -0.15 0.4)
			(end 0.15 0.4)
			(stroke
				(width 0.15)
				(type solid)
			)
			(layer "B.SilkS")
		)
		(fp_line
			(start -0.15 -0.4)
			(end 0.15 -0.4)
			(stroke
				(width 0.15)
				(type solid)
			)
			(layer "B.SilkS")
		)
		(fp_rect
			(start -1.25 0.65)
			(end 1.25 -0.65)
			(stroke
				(width 0.05)
				(type solid)
			)
			(fill no)
			(layer "B.CrtYd")
		)
		(fp_rect
			(start -0.8 0.4)
			(end 0.8 -0.4)
			(stroke
				(width 0.15)
				(type solid)
			)
			(fill no)
			(layer "B.Fab")
		)
		(pad "1" smd roundrect
			(at -0.7 0 180)
			(size 0.8 1)
			(layers "B.Cu" "B.Mask" "B.Paste")
			(roundrect_rratio 0.2)
			(net 1 "GND")
			(pintype "passive")
		)
		(pad "2" smd roundrect
			(at 0.7 0 180)
			(size 0.8 1)
			(layers "B.Cu" "B.Mask" "B.Paste")
			(roundrect_rratio 0.2)
			(net 2 "VCC3V3")
			(pintype "passive")
		)
	)
	(footprint "antmicro-footprints:C_0201"
		(layer "B.Cu")
		(at 106.875 120.375 -90)
		(descr "Capacitor SMD 0201")
		(tags "capacitor SMD 0201")
		(property "Reference" "C161"
			(at -1.375 -1.225 90)
			(layer "B.SilkS")
			(effects
				(font
					(size 0.7 0.7)
					(thickness 0.15)
				)
				(justify left bottom mirror)
			)
		)
		(property "Value" "C_470n_0201"
			(at 0 -1.4 90)
			(layer "B.Fab")
			(effects
				(font
					(size 0.7 0.7)
					(thickness 0.15)
				)
				(justify left bottom mirror)
			)
		)
		(property "Datasheet" "https://product.tdk.com/en/search/capacitor/ceramic/mlcc/info?part_no=C0603X5R1A474M030BC"
			(at 0 0 270)
			(layer "F.Fab")
			(hide yes)
			(effects
				(font
					(size 1.27 1.27)
					(thickness 0.15)
				)
			)
		)
		(property "Description" "SMD Multilayer Ceramic Capacitor, 0.47 µF, 10 V, 0201 [0603 Metric], ± 20%, X5R, C"
			(at 0 0 270)
			(layer "F.Fab")
			(hide yes)
			(effects
				(font
					(size 1.27 1.27)
					(thickness 0.15)
				)
			)
		)
		(property "Author" "Antmicro"
			(at -13.5 227.25 0)
			(layer "B.Fab")
			(hide yes)
			(effects
				(font
					(size 1 1)
					(thickness 0.15)
				)
				(justify mirror)
			)
		)
		(property "Dielectric" ""
			(at -13.5 227.25 0)
			(layer "B.Fab")
			(hide yes)
			(effects
				(font
					(size 1 1)
					(thickness 0.15)
				)
				(justify mirror)
			)
		)
		(property "License" "Apache-2.0"
			(at -13.5 227.25 0)
			(layer "B.Fab")
			(hide yes)
			(effects
				(font
					(size 1 1)
					(thickness 0.15)
				)
				(justify mirror)
			)
		)
		(property "MPN" "C0603X5R1A474M030BC"
			(at -13.5 227.25 0)
			(layer "B.Fab")
			(hide yes)
			(effects
				(font
					(size 1 1)
					(thickness 0.15)
				)
				(justify mirror)
			)
		)
		(property "Manufacturer" "TDK"
			(at -13.5 227.25 0)
			(layer "B.Fab")
			(hide yes)
			(effects
				(font
					(size 1 1)
					(thickness 0.15)
				)
				(justify mirror)
			)
		)
		(property "Public" "False"
			(at -13.5 227.25 0)
			(layer "B.Fab")
			(hide yes)
			(effects
				(font
					(size 1 1)
					(thickness 0.15)
				)
				(justify mirror)
			)
		)
		(property "Val" "470n"
			(at -13.5 227.25 0)
			(layer "B.Fab")
			(hide yes)
			(effects
				(font
					(size 1 1)
					(thickness 0.15)
				)
				(justify mirror)
			)
		)
		(property "Voltage" ""
			(at -13.5 227.25 0)
			(layer "B.Fab")
			(hide yes)
			(effects
				(font
					(size 1 1)
					(thickness 0.15)
				)
				(justify mirror)
			)
		)
		(property "DNP" ""
			(at 0 0 270)
			(unlocked yes)
			(layer "B.Fab")
			(hide yes)
			(effects
				(font
					(size 1 1)
					(thickness 0.15)
				)
				(justify mirror)
			)
		)
		(sheetname "/FPGA power supply/")
		(sheetfile "fpga-power-supply.kicad_sch")
		(attr smd)
		(fp_rect
			(start -0.7 0.35)
			(end 0.7 -0.35)
			(stroke
				(width 0.05)
				(type default)
			)
			(fill no)
			(layer "B.CrtYd")
		)
		(fp_rect
			(start 0.3 -0.15)
			(end -0.301 0.149)
			(stroke
				(width 0.15)
				(type solid)
			)
			(fill no)
			(layer "B.Fab")
		)
		(pad "" smd roundrect
			(at -0.349 0.002 270)
			(size 0.318 0.36)
			(layers "B.Paste")
			(roundrect_rratio 0.25)
		)
		(pad "" smd roundrect
			(at 0.341 0.002 270)
			(size 0.318 0.36)
			(layers "B.Paste")
			(roundrect_rratio 0.25)
		)
		(pad "1" smd roundrect
			(at -0.321 0.002 270)
			(size 0.46 0.4)
			(layers "B.Cu" "B.Mask")
			(roundrect_rratio 0.25)
			(net 1 "GND")
			(pintype "passive")
		)
		(pad "2" smd roundrect
			(at 0.32 0.002 270)
			(size 0.46 0.4)
			(layers "B.Cu" "B.Mask")
			(roundrect_rratio 0.25)
			(net 6 "VCC1V0")
			(pintype "passive")
		)
	)
	(footprint "antmicro-footprints:C_0201"
		(layer "B.Cu")
		(at 103.325 124.675)
		(descr "Capacitor SMD 0201")
		(tags "capacitor SMD 0201")
		(property "Reference" "C163"
			(at -1.325 1.225 0)
			(layer "B.SilkS")
			(effects
				(font
					(size 0.7 0.7)
					(thickness 0.15)
				)
				(justify right bottom mirror)
			)
		)
		(property "Value" "C_470n_0201"
			(at 0 -1.4 0)
			(layer "B.Fab")
			(effects
				(font
					(size 0.7 0.7)
					(thickness 0.15)
				)
				(justify right bottom mirror)
			)
		)
		(property "Datasheet" "https://product.tdk.com/en/search/capacitor/ceramic/mlcc/info?part_no=C0603X5R1A474M030BC"
			(at 0 0 0)
			(layer "F.Fab")
			(hide yes)
			(effects
				(font
					(size 1.27 1.27)
					(thickness 0.15)
				)
			)
		)
		(property "Description" "SMD Multilayer Ceramic Capacitor, 0.47 µF, 10 V, 0201 [0603 Metric], ± 20%, X5R, C"
			(at 0 0 0)
			(layer "F.Fab")
			(hide yes)
			(effects
				(font
					(size 1.27 1.27)
					(thickness 0.15)
				)
			)
		)
		(property "Author" "Antmicro"
			(at 0 0 0)
			(layer "B.Fab")
			(hide yes)
			(effects
				(font
					(size 1 1)
					(thickness 0.15)
				)
				(justify mirror)
			)
		)
		(property "Dielectric" ""
			(at 0 0 0)
			(layer "B.Fab")
			(hide yes)
			(effects
				(font
					(size 1 1)
					(thickness 0.15)
				)
				(justify mirror)
			)
		)
		(property "License" "Apache-2.0"
			(at 0 0 0)
			(layer "B.Fab")
			(hide yes)
			(effects
				(font
					(size 1 1)
					(thickness 0.15)
				)
				(justify mirror)
			)
		)
		(property "MPN" "C0603X5R1A474M030BC"
			(at 0 0 0)
			(layer "B.Fab")
			(hide yes)
			(effects
				(font
					(size 1 1)
					(thickness 0.15)
				)
				(justify mirror)
			)
		)
		(property "Manufacturer" "TDK"
			(at 0 0 0)
			(layer "B.Fab")
			(hide yes)
			(effects
				(font
					(size 1 1)
					(thickness 0.15)
				)
				(justify mirror)
			)
		)
		(property "Public" "False"
			(at 0 0 0)
			(layer "B.Fab")
			(hide yes)
			(effects
				(font
					(size 1 1)
					(thickness 0.15)
				)
				(justify mirror)
			)
		)
		(property "Val" "470n"
			(at 0 0 0)
			(layer "B.Fab")
			(hide yes)
			(effects
				(font
					(size 1 1)
					(thickness 0.15)
				)
				(justify mirror)
			)
		)
		(property "Voltage" ""
			(at 0 0 0)
			(layer "B.Fab")
			(hide yes)
			(effects
				(font
					(size 1 1)
					(thickness 0.15)
				)
				(justify mirror)
			)
		)
		(property "DNP" ""
			(at 0 0 0)
			(unlocked yes)
			(layer "B.Fab")
			(hide yes)
			(effects
				(font
					(size 1 1)
					(thickness 0.15)
				)
				(justify mirror)
			)
		)
		(sheetname "/FPGA power supply/")
		(sheetfile "fpga-power-supply.kicad_sch")
		(attr smd)
		(fp_rect
			(start -0.7 0.35)
			(end 0.7 -0.35)
			(stroke
				(width 0.05)
				(type default)
			)
			(fill no)
			(layer "B.CrtYd")
		)
		(fp_rect
			(start 0.3 -0.15)
			(end -0.301 0.149)
			(stroke
				(width 0.15)
				(type solid)
			)
			(fill no)
			(layer "B.Fab")
		)
		(pad "" smd roundrect
			(at -0.349 0.002)
			(size 0.318 0.36)
			(layers "B.Paste")
			(roundrect_rratio 0.25)
		)
		(pad "" smd roundrect
			(at 0.341 0.002)
			(size 0.318 0.36)
			(layers "B.Paste")
			(roundrect_rratio 0.25)
		)
		(pad "1" smd roundrect
			(at -0.321 0.002)
			(size 0.46 0.4)
			(layers "B.Cu" "B.Mask")
			(roundrect_rratio 0.25)
			(net 1 "GND")
			(pintype "passive")
		)
		(pad "2" smd roundrect
			(at 0.32 0.002)
			(size 0.46 0.4)
			(layers "B.Cu" "B.Mask")
			(roundrect_rratio 0.25)
			(net 6 "VCC1V0")
			(pintype "passive")
		)
	)
	(footprint "antmicro-footprints:C_0201"
		(layer "B.Cu")
		(at 101.325 123.625 180)
		(descr "Capacitor SMD 0201")
		(tags "capacitor SMD 0201")
		(property "Reference" "C175"
			(at -1.775 0.425 0)
			(layer "B.SilkS")
			(effects
				(font
					(size 0.7 0.7)
					(thickness 0.15)
				)
				(justify left bottom mirror)
			)
		)
		(property "Value" "C_470n_0201"
			(at 0 -1.4 0)
			(layer "B.Fab")
			(effects
				(font
					(size 0.7 0.7)
					(thickness 0.15)
				)
				(justify left bottom mirror)
			)
		)
		(property "Datasheet" "https://product.tdk.com/en/search/capacitor/ceramic/mlcc/info?part_no=C0603X5R1A474M030BC"
			(at 0 0 180)
			(layer "F.Fab")
			(hide yes)
			(effects
				(font
					(size 1.27 1.27)
					(thickness 0.15)
				)
			)
		)
		(property "Description" "SMD Multilayer Ceramic Capacitor, 0.47 µF, 10 V, 0201 [0603 Metric], ± 20%, X5R, C"
			(at 0 0 180)
			(layer "F.Fab")
			(hide yes)
			(effects
				(font
					(size 1.27 1.27)
					(thickness 0.15)
				)
			)
		)
		(property "Author" "Antmicro"
			(at 202.65 247.25 0)
			(layer "B.Fab")
			(hide yes)
			(effects
				(font
					(size 1 1)
					(thickness 0.15)
				)
				(justify mirror)
			)
		)
		(property "Dielectric" ""
			(at 202.65 247.25 0)
			(layer "B.Fab")
			(hide yes)
			(effects
				(font
					(size 1 1)
					(thickness 0.15)
				)
				(justify mirror)
			)
		)
		(property "License" "Apache-2.0"
			(at 202.65 247.25 0)
			(layer "B.Fab")
			(hide yes)
			(effects
				(font
					(size 1 1)
					(thickness 0.15)
				)
				(justify mirror)
			)
		)
		(property "MPN" "C0603X5R1A474M030BC"
			(at 202.65 247.25 0)
			(layer "B.Fab")
			(hide yes)
			(effects
				(font
					(size 1 1)
					(thickness 0.15)
				)
				(justify mirror)
			)
		)
		(property "Manufacturer" "TDK"
			(at 202.65 247.25 0)
			(layer "B.Fab")
			(hide yes)
			(effects
				(font
					(size 1 1)
					(thickness 0.15)
				)
				(justify mirror)
			)
		)
		(property "Public" "False"
			(at 202.65 247.25 0)
			(layer "B.Fab")
			(hide yes)
			(effects
				(font
					(size 1 1)
					(thickness 0.15)
				)
				(justify mirror)
			)
		)
		(property "Val" "470n"
			(at 202.65 247.25 0)
			(layer "B.Fab")
			(hide yes)
			(effects
				(font
					(size 1 1)
					(thickness 0.15)
				)
				(justify mirror)
			)
		)
		(property "Voltage" ""
			(at 202.65 247.25 0)
			(layer "B.Fab")
			(hide yes)
			(effects
				(font
					(size 1 1)
					(thickness 0.15)
				)
				(justify mirror)
			)
		)
		(property "DNP" ""
			(at 0 0 180)
			(unlocked yes)
			(layer "B.Fab")
			(hide yes)
			(effects
				(font
					(size 1 1)
					(thickness 0.15)
				)
				(justify mirror)
			)
		)
		(sheetname "/FPGA power supply/")
		(sheetfile "fpga-power-supply.kicad_sch")
		(attr smd)
		(fp_rect
			(start -0.7 0.35)
			(end 0.7 -0.35)
			(stroke
				(width 0.05)
				(type default)
			)
			(fill no)
			(layer "B.CrtYd")
		)
		(fp_rect
			(start 0.3 -0.15)
			(end -0.301 0.149)
			(stroke
				(width 0.15)
				(type solid)
			)
			(fill no)
			(layer "B.Fab")
		)
		(pad "" smd roundrect
			(at -0.349 0.002 180)
			(size 0.318 0.36)
			(layers "B.Paste")
			(roundrect_rratio 0.25)
		)
		(pad "" smd roundrect
			(at 0.341 0.002 180)
			(size 0.318 0.36)
			(layers "B.Paste")
			(roundrect_rratio 0.25)
		)
		(pad "1" smd roundrect
			(at -0.321 0.002 180)
			(size 0.46 0.4)
			(layers "B.Cu" "B.Mask")
			(roundrect_rratio 0.25)
			(net 1 "GND")
			(pintype "passive")
		)
		(pad "2" smd roundrect
			(at 0.32 0.002 180)
			(size 0.46 0.4)
			(layers "B.Cu" "B.Mask")
			(roundrect_rratio 0.25)
			(net 6 "VCC1V0")
			(pintype "passive")
		)
	)
	(footprint "antmicro-footprints:C_0402_1005Metric"
		(layer "B.Cu")
		(at 96.375 124.075 180)
		(descr "Capacitor SMD 0402")
		(tags "capacitor SMD 0402")
		(property "Reference" "C140"
			(at 20.475 -0.825 0)
			(layer "B.SilkS")
			(effects
				(font
					(size 0.7 0.7)
					(thickness 0.15)
				)
				(justify left bottom mirror)
			)
		)
		(property "Value" "C_470n_0402"
			(at 0 -1.4 0)
			(layer "B.Fab")
			(effects
				(font
					(size 0.7 0.7)
					(thickness 0.15)
				)
				(justify left bottom mirror)
			)
		)
		(property "Datasheet" "https://product.tdk.com/en/search/capacitor/ceramic/mlcc/info?part_no=C1005X5R1E474M050BB"
			(at 0 0 180)
			(layer "F.Fab")
			(hide yes)
			(effects
				(font
					(size 1.27 1.27)
					(thickness 0.15)
				)
			)
		)
		(property "Description" "SMD Multilayer Ceramic Capacitor, 0.47 µF, 25 V, 0402 [1005 Metric], ± 20%, X5R, C"
			(at 0 0 180)
			(layer "F.Fab")
			(hide yes)
			(effects
				(font
					(size 1.27 1.27)
					(thickness 0.15)
				)
			)
		)
		(property "Author" "Antmicro"
			(at 192.75 248.15 0)
			(layer "B.Fab")
			(hide yes)
			(effects
				(font
					(size 1 1)
					(thickness 0.15)
				)
				(justify mirror)
			)
		)
		(property "Dielectric" ""
			(at 192.75 248.15 0)
			(layer "B.Fab")
			(hide yes)
			(effects
				(font
					(size 1 1)
					(thickness 0.15)
				)
				(justify mirror)
			)
		)
		(property "License" "Apache-2.0"
			(at 192.75 248.15 0)
			(layer "B.Fab")
			(hide yes)
			(effects
				(font
					(size 1 1)
					(thickness 0.15)
				)
				(justify mirror)
			)
		)
		(property "MPN" "C1005X5R1E474M050BB"
			(at 192.75 248.15 0)
			(layer "B.Fab")
			(hide yes)
			(effects
				(font
					(size 1 1)
					(thickness 0.15)
				)
				(justify mirror)
			)
		)
		(property "Manufacturer" "TDK"
			(at 192.75 248.15 0)
			(layer "B.Fab")
			(hide yes)
			(effects
				(font
					(size 1 1)
					(thickness 0.15)
				)
				(justify mirror)
			)
		)
		(property "Val" "470n"
			(at 192.75 248.15 0)
			(layer "B.Fab")
			(hide yes)
			(effects
				(font
					(size 1 1)
					(thickness 0.15)
				)
				(justify mirror)
			)
		)
		(property "Voltage" ""
			(at 192.75 248.15 0)
			(layer "B.Fab")
			(hide yes)
			(effects
				(font
					(size 1 1)
					(thickness 0.15)
				)
				(justify mirror)
			)
		)
		(property "DNP" ""
			(at 0 0 180)
			(unlocked yes)
			(layer "B.Fab")
			(hide yes)
			(effects
				(font
					(size 1 1)
					(thickness 0.15)
				)
				(justify mirror)
			)
		)
		(sheetname "/FPGA power supply/")
		(sheetfile "fpga-power-supply.kicad_sch")
		(attr smd)
		(fp_rect
			(start -0.925 0.47)
			(end 0.925 -0.47)
			(stroke
				(width 0.05)
				(type default)
			)
			(fill no)
			(layer "B.CrtYd")
		)
		(fp_line
			(start 0.504 0.25)
			(end 0.504 -0.248)
			(stroke
				(width 0.15)
				(type solid)
			)
			(layer "B.Fab")
		)
		(fp_line
			(start 0.504 -0.248)
			(end -0.494 -0.248)
			(stroke
				(width 0.15)
				(type solid)
			)
			(layer "B.Fab")
		)
		(fp_line
			(start -0.494 0.25)
			(end 0.504 0.25)
			(stroke
				(width 0.15)
				(type solid)
			)
			(layer "B.Fab")
		)
		(fp_line
			(start -0.494 -0.248)
			(end -0.494 0.25)
			(stroke
				(width 0.15)
				(type solid)
			)
			(layer "B.Fab")
		)
		(pad "1" smd roundrect
			(at -0.48 0 180)
			(size 0.59 0.64)
			(layers "B.Cu" "B.Mask" "B.Paste")
			(roundrect_rratio 0.25)
			(net 1 "GND")
			(pintype "passive")
		)
		(pad "2" smd roundrect
			(at 0.48 0 180)
			(size 0.59 0.64)
			(layers "B.Cu" "B.Mask" "B.Paste")
			(roundrect_rratio 0.25)
			(net 6 "VCC1V0")
			(pintype "passive")
		)
	)
	(footprint "antmicro-footprints:C_0201"
		(layer "B.Cu")
		(at 96.725 123.175 180)
		(descr "Capacitor SMD 0201")
		(tags "capacitor SMD 0201")
		(property "Reference" "C142"
			(at 20.825 -0.625 0)
			(layer "B.SilkS")
			(effects
				(font
					(size 0.7 0.7)
					(thickness 0.15)
				)
				(justify left bottom mirror)
			)
		)
		(property "Value" "C_470n_0201"
			(at 0 -1.4 0)
			(layer "B.Fab")
			(effects
				(font
					(size 0.7 0.7)
					(thickness 0.15)
				)
				(justify left bottom mirror)
			)
		)
		(property "Datasheet" "https://product.tdk.com/en/search/capacitor/ceramic/mlcc/info?part_no=C0603X5R1A474M030BC"
			(at 0 0 180)
			(layer "F.Fab")
			(hide yes)
			(effects
				(font
					(size 1.27 1.27)
					(thickness 0.15)
				)
			)
		)
		(property "Description" "SMD Multilayer Ceramic Capacitor, 0.47 µF, 10 V, 0201 [0603 Metric], ± 20%, X5R, C"
			(at 0 0 180)
			(layer "F.Fab")
			(hide yes)
			(effects
				(font
					(size 1.27 1.27)
					(thickness 0.15)
				)
			)
		)
		(property "Author" "Antmicro"
			(at 193.45 246.35 0)
			(layer "B.Fab")
			(hide yes)
			(effects
				(font
					(size 1 1)
					(thickness 0.15)
				)
				(justify mirror)
			)
		)
		(property "Dielectric" ""
			(at 193.45 246.35 0)
			(layer "B.Fab")
			(hide yes)
			(effects
				(font
					(size 1 1)
					(thickness 0.15)
				)
				(justify mirror)
			)
		)
		(property "License" "Apache-2.0"
			(at 193.45 246.35 0)
			(layer "B.Fab")
			(hide yes)
			(effects
				(font
					(size 1 1)
					(thickness 0.15)
				)
				(justify mirror)
			)
		)
		(property "MPN" "C0603X5R1A474M030BC"
			(at 193.45 246.35 0)
			(layer "B.Fab")
			(hide yes)
			(effects
				(font
					(size 1 1)
					(thickness 0.15)
				)
				(justify mirror)
			)
		)
		(property "Manufacturer" "TDK"
			(at 193.45 246.35 0)
			(layer "B.Fab")
			(hide yes)
			(effects
				(font
					(size 1 1)
					(thickness 0.15)
				)
				(justify mirror)
			)
		)
		(property "Public" "False"
			(at 193.45 246.35 0)
			(layer "B.Fab")
			(hide yes)
			(effects
				(font
					(size 1 1)
					(thickness 0.15)
				)
				(justify mirror)
			)
		)
		(property "Val" "470n"
			(at 193.45 246.35 0)
			(layer "B.Fab")
			(hide yes)
			(effects
				(font
					(size 1 1)
					(thickness 0.15)
				)
				(justify mirror)
			)
		)
		(property "Voltage" ""
			(at 193.45 246.35 0)
			(layer "B.Fab")
			(hide yes)
			(effects
				(font
					(size 1 1)
					(thickness 0.15)
				)
				(justify mirror)
			)
		)
		(property "DNP" ""
			(at 0 0 180)
			(unlocked yes)
			(layer "B.Fab")
			(hide yes)
			(effects
				(font
					(size 1 1)
					(thickness 0.15)
				)
				(justify mirror)
			)
		)
		(sheetname "/FPGA power supply/")
		(sheetfile "fpga-power-supply.kicad_sch")
		(attr smd)
		(fp_rect
			(start -0.7 0.35)
			(end 0.7 -0.35)
			(stroke
				(width 0.05)
				(type default)
			)
			(fill no)
			(layer "B.CrtYd")
		)
		(fp_rect
			(start 0.3 -0.15)
			(end -0.301 0.149)
			(stroke
				(width 0.15)
				(type solid)
			)
			(fill no)
			(layer "B.Fab")
		)
		(pad "" smd roundrect
			(at -0.349 0.002 180)
			(size 0.318 0.36)
			(layers "B.Paste")
			(roundrect_rratio 0.25)
		)
		(pad "" smd roundrect
			(at 0.341 0.002 180)
			(size 0.318 0.36)
			(layers "B.Paste")
			(roundrect_rratio 0.25)
		)
		(pad "1" smd roundrect
			(at -0.321 0.002 180)
			(size 0.46 0.4)
			(layers "B.Cu" "B.Mask")
			(roundrect_rratio 0.25)
			(net 1 "GND")
			(pintype "passive")
		)
		(pad "2" smd roundrect
			(at 0.32 0.002 180)
			(size 0.46 0.4)
			(layers "B.Cu" "B.Mask")
			(roundrect_rratio 0.25)
			(net 6 "VCC1V0")
			(pintype "passive")
		)
	)
	(footprint "antmicro-footprints:C_0402_1005Metric"
		(layer "B.Cu")
		(at 102.275 118.375 -90)
		(descr "Capacitor SMD 0402")
		(tags "capacitor SMD 0402")
		(property "Reference" "C144"
			(at -1.575 0.475 90)
			(layer "B.SilkS")
			(effects
				(font
					(size 0.7 0.7)
					(thickness 0.15)
				)
				(justify left bottom mirror)
			)
		)
		(property "Value" "C_470n_0402"
			(at 0 -1.4 90)
			(layer "B.Fab")
			(effects
				(font
					(size 0.7 0.7)
					(thickness 0.15)
				)
				(justify left bottom mirror)
			)
		)
		(property "Datasheet" "https://product.tdk.com/en/search/capacitor/ceramic/mlcc/info?part_no=C1005X5R1E474M050BB"
			(at 0 0 270)
			(layer "F.Fab")
			(hide yes)
			(effects
				(font
					(size 1.27 1.27)
					(thickness 0.15)
				)
			)
		)
		(property "Description" "SMD Multilayer Ceramic Capacitor, 0.47 µF, 25 V, 0402 [1005 Metric], ± 20%, X5R, C"
			(at 0 0 270)
			(layer "F.Fab")
			(hide yes)
			(effects
				(font
					(size 1.27 1.27)
					(thickness 0.15)
				)
			)
		)
		(property "Author" "Antmicro"
			(at -16.1 220.65 0)
			(layer "B.Fab")
			(hide yes)
			(effects
				(font
					(size 1 1)
					(thickness 0.15)
				)
				(justify mirror)
			)
		)
		(property "Dielectric" ""
			(at -16.1 220.65 0)
			(layer "B.Fab")
			(hide yes)
			(effects
				(font
					(size 1 1)
					(thickness 0.15)
				)
				(justify mirror)
			)
		)
		(property "License" "Apache-2.0"
			(at -16.1 220.65 0)
			(layer "B.Fab")
			(hide yes)
			(effects
				(font
					(size 1 1)
					(thickness 0.15)
				)
				(justify mirror)
			)
		)
		(property "MPN" "C1005X5R1E474M050BB"
			(at -16.1 220.65 0)
			(layer "B.Fab")
			(hide yes)
			(effects
				(font
					(size 1 1)
					(thickness 0.15)
				)
				(justify mirror)
			)
		)
		(property "Manufacturer" "TDK"
			(at -16.1 220.65 0)
			(layer "B.Fab")
			(hide yes)
			(effects
				(font
					(size 1 1)
					(thickness 0.15)
				)
				(justify mirror)
			)
		)
		(property "Val" "470n"
			(at -16.1 220.65 0)
			(layer "B.Fab")
			(hide yes)
			(effects
				(font
					(size 1 1)
					(thickness 0.15)
				)
				(justify mirror)
			)
		)
		(property "Voltage" ""
			(at -16.1 220.65 0)
			(layer "B.Fab")
			(hide yes)
			(effects
				(font
					(size 1 1)
					(thickness 0.15)
				)
				(justify mirror)
			)
		)
		(sheetname "/FPGA power supply/")
		(sheetfile "fpga-power-supply.kicad_sch")
		(attr smd)
		(fp_rect
			(start -0.925 0.47)
			(end 0.925 -0.47)
			(stroke
				(width 0.05)
				(type default)
			)
			(fill no)
			(layer "B.CrtYd")
		)
		(fp_line
			(start -0.494 0.25)
			(end 0.504 0.25)
			(stroke
				(width 0.15)
				(type solid)
			)
			(layer "B.Fab")
		)
		(fp_line
			(start 0.504 0.25)
			(end 0.504 -0.248)
			(stroke
				(width 0.15)
				(type solid)
			)
			(layer "B.Fab")
		)
		(fp_line
			(start -0.494 -0.248)
			(end -0.494 0.25)
			(stroke
				(width 0.15)
				(type solid)
			)
			(layer "B.Fab")
		)
		(fp_line
			(start 0.504 -0.248)
			(end -0.494 -0.248)
			(stroke
				(width 0.15)
				(type solid)
			)
			(layer "B.Fab")
		)
		(pad "1" smd roundrect
			(at -0.48 0 270)
			(size 0.59 0.64)
			(layers "B.Cu" "B.Mask" "B.Paste")
			(roundrect_rratio 0.25)
			(net 1 "GND")
			(pintype "passive")
		)
		(pad "2" smd roundrect
			(at 0.48 0 270)
			(size 0.59 0.64)
			(layers "B.Cu" "B.Mask" "B.Paste")
			(roundrect_rratio 0.25)
			(net 5 "VCC1V8")
			(pintype "passive")
		)
	)
	(footprint "antmicro-footprints:C_0201"
		(layer "B.Cu")
		(at 98.325 121.675)
		(descr "Capacitor SMD 0201")
		(tags "capacitor SMD 0201")
		(property "Reference" "C146"
			(at -22.425 0.825 0)
			(layer "B.SilkS")
			(effects
				(font
					(size 0.7 0.7)
					(thickness 0.15)
				)
				(justify right bottom mirror)
			)
		)
		(property "Value" "C_470n_0201"
			(at 0 -1.4 0)
			(layer "B.Fab")
			(effects
				(font
					(size 0.7 0.7)
					(thickness 0.15)
				)
				(justify right bottom mirror)
			)
		)
		(property "Datasheet" "https://product.tdk.com/en/search/capacitor/ceramic/mlcc/info?part_no=C0603X5R1A474M030BC"
			(at 0 0 0)
			(layer "F.Fab")
			(hide yes)
			(effects
				(font
					(size 1.27 1.27)
					(thickness 0.15)
				)
			)
		)
		(property "Description" "SMD Multilayer Ceramic Capacitor, 0.47 µF, 10 V, 0201 [0603 Metric], ± 20%, X5R, C"
			(at 0 0 0)
			(layer "F.Fab")
			(hide yes)
			(effects
				(font
					(size 1.27 1.27)
					(thickness 0.15)
				)
			)
		)
		(property "Author" "Antmicro"
			(at 0 0 0)
			(layer "B.Fab")
			(hide yes)
			(effects
				(font
					(size 1 1)
					(thickness 0.15)
				)
				(justify mirror)
			)
		)
		(property "Dielectric" ""
			(at 0 0 0)
			(layer "B.Fab")
			(hide yes)
			(effects
				(font
					(size 1 1)
					(thickness 0.15)
				)
				(justify mirror)
			)
		)
		(property "License" "Apache-2.0"
			(at 0 0 0)
			(layer "B.Fab")
			(hide yes)
			(effects
				(font
					(size 1 1)
					(thickness 0.15)
				)
				(justify mirror)
			)
		)
		(property "MPN" "C0603X5R1A474M030BC"
			(at 0 0 0)
			(layer "B.Fab")
			(hide yes)
			(effects
				(font
					(size 1 1)
					(thickness 0.15)
				)
				(justify mirror)
			)
		)
		(property "Manufacturer" "TDK"
			(at 0 0 0)
			(layer "B.Fab")
			(hide yes)
			(effects
				(font
					(size 1 1)
					(thickness 0.15)
				)
				(justify mirror)
			)
		)
		(property "Public" "False"
			(at 0 0 0)
			(layer "B.Fab")
			(hide yes)
			(effects
				(font
					(size 1 1)
					(thickness 0.15)
				)
				(justify mirror)
			)
		)
		(property "Val" "470n"
			(at 0 0 0)
			(layer "B.Fab")
			(hide yes)
			(effects
				(font
					(size 1 1)
					(thickness 0.15)
				)
				(justify mirror)
			)
		)
		(property "Voltage" ""
			(at 0 0 0)
			(layer "B.Fab")
			(hide yes)
			(effects
				(font
					(size 1 1)
					(thickness 0.15)
				)
				(justify mirror)
			)
		)
		(sheetname "/FPGA power supply/")
		(sheetfile "fpga-power-supply.kicad_sch")
		(attr smd)
		(fp_rect
			(start -0.7 0.35)
			(end 0.7 -0.35)
			(stroke
				(width 0.05)
				(type default)
			)
			(fill no)
			(layer "B.CrtYd")
		)
		(fp_rect
			(start 0.3 -0.15)
			(end -0.301 0.149)
			(stroke
				(width 0.15)
				(type solid)
			)
			(fill no)
			(layer "B.Fab")
		)
		(pad "" smd roundrect
			(at -0.349 0.002)
			(size 0.318 0.36)
			(layers "B.Paste")
			(roundrect_rratio 0.25)
		)
		(pad "" smd roundrect
			(at 0.341 0.002)
			(size 0.318 0.36)
			(layers "B.Paste")
			(roundrect_rratio 0.25)
		)
		(pad "1" smd roundrect
			(at -0.321 0.002)
			(size 0.46 0.4)
			(layers "B.Cu" "B.Mask")
			(roundrect_rratio 0.25)
			(net 1 "GND")
			(pintype "passive")
		)
		(pad "2" smd roundrect
			(at 0.32 0.002)
			(size 0.46 0.4)
			(layers "B.Cu" "B.Mask")
			(roundrect_rratio 0.25)
			(net 5 "VCC1V8")
			(pintype "passive")
		)
	)
	(footprint "antmicro-footprints:C_0402_1005Metric"
		(layer "B.Cu")
		(at 100.275 118.375 -90)
		(descr "Capacitor SMD 0402")
		(tags "capacitor SMD 0402")
		(property "Reference" "C148"
			(at -1.575 0.475 90)
			(layer "B.SilkS")
			(effects
				(font
					(size 0.7 0.7)
					(thickness 0.15)
				)
				(justify left bottom mirror)
			)
		)
		(property "Value" "C_470n_0402"
			(at 0 -1.4 90)
			(layer "B.Fab")
			(effects
				(font
					(size 0.7 0.7)
					(thickness 0.15)
				)
				(justify left bottom mirror)
			)
		)
		(property "Datasheet" "https://product.tdk.com/en/search/capacitor/ceramic/mlcc/info?part_no=C1005X5R1E474M050BB"
			(at 0 0 270)
			(layer "F.Fab")
			(hide yes)
			(effects
				(font
					(size 1.27 1.27)
					(thickness 0.15)
				)
			)
		)
		(property "Description" "SMD Multilayer Ceramic Capacitor, 0.47 µF, 25 V, 0402 [1005 Metric], ± 20%, X5R, C"
			(at 0 0 270)
			(layer "F.Fab")
			(hide yes)
			(effects
				(font
					(size 1.27 1.27)
					(thickness 0.15)
				)
			)
		)
		(property "Author" "Antmicro"
			(at -18.1 218.65 0)
			(layer "B.Fab")
			(hide yes)
			(effects
				(font
					(size 1 1)
					(thickness 0.15)
				)
				(justify mirror)
			)
		)
		(property "Dielectric" ""
			(at -18.1 218.65 0)
			(layer "B.Fab")
			(hide yes)
			(effects
				(font
					(size 1 1)
					(thickness 0.15)
				)
				(justify mirror)
			)
		)
		(property "License" "Apache-2.0"
			(at -18.1 218.65 0)
			(layer "B.Fab")
			(hide yes)
			(effects
				(font
					(size 1 1)
					(thickness 0.15)
				)
				(justify mirror)
			)
		)
		(property "MPN" "C1005X5R1E474M050BB"
			(at -18.1 218.65 0)
			(layer "B.Fab")
			(hide yes)
			(effects
				(font
					(size 1 1)
					(thickness 0.15)
				)
				(justify mirror)
			)
		)
		(property "Manufacturer" "TDK"
			(at -18.1 218.65 0)
			(layer "B.Fab")
			(hide yes)
			(effects
				(font
					(size 1 1)
					(thickness 0.15)
				)
				(justify mirror)
			)
		)
		(property "Val" "470n"
			(at -18.1 218.65 0)
			(layer "B.Fab")
			(hide yes)
			(effects
				(font
					(size 1 1)
					(thickness 0.15)
				)
				(justify mirror)
			)
		)
		(property "Voltage" ""
			(at -18.1 218.65 0)
			(layer "B.Fab")
			(hide yes)
			(effects
				(font
					(size 1 1)
					(thickness 0.15)
				)
				(justify mirror)
			)
		)
		(sheetname "/FPGA power supply/")
		(sheetfile "fpga-power-supply.kicad_sch")
		(attr smd)
		(fp_rect
			(start -0.925 0.47)
			(end 0.925 -0.47)
			(stroke
				(width 0.05)
				(type default)
			)
			(fill no)
			(layer "B.CrtYd")
		)
		(fp_line
			(start -0.494 0.25)
			(end 0.504 0.25)
			(stroke
				(width 0.15)
				(type solid)
			)
			(layer "B.Fab")
		)
		(fp_line
			(start 0.504 0.25)
			(end 0.504 -0.248)
			(stroke
				(width 0.15)
				(type solid)
			)
			(layer "B.Fab")
		)
		(fp_line
			(start -0.494 -0.248)
			(end -0.494 0.25)
			(stroke
				(width 0.15)
				(type solid)
			)
			(layer "B.Fab")
		)
		(fp_line
			(start 0.504 -0.248)
			(end -0.494 -0.248)
			(stroke
				(width 0.15)
				(type solid)
			)
			(layer "B.Fab")
		)
		(pad "1" smd roundrect
			(at -0.48 0 270)
			(size 0.59 0.64)
			(layers "B.Cu" "B.Mask" "B.Paste")
			(roundrect_rratio 0.25)
			(net 1 "GND")
			(pintype "passive")
		)
		(pad "2" smd roundrect
			(at 0.48 0 270)
			(size 0.59 0.64)
			(layers "B.Cu" "B.Mask" "B.Paste")
			(roundrect_rratio 0.25)
			(net 5 "VCC1V8")
			(pintype "passive")
		)
	)
	(footprint "antmicro-footprints:C_0402_1005Metric"
		(layer "B.Cu")
		(at 107.225 148.275 90)
		(descr "Capacitor SMD 0402")
		(tags "capacitor SMD 0402")
		(property "Reference" "C63"
			(at -2.925 0.375 90)
			(layer "B.SilkS")
			(effects
				(font
					(size 0.7 0.7)
					(thickness 0.15)
				)
				(justify right bottom mirror)
			)
		)
		(property "Value" "C_100n_6V3_0402"
			(at 0 -1.4 90)
			(layer "B.Fab")
			(effects
				(font
					(size 0.7 0.7)
					(thickness 0.15)
				)
				(justify right bottom mirror)
			)
		)
		(property "Datasheet" "https://www.passivecomponent.com/wp-content/uploads/datasheet/WTC_MLCC_General_Purpose.pdf"
			(at 0 0 90)
			(layer "F.Fab")
			(hide yes)
			(effects
				(font
					(size 1.27 1.27)
					(thickness 0.15)
				)
			)
		)
		(property "Description" "SMT Multilayer Ceramic Capacitor, 0.1 µF, 6.3 V, 0402 [1005 Metric], ± 10%, X5R, Walsin MLCC"
			(at 0 0 90)
			(layer "F.Fab")
			(hide yes)
			(effects
				(font
					(size 1.27 1.27)
					(thickness 0.15)
				)
			)
		)
		(property "Author" "Antmicro"
			(at 255.5 41.05 0)
			(layer "B.Fab")
			(hide yes)
			(effects
				(font
					(size 1 1)
					(thickness 0.15)
				)
				(justify mirror)
			)
		)
		(property "Dielectric" ""
			(at 255.5 41.05 0)
			(layer "B.Fab")
			(hide yes)
			(effects
				(font
					(size 1 1)
					(thickness 0.15)
				)
				(justify mirror)
			)
		)
		(property "License" "Apache-2.0"
			(at 255.5 41.05 0)
			(layer "B.Fab")
			(hide yes)
			(effects
				(font
					(size 1 1)
					(thickness 0.15)
				)
				(justify mirror)
			)
		)
		(property "MPN" "0402X104K6R3CT"
			(at 255.5 41.05 0)
			(layer "B.Fab")
			(hide yes)
			(effects
				(font
					(size 1 1)
					(thickness 0.15)
				)
				(justify mirror)
			)
		)
		(property "Manufacturer" "Walsin"
			(at 255.5 41.05 0)
			(layer "B.Fab")
			(hide yes)
			(effects
				(font
					(size 1 1)
					(thickness 0.15)
				)
				(justify mirror)
			)
		)
		(property "Public" "False"
			(at 255.5 41.05 0)
			(layer "B.Fab")
			(hide yes)
			(effects
				(font
					(size 1 1)
					(thickness 0.15)
				)
				(justify mirror)
			)
		)
		(property "Val" "100n"
			(at 255.5 41.05 0)
			(layer "B.Fab")
			(hide yes)
			(effects
				(font
					(size 1 1)
					(thickness 0.15)
				)
				(justify mirror)
			)
		)
		(property "Voltage" ""
			(at 255.5 41.05 0)
			(layer "B.Fab")
			(hide yes)
			(effects
				(font
					(size 1 1)
					(thickness 0.15)
				)
				(justify mirror)
			)
		)
		(sheetname "/DDR3/")
		(sheetfile "ddr3.kicad_sch")
		(attr smd)
		(fp_rect
			(start -0.925 0.47)
			(end 0.925 -0.47)
			(stroke
				(width 0.05)
				(type default)
			)
			(fill no)
			(layer "B.CrtYd")
		)
		(fp_line
			(start 0.504 -0.248)
			(end -0.494 -0.248)
			(stroke
				(width 0.15)
				(type solid)
			)
			(layer "B.Fab")
		)
		(fp_line
			(start -0.494 -0.248)
			(end -0.494 0.25)
			(stroke
				(width 0.15)
				(type solid)
			)
			(layer "B.Fab")
		)
		(fp_line
			(start 0.504 0.25)
			(end 0.504 -0.248)
			(stroke
				(width 0.15)
				(type solid)
			)
			(layer "B.Fab")
		)
		(fp_line
			(start -0.494 0.25)
			(end 0.504 0.25)
			(stroke
				(width 0.15)
				(type solid)
			)
			(layer "B.Fab")
		)
		(pad "1" smd roundrect
			(at -0.48 0 90)
			(size 0.59 0.64)
			(layers "B.Cu" "B.Mask" "B.Paste")
			(roundrect_rratio 0.25)
			(net 109 "Net-(C63-Pad1)")
			(pintype "passive")
		)
		(pad "2" smd roundrect
			(at 0.48 0 90)
			(size 0.59 0.64)
			(layers "B.Cu" "B.Mask" "B.Paste")
			(roundrect_rratio 0.25)
			(net 1 "GND")
			(pintype "passive")
		)
	)
	(footprint "antmicro-footprints:R_0402_1005Metric"
		(layer "B.Cu")
		(at 105.175 148.275 90)
		(descr "Resistor SMD 0402")
		(tags "resistor SMD 0402")
		(property "Reference" "R100"
			(at -3.625 0.375 90)
			(layer "B.SilkS")
			(effects
				(font
					(size 0.7 0.7)
					(thickness 0.15)
				)
				(justify right bottom mirror)
			)
		)
		(property "Value" "R_51R_0402"
			(at 0 -1.4 90)
			(layer "B.Fab")
			(effects
				(font
					(size 0.7 0.7)
					(thickness 0.15)
				)
				(justify right bottom mirror)
			)
		)
		(property "Datasheet" "https://www.bourns.com/docs/product-datasheets/cr.pdf"
			(at 0 0 90)
			(layer "F.Fab")
			(hide yes)
			(effects
				(font
					(size 1.27 1.27)
					(thickness 0.15)
				)
			)
		)
		(property "Description" "SMD Chip Resistor, 51 ohm, ± 1%, 63 mW, 0402 [1005 Metric], Thick Film, General Purpose"
			(at 0 0 90)
			(layer "F.Fab")
			(hide yes)
			(effects
				(font
					(size 1.27 1.27)
					(thickness 0.15)
				)
			)
		)
		(property "Author" "Antmicro"
			(at 253.45 43.1 0)
			(layer "B.Fab")
			(hide yes)
			(effects
				(font
					(size 1 1)
					(thickness 0.15)
				)
				(justify mirror)
			)
		)
		(property "License" "Apache-2.0"
			(at 253.45 43.1 0)
			(layer "B.Fab")
			(hide yes)
			(effects
				(font
					(size 1 1)
					(thickness 0.15)
				)
				(justify mirror)
			)
		)
		(property "MPN" "CR0402-FX-51R0GLF"
			(at 253.45 43.1 0)
			(layer "B.Fab")
			(hide yes)
			(effects
				(font
					(size 1 1)
					(thickness 0.15)
				)
				(justify mirror)
			)
		)
		(property "Manufacturer" "Bourns"
			(at 253.45 43.1 0)
			(layer "B.Fab")
			(hide yes)
			(effects
				(font
					(size 1 1)
					(thickness 0.15)
				)
				(justify mirror)
			)
		)
		(property "Tolerance" "1%"
			(at 253.45 43.1 0)
			(layer "B.Fab")
			(hide yes)
			(effects
				(font
					(size 1 1)
					(thickness 0.15)
				)
				(justify mirror)
			)
		)
		(property "Val" "51R"
			(at 253.45 43.1 0)
			(layer "B.Fab")
			(hide yes)
			(effects
				(font
					(size 1 1)
					(thickness 0.15)
				)
				(justify mirror)
			)
		)
		(sheetname "/DDR3/")
		(sheetfile "ddr3.kicad_sch")
		(attr smd exclude_from_pos_files exclude_from_bom dnp)
		(fp_rect
			(start -0.925 0.47)
			(end 0.925 -0.47)
			(stroke
				(width 0.05)
				(type default)
			)
			(fill no)
			(layer "B.CrtYd")
		)
		(fp_rect
			(start -0.5 0.25)
			(end 0.5 -0.25)
			(stroke
				(width 0.15)
				(type solid)
			)
			(fill no)
			(layer "B.Fab")
		)
		(pad "1" smd roundrect
			(at -0.48 0 90)
			(size 0.59 0.64)
			(layers "B.Cu" "B.Mask" "B.Paste")
			(roundrect_rratio 0.25)
			(net 109 "Net-(C63-Pad1)")
			(pintype "passive")
		)
		(pad "2" smd roundrect
			(at 0.48 0 90)
			(size 0.59 0.64)
			(layers "B.Cu" "B.Mask" "B.Paste")
			(roundrect_rratio 0.25)
			(net 478 "DDR3_CLK_N")
			(pintype "passive")
		)
	)
	(footprint "antmicro-footprints:C_0402_1005Metric"
		(layer "B.Cu")
		(at 107.275 114.475 -90)
		(descr "Capacitor SMD 0402")
		(tags "capacitor SMD 0402")
		(property "Reference" "C109"
			(at -1.475 -1.225 90)
			(layer "B.SilkS")
			(effects
				(font
					(size 0.7 0.7)
					(thickness 0.15)
				)
				(justify left bottom mirror)
			)
		)
		(property "Value" "C_470n_0402"
			(at 0 -1.4 90)
			(layer "B.Fab")
			(effects
				(font
					(size 0.7 0.7)
					(thickness 0.15)
				)
				(justify left bottom mirror)
			)
		)
		(property "Datasheet" "https://product.tdk.com/en/search/capacitor/ceramic/mlcc/info?part_no=C1005X5R1E474M050BB"
			(at 0 0 270)
			(layer "F.Fab")
			(hide yes)
			(effects
				(font
					(size 1.27 1.27)
					(thickness 0.15)
				)
			)
		)
		(property "Description" "SMD Multilayer Ceramic Capacitor, 0.47 µF, 25 V, 0402 [1005 Metric], ± 20%, X5R, C"
			(at 0 0 270)
			(layer "F.Fab")
			(hide yes)
			(effects
				(font
					(size 1.27 1.27)
					(thickness 0.15)
				)
			)
		)
		(property "Author" "Antmicro"
			(at -7.2 221.75 0)
			(layer "B.Fab")
			(hide yes)
			(effects
				(font
					(size 1 1)
					(thickness 0.15)
				)
				(justify mirror)
			)
		)
		(property "Dielectric" ""
			(at -7.2 221.75 0)
			(layer "B.Fab")
			(hide yes)
			(effects
				(font
					(size 1 1)
					(thickness 0.15)
				)
				(justify mirror)
			)
		)
		(property "License" "Apache-2.0"
			(at -7.2 221.75 0)
			(layer "B.Fab")
			(hide yes)
			(effects
				(font
					(size 1 1)
					(thickness 0.15)
				)
				(justify mirror)
			)
		)
		(property "MPN" "C1005X5R1E474M050BB"
			(at -7.2 221.75 0)
			(layer "B.Fab")
			(hide yes)
			(effects
				(font
					(size 1 1)
					(thickness 0.15)
				)
				(justify mirror)
			)
		)
		(property "Manufacturer" "TDK"
			(at -7.2 221.75 0)
			(layer "B.Fab")
			(hide yes)
			(effects
				(font
					(size 1 1)
					(thickness 0.15)
				)
				(justify mirror)
			)
		)
		(property "Val" "470n"
			(at -7.2 221.75 0)
			(layer "B.Fab")
			(hide yes)
			(effects
				(font
					(size 1 1)
					(thickness 0.15)
				)
				(justify mirror)
			)
		)
		(property "Voltage" ""
			(at -7.2 221.75 0)
			(layer "B.Fab")
			(hide yes)
			(effects
				(font
					(size 1 1)
					(thickness 0.15)
				)
				(justify mirror)
			)
		)
		(sheetname "/FPGA banks 34-35 & CFG/")
		(sheetfile "fpga-banks-34-25-cfg.kicad_sch")
		(attr smd)
		(fp_rect
			(start -0.925 0.47)
			(end 0.925 -0.47)
			(stroke
				(width 0.05)
				(type default)
			)
			(fill no)
			(layer "B.CrtYd")
		)
		(fp_line
			(start -0.494 0.25)
			(end 0.504 0.25)
			(stroke
				(width 0.15)
				(type solid)
			)
			(layer "B.Fab")
		)
		(fp_line
			(start 0.504 0.25)
			(end 0.504 -0.248)
			(stroke
				(width 0.15)
				(type solid)
			)
			(layer "B.Fab")
		)
		(fp_line
			(start -0.494 -0.248)
			(end -0.494 0.25)
			(stroke
				(width 0.15)
				(type solid)
			)
			(layer "B.Fab")
		)
		(fp_line
			(start 0.504 -0.248)
			(end -0.494 -0.248)
			(stroke
				(width 0.15)
				(type solid)
			)
			(layer "B.Fab")
		)
		(pad "1" smd roundrect
			(at -0.48 0 270)
			(size 0.59 0.64)
			(layers "B.Cu" "B.Mask" "B.Paste")
			(roundrect_rratio 0.25)
			(net 1 "GND")
			(pintype "passive")
		)
		(pad "2" smd roundrect
			(at 0.48 0 270)
			(size 0.59 0.64)
			(layers "B.Cu" "B.Mask" "B.Paste")
			(roundrect_rratio 0.25)
			(net 2 "VCC3V3")
			(pintype "passive")
		)
	)
	(footprint "antmicro-footprints:C_0402_1005Metric"
		(layer "B.Cu")
		(at 111.275 112.575 -90)
		(descr "Capacitor SMD 0402")
		(tags "capacitor SMD 0402")
		(property "Reference" "C121"
			(at -1.375 -1.225 90)
			(layer "B.SilkS")
			(effects
				(font
					(size 0.7 0.7)
					(thickness 0.15)
				)
				(justify left bottom mirror)
			)
		)
		(property "Value" "C_470n_0402"
			(at 0 -1.4 90)
			(layer "B.Fab")
			(effects
				(font
					(size 0.7 0.7)
					(thickness 0.15)
				)
				(justify left bottom mirror)
			)
		)
		(property "Datasheet" "https://product.tdk.com/en/search/capacitor/ceramic/mlcc/info?part_no=C1005X5R1E474M050BB"
			(at 0 0 270)
			(layer "F.Fab")
			(hide yes)
			(effects
				(font
					(size 1.27 1.27)
					(thickness 0.15)
				)
			)
		)
		(property "Description" "SMD Multilayer Ceramic Capacitor, 0.47 µF, 25 V, 0402 [1005 Metric], ± 20%, X5R, C"
			(at 0 0 270)
			(layer "F.Fab")
			(hide yes)
			(effects
				(font
					(size 1.27 1.27)
					(thickness 0.15)
				)
			)
		)
		(property "Author" "Antmicro"
			(at -1.3 223.85 0)
			(layer "B.Fab")
			(hide yes)
			(effects
				(font
					(size 1 1)
					(thickness 0.15)
				)
				(justify mirror)
			)
		)
		(property "Dielectric" ""
			(at -1.3 223.85 0)
			(layer "B.Fab")
			(hide yes)
			(effects
				(font
					(size 1 1)
					(thickness 0.15)
				)
				(justify mirror)
			)
		)
		(property "License" "Apache-2.0"
			(at -1.3 223.85 0)
			(layer "B.Fab")
			(hide yes)
			(effects
				(font
					(size 1 1)
					(thickness 0.15)
				)
				(justify mirror)
			)
		)
		(property "MPN" "C1005X5R1E474M050BB"
			(at -1.3 223.85 0)
			(layer "B.Fab")
			(hide yes)
			(effects
				(font
					(size 1 1)
					(thickness 0.15)
				)
				(justify mirror)
			)
		)
		(property "Manufacturer" "TDK"
			(at -1.3 223.85 0)
			(layer "B.Fab")
			(hide yes)
			(effects
				(font
					(size 1 1)
					(thickness 0.15)
				)
				(justify mirror)
			)
		)
		(property "Val" "470n"
			(at -1.3 223.85 0)
			(layer "B.Fab")
			(hide yes)
			(effects
				(font
					(size 1 1)
					(thickness 0.15)
				)
				(justify mirror)
			)
		)
		(property "Voltage" ""
			(at -1.3 223.85 0)
			(layer "B.Fab")
			(hide yes)
			(effects
				(font
					(size 1 1)
					(thickness 0.15)
				)
				(justify mirror)
			)
		)
		(sheetname "/FPGA banks 34-35 & CFG/")
		(sheetfile "fpga-banks-34-25-cfg.kicad_sch")
		(attr smd)
		(fp_rect
			(start -0.925 0.47)
			(end 0.925 -0.47)
			(stroke
				(width 0.05)
				(type default)
			)
			(fill no)
			(layer "B.CrtYd")
		)
		(fp_line
			(start -0.494 0.25)
			(end 0.504 0.25)
			(stroke
				(width 0.15)
				(type solid)
			)
			(layer "B.Fab")
		)
		(fp_line
			(start 0.504 0.25)
			(end 0.504 -0.248)
			(stroke
				(width 0.15)
				(type solid)
			)
			(layer "B.Fab")
		)
		(fp_line
			(start -0.494 -0.248)
			(end -0.494 0.25)
			(stroke
				(width 0.15)
				(type solid)
			)
			(layer "B.Fab")
		)
		(fp_line
			(start 0.504 -0.248)
			(end -0.494 -0.248)
			(stroke
				(width 0.15)
				(type solid)
			)
			(layer "B.Fab")
		)
		(pad "1" smd roundrect
			(at -0.48 0 270)
			(size 0.59 0.64)
			(layers "B.Cu" "B.Mask" "B.Paste")
			(roundrect_rratio 0.25)
			(net 1 "GND")
			(pintype "passive")
		)
		(pad "2" smd roundrect
			(at 0.48 0 270)
			(size 0.59 0.64)
			(layers "B.Cu" "B.Mask" "B.Paste")
			(roundrect_rratio 0.25)
			(net 2 "VCC3V3")
			(pintype "passive")
		)
	)
	(footprint "antmicro-footprints:C_0402_1005Metric"
		(layer "B.Cu")
		(at 109.275 118.675 180)
		(descr "Capacitor SMD 0402")
		(tags "capacitor SMD 0402")
		(property "Reference" "C127"
			(at -3.623 -0.425 0)
			(layer "B.SilkS")
			(effects
				(font
					(size 0.7 0.7)
					(thickness 0.15)
				)
				(justify left bottom mirror)
			)
		)
		(property "Value" "C_470n_0402"
			(at 0 -1.4 0)
			(layer "B.Fab")
			(effects
				(font
					(size 0.7 0.7)
					(thickness 0.15)
				)
				(justify left bottom mirror)
			)
		)
		(property "Datasheet" "https://product.tdk.com/en/search/capacitor/ceramic/mlcc/info?part_no=C1005X5R1E474M050BB"
			(at 0 0 180)
			(layer "F.Fab")
			(hide yes)
			(effects
				(font
					(size 1.27 1.27)
					(thickness 0.15)
				)
			)
		)
		(property "Description" "SMD Multilayer Ceramic Capacitor, 0.47 µF, 25 V, 0402 [1005 Metric], ± 20%, X5R, C"
			(at 0 0 180)
			(layer "F.Fab")
			(hide yes)
			(effects
				(font
					(size 1.27 1.27)
					(thickness 0.15)
				)
			)
		)
		(property "Author" "Antmicro"
			(at 218.55 237.35 0)
			(layer "B.Fab")
			(hide yes)
			(effects
				(font
					(size 1 1)
					(thickness 0.15)
				)
				(justify mirror)
			)
		)
		(property "Dielectric" ""
			(at 218.55 237.35 0)
			(layer "B.Fab")
			(hide yes)
			(effects
				(font
					(size 1 1)
					(thickness 0.15)
				)
				(justify mirror)
			)
		)
		(property "License" "Apache-2.0"
			(at 218.55 237.35 0)
			(layer "B.Fab")
			(hide yes)
			(effects
				(font
					(size 1 1)
					(thickness 0.15)
				)
				(justify mirror)
			)
		)
		(property "MPN" "C1005X5R1E474M050BB"
			(at 218.55 237.35 0)
			(layer "B.Fab")
			(hide yes)
			(effects
				(font
					(size 1 1)
					(thickness 0.15)
				)
				(justify mirror)
			)
		)
		(property "Manufacturer" "TDK"
			(at 218.55 237.35 0)
			(layer "B.Fab")
			(hide yes)
			(effects
				(font
					(size 1 1)
					(thickness 0.15)
				)
				(justify mirror)
			)
		)
		(property "Val" "470n"
			(at 218.55 237.35 0)
			(layer "B.Fab")
			(hide yes)
			(effects
				(font
					(size 1 1)
					(thickness 0.15)
				)
				(justify mirror)
			)
		)
		(property "Voltage" ""
			(at 218.55 237.35 0)
			(layer "B.Fab")
			(hide yes)
			(effects
				(font
					(size 1 1)
					(thickness 0.15)
				)
				(justify mirror)
			)
		)
		(sheetname "/FPGA banks 34-35 & CFG/")
		(sheetfile "fpga-banks-34-25-cfg.kicad_sch")
		(attr smd)
		(fp_rect
			(start -0.925 0.47)
			(end 0.925 -0.47)
			(stroke
				(width 0.05)
				(type default)
			)
			(fill no)
			(layer "B.CrtYd")
		)
		(fp_line
			(start 0.504 0.25)
			(end 0.504 -0.248)
			(stroke
				(width 0.15)
				(type solid)
			)
			(layer "B.Fab")
		)
		(fp_line
			(start 0.504 -0.248)
			(end -0.494 -0.248)
			(stroke
				(width 0.15)
				(type solid)
			)
			(layer "B.Fab")
		)
		(fp_line
			(start -0.494 0.25)
			(end 0.504 0.25)
			(stroke
				(width 0.15)
				(type solid)
			)
			(layer "B.Fab")
		)
		(fp_line
			(start -0.494 -0.248)
			(end -0.494 0.25)
			(stroke
				(width 0.15)
				(type solid)
			)
			(layer "B.Fab")
		)
		(pad "1" smd roundrect
			(at -0.48 0 180)
			(size 0.59 0.64)
			(layers "B.Cu" "B.Mask" "B.Paste")
			(roundrect_rratio 0.25)
			(net 1 "GND")
			(pintype "passive")
		)
		(pad "2" smd roundrect
			(at 0.48 0 180)
			(size 0.59 0.64)
			(layers "B.Cu" "B.Mask" "B.Paste")
			(roundrect_rratio 0.25)
			(net 2 "VCC3V3")
			(pintype "passive")
		)
	)
	(footprint "antmicro-footprints:C_0402_1005Metric"
		(layer "B.Cu")
		(at 104.275 115.675)
		(descr "Capacitor SMD 0402")
		(tags "capacitor SMD 0402")
		(property "Reference" "C110"
			(at -4.075 0.925 0)
			(layer "B.SilkS")
			(effects
				(font
					(size 0.7 0.7)
					(thickness 0.15)
				)
				(justify right bottom mirror)
			)
		)
		(property "Value" "C_470n_0402"
			(at 0 -1.4 0)
			(layer "B.Fab")
			(effects
				(font
					(size 0.7 0.7)
					(thickness 0.15)
				)
				(justify right bottom mirror)
			)
		)
		(property "Datasheet" "https://product.tdk.com/en/search/capacitor/ceramic/mlcc/info?part_no=C1005X5R1E474M050BB"
			(at 0 0 0)
			(layer "F.Fab")
			(hide yes)
			(effects
				(font
					(size 1.27 1.27)
					(thickness 0.15)
				)
			)
		)
		(property "Description" "SMD Multilayer Ceramic Capacitor, 0.47 µF, 25 V, 0402 [1005 Metric], ± 20%, X5R, C"
			(at 0 0 0)
			(layer "F.Fab")
			(hide yes)
			(effects
				(font
					(size 1.27 1.27)
					(thickness 0.15)
				)
			)
		)
		(property "Author" "Antmicro"
			(at 0 0 0)
			(layer "B.Fab")
			(hide yes)
			(effects
				(font
					(size 1 1)
					(thickness 0.15)
				)
				(justify mirror)
			)
		)
		(property "Dielectric" ""
			(at 0 0 0)
			(layer "B.Fab")
			(hide yes)
			(effects
				(font
					(size 1 1)
					(thickness 0.15)
				)
				(justify mirror)
			)
		)
		(property "License" "Apache-2.0"
			(at 0 0 0)
			(layer "B.Fab")
			(hide yes)
			(effects
				(font
					(size 1 1)
					(thickness 0.15)
				)
				(justify mirror)
			)
		)
		(property "MPN" "C1005X5R1E474M050BB"
			(at 0 0 0)
			(layer "B.Fab")
			(hide yes)
			(effects
				(font
					(size 1 1)
					(thickness 0.15)
				)
				(justify mirror)
			)
		)
		(property "Manufacturer" "TDK"
			(at 0 0 0)
			(layer "B.Fab")
			(hide yes)
			(effects
				(font
					(size 1 1)
					(thickness 0.15)
				)
				(justify mirror)
			)
		)
		(property "Val" "470n"
			(at 0 0 0)
			(layer "B.Fab")
			(hide yes)
			(effects
				(font
					(size 1 1)
					(thickness 0.15)
				)
				(justify mirror)
			)
		)
		(property "Voltage" ""
			(at 0 0 0)
			(layer "B.Fab")
			(hide yes)
			(effects
				(font
					(size 1 1)
					(thickness 0.15)
				)
				(justify mirror)
			)
		)
		(property "DNP" ""
			(at 0 0 0)
			(unlocked yes)
			(layer "B.Fab")
			(hide yes)
			(effects
				(font
					(size 1 1)
					(thickness 0.15)
				)
				(justify mirror)
			)
		)
		(sheetname "/FPGA banks 13-16/")
		(sheetfile "fpga-banks-13-16.kicad_sch")
		(attr smd)
		(fp_rect
			(start -0.925 0.47)
			(end 0.925 -0.47)
			(stroke
				(width 0.05)
				(type default)
			)
			(fill no)
			(layer "B.CrtYd")
		)
		(fp_line
			(start -0.494 -0.248)
			(end -0.494 0.25)
			(stroke
				(width 0.15)
				(type solid)
			)
			(layer "B.Fab")
		)
		(fp_line
			(start -0.494 0.25)
			(end 0.504 0.25)
			(stroke
				(width 0.15)
				(type solid)
			)
			(layer "B.Fab")
		)
		(fp_line
			(start 0.504 -0.248)
			(end -0.494 -0.248)
			(stroke
				(width 0.15)
				(type solid)
			)
			(layer "B.Fab")
		)
		(fp_line
			(start 0.504 0.25)
			(end 0.504 -0.248)
			(stroke
				(width 0.15)
				(type solid)
			)
			(layer "B.Fab")
		)
		(pad "1" smd roundrect
			(at -0.48 0)
			(size 0.59 0.64)
			(layers "B.Cu" "B.Mask" "B.Paste")
			(roundrect_rratio 0.25)
			(net 1 "GND")
			(pintype "passive")
		)
		(pad "2" smd roundrect
			(at 0.48 0)
			(size 0.59 0.64)
			(layers "B.Cu" "B.Mask" "B.Paste")
			(roundrect_rratio 0.25)
			(net 2 "VCC3V3")
			(pintype "passive")
		)
	)
	(footprint "antmicro-footprints:C_0402_1005Metric"
		(layer "B.Cu")
		(at 108.275 112.175 180)
		(descr "Capacitor SMD 0402")
		(tags "capacitor SMD 0402")
		(property "Reference" "C116"
			(at -0.625 0.475 0)
			(layer "B.SilkS")
			(effects
				(font
					(size 0.7 0.7)
					(thickness 0.15)
				)
				(justify left bottom mirror)
			)
		)
		(property "Value" "C_470n_0402"
			(at 0 -1.4 0)
			(layer "B.Fab")
			(effects
				(font
					(size 0.7 0.7)
					(thickness 0.15)
				)
				(justify left bottom mirror)
			)
		)
		(property "Datasheet" "https://product.tdk.com/en/search/capacitor/ceramic/mlcc/info?part_no=C1005X5R1E474M050BB"
			(at 0 0 180)
			(layer "F.Fab")
			(hide yes)
			(effects
				(font
					(size 1.27 1.27)
					(thickness 0.15)
				)
			)
		)
		(property "Description" "SMD Multilayer Ceramic Capacitor, 0.47 µF, 25 V, 0402 [1005 Metric], ± 20%, X5R, C"
			(at 0 0 180)
			(layer "F.Fab")
			(hide yes)
			(effects
				(font
					(size 1.27 1.27)
					(thickness 0.15)
				)
			)
		)
		(property "Author" "Antmicro"
			(at 216.55 224.35 0)
			(layer "B.Fab")
			(hide yes)
			(effects
				(font
					(size 1 1)
					(thickness 0.15)
				)
				(justify mirror)
			)
		)
		(property "Dielectric" ""
			(at 216.55 224.35 0)
			(layer "B.Fab")
			(hide yes)
			(effects
				(font
					(size 1 1)
					(thickness 0.15)
				)
				(justify mirror)
			)
		)
		(property "License" "Apache-2.0"
			(at 216.55 224.35 0)
			(layer "B.Fab")
			(hide yes)
			(effects
				(font
					(size 1 1)
					(thickness 0.15)
				)
				(justify mirror)
			)
		)
		(property "MPN" "C1005X5R1E474M050BB"
			(at 216.55 224.35 0)
			(layer "B.Fab")
			(hide yes)
			(effects
				(font
					(size 1 1)
					(thickness 0.15)
				)
				(justify mirror)
			)
		)
		(property "Manufacturer" "TDK"
			(at 216.55 224.35 0)
			(layer "B.Fab")
			(hide yes)
			(effects
				(font
					(size 1 1)
					(thickness 0.15)
				)
				(justify mirror)
			)
		)
		(property "Val" "470n"
			(at 216.55 224.35 0)
			(layer "B.Fab")
			(hide yes)
			(effects
				(font
					(size 1 1)
					(thickness 0.15)
				)
				(justify mirror)
			)
		)
		(property "Voltage" ""
			(at 216.55 224.35 0)
			(layer "B.Fab")
			(hide yes)
			(effects
				(font
					(size 1 1)
					(thickness 0.15)
				)
				(justify mirror)
			)
		)
		(property "DNP" ""
			(at 0 0 180)
			(unlocked yes)
			(layer "B.Fab")
			(hide yes)
			(effects
				(font
					(size 1 1)
					(thickness 0.15)
				)
				(justify mirror)
			)
		)
		(sheetname "/FPGA banks 13-16/")
		(sheetfile "fpga-banks-13-16.kicad_sch")
		(attr smd)
		(fp_rect
			(start -0.925 0.47)
			(end 0.925 -0.47)
			(stroke
				(width 0.05)
				(type default)
			)
			(fill no)
			(layer "B.CrtYd")
		)
		(fp_line
			(start 0.504 0.25)
			(end 0.504 -0.248)
			(stroke
				(width 0.15)
				(type solid)
			)
			(layer "B.Fab")
		)
		(fp_line
			(start 0.504 -0.248)
			(end -0.494 -0.248)
			(stroke
				(width 0.15)
				(type solid)
			)
			(layer "B.Fab")
		)
		(fp_line
			(start -0.494 0.25)
			(end 0.504 0.25)
			(stroke
				(width 0.15)
				(type solid)
			)
			(layer "B.Fab")
		)
		(fp_line
			(start -0.494 -0.248)
			(end -0.494 0.25)
			(stroke
				(width 0.15)
				(type solid)
			)
			(layer "B.Fab")
		)
		(pad "1" smd roundrect
			(at -0.48 0 180)
			(size 0.59 0.64)
			(layers "B.Cu" "B.Mask" "B.Paste")
			(roundrect_rratio 0.25)
			(net 1 "GND")
			(pintype "passive")
		)
		(pad "2" smd roundrect
			(at 0.48 0 180)
			(size 0.59 0.64)
			(layers "B.Cu" "B.Mask" "B.Paste")
			(roundrect_rratio 0.25)
			(net 2 "VCC3V3")
			(pintype "passive")
		)
	)
	(footprint "antmicro-footprints:C_0402_1005Metric"
		(layer "B.Cu")
		(at 103.775 109.975 180)
		(descr "Capacitor SMD 0402")
		(tags "capacitor SMD 0402")
		(property "Reference" "C122"
			(at -1.425 0.575 0)
			(layer "B.SilkS")
			(effects
				(font
					(size 0.7 0.7)
					(thickness 0.15)
				)
				(justify left bottom mirror)
			)
		)
		(property "Value" "C_470n_0402"
			(at 0 -1.4 0)
			(layer "B.Fab")
			(effects
				(font
					(size 0.7 0.7)
					(thickness 0.15)
				)
				(justify left bottom mirror)
			)
		)
		(property "Datasheet" "https://product.tdk.com/en/search/capacitor/ceramic/mlcc/info?part_no=C1005X5R1E474M050BB"
			(at 0 0 180)
			(layer "F.Fab")
			(hide yes)
			(effects
				(font
					(size 1.27 1.27)
					(thickness 0.15)
				)
			)
		)
		(property "Description" "SMD Multilayer Ceramic Capacitor, 0.47 µF, 25 V, 0402 [1005 Metric], ± 20%, X5R, C"
			(at 0 0 180)
			(layer "F.Fab")
			(hide yes)
			(effects
				(font
					(size 1.27 1.27)
					(thickness 0.15)
				)
			)
		)
		(property "Author" "Antmicro"
			(at 207.55 219.95 0)
			(layer "B.Fab")
			(hide yes)
			(effects
				(font
					(size 1 1)
					(thickness 0.15)
				)
				(justify mirror)
			)
		)
		(property "Dielectric" ""
			(at 207.55 219.95 0)
			(layer "B.Fab")
			(hide yes)
			(effects
				(font
					(size 1 1)
					(thickness 0.15)
				)
				(justify mirror)
			)
		)
		(property "License" "Apache-2.0"
			(at 207.55 219.95 0)
			(layer "B.Fab")
			(hide yes)
			(effects
				(font
					(size 1 1)
					(thickness 0.15)
				)
				(justify mirror)
			)
		)
		(property "MPN" "C1005X5R1E474M050BB"
			(at 207.55 219.95 0)
			(layer "B.Fab")
			(hide yes)
			(effects
				(font
					(size 1 1)
					(thickness 0.15)
				)
				(justify mirror)
			)
		)
		(property "Manufacturer" "TDK"
			(at 207.55 219.95 0)
			(layer "B.Fab")
			(hide yes)
			(effects
				(font
					(size 1 1)
					(thickness 0.15)
				)
				(justify mirror)
			)
		)
		(property "Val" "470n"
			(at 207.55 219.95 0)
			(layer "B.Fab")
			(hide yes)
			(effects
				(font
					(size 1 1)
					(thickness 0.15)
				)
				(justify mirror)
			)
		)
		(property "Voltage" ""
			(at 207.55 219.95 0)
			(layer "B.Fab")
			(hide yes)
			(effects
				(font
					(size 1 1)
					(thickness 0.15)
				)
				(justify mirror)
			)
		)
		(property "DNP" ""
			(at 0 0 180)
			(unlocked yes)
			(layer "B.Fab")
			(hide yes)
			(effects
				(font
					(size 1 1)
					(thickness 0.15)
				)
				(justify mirror)
			)
		)
		(sheetname "/FPGA banks 13-16/")
		(sheetfile "fpga-banks-13-16.kicad_sch")
		(attr smd)
		(fp_rect
			(start -0.925 0.47)
			(end 0.925 -0.47)
			(stroke
				(width 0.05)
				(type default)
			)
			(fill no)
			(layer "B.CrtYd")
		)
		(fp_line
			(start 0.504 0.25)
			(end 0.504 -0.248)
			(stroke
				(width 0.15)
				(type solid)
			)
			(layer "B.Fab")
		)
		(fp_line
			(start 0.504 -0.248)
			(end -0.494 -0.248)
			(stroke
				(width 0.15)
				(type solid)
			)
			(layer "B.Fab")
		)
		(fp_line
			(start -0.494 0.25)
			(end 0.504 0.25)
			(stroke
				(width 0.15)
				(type solid)
			)
			(layer "B.Fab")
		)
		(fp_line
			(start -0.494 -0.248)
			(end -0.494 0.25)
			(stroke
				(width 0.15)
				(type solid)
			)
			(layer "B.Fab")
		)
		(pad "1" smd roundrect
			(at -0.48 0 180)
			(size 0.59 0.64)
			(layers "B.Cu" "B.Mask" "B.Paste")
			(roundrect_rratio 0.25)
			(net 1 "GND")
			(pintype "passive")
		)
		(pad "2" smd roundrect
			(at 0.48 0 180)
			(size 0.59 0.64)
			(layers "B.Cu" "B.Mask" "B.Paste")
			(roundrect_rratio 0.25)
			(net 2 "VCC3V3")
			(pintype "passive")
		)
	)
	(footprint "antmicro-footprints:C_0402_1005Metric"
		(layer "B.Cu")
		(at 95.575 112.675 180)
		(descr "Capacitor SMD 0402")
		(tags "capacitor SMD 0402")
		(property "Reference" "C128"
			(at -1.425 0.475 0)
			(layer "B.SilkS")
			(effects
				(font
					(size 0.7 0.7)
					(thickness 0.15)
				)
				(justify left bottom mirror)
			)
		)
		(property "Value" "C_470n_0402"
			(at 0 -1.4 0)
			(layer "B.Fab")
			(effects
				(font
					(size 0.7 0.7)
					(thickness 0.15)
				)
				(justify left bottom mirror)
			)
		)
		(property "Datasheet" "https://product.tdk.com/en/search/capacitor/ceramic/mlcc/info?part_no=C1005X5R1E474M050BB"
			(at 0 0 180)
			(layer "F.Fab")
			(hide yes)
			(effects
				(font
					(size 1.27 1.27)
					(thickness 0.15)
				)
			)
		)
		(property "Description" "SMD Multilayer Ceramic Capacitor, 0.47 µF, 25 V, 0402 [1005 Metric], ± 20%, X5R, C"
			(at 0 0 180)
			(layer "F.Fab")
			(hide yes)
			(effects
				(font
					(size 1.27 1.27)
					(thickness 0.15)
				)
			)
		)
		(property "Author" "Antmicro"
			(at 191.15 225.35 0)
			(layer "B.Fab")
			(hide yes)
			(effects
				(font
					(size 1 1)
					(thickness 0.15)
				)
				(justify mirror)
			)
		)
		(property "Dielectric" ""
			(at 191.15 225.35 0)
			(layer "B.Fab")
			(hide yes)
			(effects
				(font
					(size 1 1)
					(thickness 0.15)
				)
				(justify mirror)
			)
		)
		(property "License" "Apache-2.0"
			(at 191.15 225.35 0)
			(layer "B.Fab")
			(hide yes)
			(effects
				(font
					(size 1 1)
					(thickness 0.15)
				)
				(justify mirror)
			)
		)
		(property "MPN" "C1005X5R1E474M050BB"
			(at 191.15 225.35 0)
			(layer "B.Fab")
			(hide yes)
			(effects
				(font
					(size 1 1)
					(thickness 0.15)
				)
				(justify mirror)
			)
		)
		(property "Manufacturer" "TDK"
			(at 191.15 225.35 0)
			(layer "B.Fab")
			(hide yes)
			(effects
				(font
					(size 1 1)
					(thickness 0.15)
				)
				(justify mirror)
			)
		)
		(property "Val" "470n"
			(at 191.15 225.35 0)
			(layer "B.Fab")
			(hide yes)
			(effects
				(font
					(size 1 1)
					(thickness 0.15)
				)
				(justify mirror)
			)
		)
		(property "Voltage" ""
			(at 191.15 225.35 0)
			(layer "B.Fab")
			(hide yes)
			(effects
				(font
					(size 1 1)
					(thickness 0.15)
				)
				(justify mirror)
			)
		)
		(property "DNP" ""
			(at 0 0 180)
			(unlocked yes)
			(layer "B.Fab")
			(hide yes)
			(effects
				(font
					(size 1 1)
					(thickness 0.15)
				)
				(justify mirror)
			)
		)
		(sheetname "/FPGA banks 13-16/")
		(sheetfile "fpga-banks-13-16.kicad_sch")
		(attr smd)
		(fp_rect
			(start -0.925 0.47)
			(end 0.925 -0.47)
			(stroke
				(width 0.05)
				(type default)
			)
			(fill no)
			(layer "B.CrtYd")
		)
		(fp_line
			(start 0.504 0.25)
			(end 0.504 -0.248)
			(stroke
				(width 0.15)
				(type solid)
			)
			(layer "B.Fab")
		)
		(fp_line
			(start 0.504 -0.248)
			(end -0.494 -0.248)
			(stroke
				(width 0.15)
				(type solid)
			)
			(layer "B.Fab")
		)
		(fp_line
			(start -0.494 0.25)
			(end 0.504 0.25)
			(stroke
				(width 0.15)
				(type solid)
			)
			(layer "B.Fab")
		)
		(fp_line
			(start -0.494 -0.248)
			(end -0.494 0.25)
			(stroke
				(width 0.15)
				(type solid)
			)
			(layer "B.Fab")
		)
		(pad "1" smd roundrect
			(at -0.48 0 180)
			(size 0.59 0.64)
			(layers "B.Cu" "B.Mask" "B.Paste")
			(roundrect_rratio 0.25)
			(net 1 "GND")
			(pintype "passive")
		)
		(pad "2" smd roundrect
			(at 0.48 0 180)
			(size 0.59 0.64)
			(layers "B.Cu" "B.Mask" "B.Paste")
			(roundrect_rratio 0.25)
			(net 2 "VCC3V3")
			(pintype "passive")
		)
	)
	(footprint "antmicro-footprints:C_0402_1005Metric"
		(layer "B.Cu")
		(at 96.575 115.675 180)
		(descr "Capacitor SMD 0402")
		(tags "capacitor SMD 0402")
		(property "Reference" "C111"
			(at -1.251 0.45 0)
			(layer "B.SilkS")
			(effects
				(font
					(size 0.7 0.7)
					(thickness 0.15)
				)
				(justify left bottom mirror)
			)
		)
		(property "Value" "C_470n_0402"
			(at 0 -1.4 0)
			(layer "B.Fab")
			(effects
				(font
					(size 0.7 0.7)
					(thickness 0.15)
				)
				(justify left bottom mirror)
			)
		)
		(property "Datasheet" "https://product.tdk.com/en/search/capacitor/ceramic/mlcc/info?part_no=C1005X5R1E474M050BB"
			(at 0 0 180)
			(layer "F.Fab")
			(hide yes)
			(effects
				(font
					(size 1.27 1.27)
					(thickness 0.15)
				)
			)
		)
		(property "Description" "SMD Multilayer Ceramic Capacitor, 0.47 µF, 25 V, 0402 [1005 Metric], ± 20%, X5R, C"
			(at 0 0 180)
			(layer "F.Fab")
			(hide yes)
			(effects
				(font
					(size 1.27 1.27)
					(thickness 0.15)
				)
			)
		)
		(property "Author" "Antmicro"
			(at 193.15 231.35 0)
			(layer "B.Fab")
			(hide yes)
			(effects
				(font
					(size 1 1)
					(thickness 0.15)
				)
				(justify mirror)
			)
		)
		(property "Dielectric" ""
			(at 193.15 231.35 0)
			(layer "B.Fab")
			(hide yes)
			(effects
				(font
					(size 1 1)
					(thickness 0.15)
				)
				(justify mirror)
			)
		)
		(property "License" "Apache-2.0"
			(at 193.15 231.35 0)
			(layer "B.Fab")
			(hide yes)
			(effects
				(font
					(size 1 1)
					(thickness 0.15)
				)
				(justify mirror)
			)
		)
		(property "MPN" "C1005X5R1E474M050BB"
			(at 193.15 231.35 0)
			(layer "B.Fab")
			(hide yes)
			(effects
				(font
					(size 1 1)
					(thickness 0.15)
				)
				(justify mirror)
			)
		)
		(property "Manufacturer" "TDK"
			(at 193.15 231.35 0)
			(layer "B.Fab")
			(hide yes)
			(effects
				(font
					(size 1 1)
					(thickness 0.15)
				)
				(justify mirror)
			)
		)
		(property "Val" "470n"
			(at 193.15 231.35 0)
			(layer "B.Fab")
			(hide yes)
			(effects
				(font
					(size 1 1)
					(thickness 0.15)
				)
				(justify mirror)
			)
		)
		(property "Voltage" ""
			(at 193.15 231.35 0)
			(layer "B.Fab")
			(hide yes)
			(effects
				(font
					(size 1 1)
					(thickness 0.15)
				)
				(justify mirror)
			)
		)
		(sheetname "/FPGA banks 13-16/")
		(sheetfile "fpga-banks-13-16.kicad_sch")
		(attr smd)
		(fp_rect
			(start -0.925 0.47)
			(end 0.925 -0.47)
			(stroke
				(width 0.05)
				(type default)
			)
			(fill no)
			(layer "B.CrtYd")
		)
		(fp_line
			(start 0.504 0.25)
			(end 0.504 -0.248)
			(stroke
				(width 0.15)
				(type solid)
			)
			(layer "B.Fab")
		)
		(fp_line
			(start 0.504 -0.248)
			(end -0.494 -0.248)
			(stroke
				(width 0.15)
				(type solid)
			)
			(layer "B.Fab")
		)
		(fp_line
			(start -0.494 0.25)
			(end 0.504 0.25)
			(stroke
				(width 0.15)
				(type solid)
			)
			(layer "B.Fab")
		)
		(fp_line
			(start -0.494 -0.248)
			(end -0.494 0.25)
			(stroke
				(width 0.15)
				(type solid)
			)
			(layer "B.Fab")
		)
		(pad "1" smd roundrect
			(at -0.48 0 180)
			(size 0.59 0.64)
			(layers "B.Cu" "B.Mask" "B.Paste")
			(roundrect_rratio 0.25)
			(net 1 "GND")
			(pintype "passive")
		)
		(pad "2" smd roundrect
			(at 0.48 0 180)
			(size 0.59 0.64)
			(layers "B.Cu" "B.Mask" "B.Paste")
			(roundrect_rratio 0.25)
			(net 2 "VCC3V3")
			(pintype "passive")
		)
	)
	(footprint "antmicro-footprints:C_0402_1005Metric"
		(layer "B.Cu")
		(at 96.275 118.475 -90)
		(descr "Capacitor SMD 0402")
		(tags "capacitor SMD 0402")
		(property "Reference" "C117"
			(at -1.575 0.475 90)
			(layer "B.SilkS")
			(effects
				(font
					(size 0.7 0.7)
					(thickness 0.15)
				)
				(justify left bottom mirror)
			)
		)
		(property "Value" "C_470n_0402"
			(at 0 -1.4 90)
			(layer "B.Fab")
			(effects
				(font
					(size 0.7 0.7)
					(thickness 0.15)
				)
				(justify left bottom mirror)
			)
		)
		(property "Datasheet" "https://product.tdk.com/en/search/capacitor/ceramic/mlcc/info?part_no=C1005X5R1E474M050BB"
			(at 0 0 270)
			(layer "F.Fab")
			(hide yes)
			(effects
				(font
					(size 1.27 1.27)
					(thickness 0.15)
				)
			)
		)
		(property "Description" "SMD Multilayer Ceramic Capacitor, 0.47 µF, 25 V, 0402 [1005 Metric], ± 20%, X5R, C"
			(at 0 0 270)
			(layer "F.Fab")
			(hide yes)
			(effects
				(font
					(size 1.27 1.27)
					(thickness 0.15)
				)
			)
		)
		(property "Author" "Antmicro"
			(at -22.2 214.75 0)
			(layer "B.Fab")
			(hide yes)
			(effects
				(font
					(size 1 1)
					(thickness 0.15)
				)
				(justify mirror)
			)
		)
		(property "Dielectric" ""
			(at -22.2 214.75 0)
			(layer "B.Fab")
			(hide yes)
			(effects
				(font
					(size 1 1)
					(thickness 0.15)
				)
				(justify mirror)
			)
		)
		(property "License" "Apache-2.0"
			(at -22.2 214.75 0)
			(layer "B.Fab")
			(hide yes)
			(effects
				(font
					(size 1 1)
					(thickness 0.15)
				)
				(justify mirror)
			)
		)
		(property "MPN" "C1005X5R1E474M050BB"
			(at -22.2 214.75 0)
			(layer "B.Fab")
			(hide yes)
			(effects
				(font
					(size 1 1)
					(thickness 0.15)
				)
				(justify mirror)
			)
		)
		(property "Manufacturer" "TDK"
			(at -22.2 214.75 0)
			(layer "B.Fab")
			(hide yes)
			(effects
				(font
					(size 1 1)
					(thickness 0.15)
				)
				(justify mirror)
			)
		)
		(property "Val" "470n"
			(at -22.2 214.75 0)
			(layer "B.Fab")
			(hide yes)
			(effects
				(font
					(size 1 1)
					(thickness 0.15)
				)
				(justify mirror)
			)
		)
		(property "Voltage" ""
			(at -22.2 214.75 0)
			(layer "B.Fab")
			(hide yes)
			(effects
				(font
					(size 1 1)
					(thickness 0.15)
				)
				(justify mirror)
			)
		)
		(property "DNP" ""
			(at 0 0 270)
			(unlocked yes)
			(layer "B.Fab")
			(hide yes)
			(effects
				(font
					(size 1 1)
					(thickness 0.15)
				)
				(justify mirror)
			)
		)
		(sheetname "/FPGA banks 13-16/")
		(sheetfile "fpga-banks-13-16.kicad_sch")
		(attr smd)
		(fp_rect
			(start -0.925 0.47)
			(end 0.925 -0.47)
			(stroke
				(width 0.05)
				(type default)
			)
			(fill no)
			(layer "B.CrtYd")
		)
		(fp_line
			(start -0.494 0.25)
			(end 0.504 0.25)
			(stroke
				(width 0.15)
				(type solid)
			)
			(layer "B.Fab")
		)
		(fp_line
			(start 0.504 0.25)
			(end 0.504 -0.248)
			(stroke
				(width 0.15)
				(type solid)
			)
			(layer "B.Fab")
		)
		(fp_line
			(start -0.494 -0.248)
			(end -0.494 0.25)
			(stroke
				(width 0.15)
				(type solid)
			)
			(layer "B.Fab")
		)
		(fp_line
			(start 0.504 -0.248)
			(end -0.494 -0.248)
			(stroke
				(width 0.15)
				(type solid)
			)
			(layer "B.Fab")
		)
		(pad "1" smd roundrect
			(at -0.48 0 270)
			(size 0.59 0.64)
			(layers "B.Cu" "B.Mask" "B.Paste")
			(roundrect_rratio 0.25)
			(net 1 "GND")
			(pintype "passive")
		)
		(pad "2" smd roundrect
			(at 0.48 0 270)
			(size 0.59 0.64)
			(layers "B.Cu" "B.Mask" "B.Paste")
			(roundrect_rratio 0.25)
			(net 2 "VCC3V3")
			(pintype "passive")
		)
	)
	(footprint "antmicro-footprints:C_0402_1005Metric"
		(layer "B.Cu")
		(at 92.275 109.675)
		(descr "Capacitor SMD 0402")
		(tags "capacitor SMD 0402")
		(property "Reference" "C123"
			(at -3.675 0.325 0)
			(layer "B.SilkS")
			(effects
				(font
					(size 0.7 0.7)
					(thickness 0.15)
				)
				(justify right bottom mirror)
			)
		)
		(property "Value" "C_470n_0402"
			(at 0 -1.4 0)
			(layer "B.Fab")
			(effects
				(font
					(size 0.7 0.7)
					(thickness 0.15)
				)
				(justify right bottom mirror)
			)
		)
		(property "Datasheet" "https://product.tdk.com/en/search/capacitor/ceramic/mlcc/info?part_no=C1005X5R1E474M050BB"
			(at 0 0 0)
			(layer "F.Fab")
			(hide yes)
			(effects
				(font
					(size 1.27 1.27)
					(thickness 0.15)
				)
			)
		)
		(property "Description" "SMD Multilayer Ceramic Capacitor, 0.47 µF, 25 V, 0402 [1005 Metric], ± 20%, X5R, C"
			(at 0 0 0)
			(layer "F.Fab")
			(hide yes)
			(effects
				(font
					(size 1.27 1.27)
					(thickness 0.15)
				)
			)
		)
		(property "Author" "Antmicro"
			(at 0 0 0)
			(layer "B.Fab")
			(hide yes)
			(effects
				(font
					(size 1 1)
					(thickness 0.15)
				)
				(justify mirror)
			)
		)
		(property "Dielectric" ""
			(at 0 0 0)
			(layer "B.Fab")
			(hide yes)
			(effects
				(font
					(size 1 1)
					(thickness 0.15)
				)
				(justify mirror)
			)
		)
		(property "License" "Apache-2.0"
			(at 0 0 0)
			(layer "B.Fab")
			(hide yes)
			(effects
				(font
					(size 1 1)
					(thickness 0.15)
				)
				(justify mirror)
			)
		)
		(property "MPN" "C1005X5R1E474M050BB"
			(at 0 0 0)
			(layer "B.Fab")
			(hide yes)
			(effects
				(font
					(size 1 1)
					(thickness 0.15)
				)
				(justify mirror)
			)
		)
		(property "Manufacturer" "TDK"
			(at 0 0 0)
			(layer "B.Fab")
			(hide yes)
			(effects
				(font
					(size 1 1)
					(thickness 0.15)
				)
				(justify mirror)
			)
		)
		(property "Val" "470n"
			(at 0 0 0)
			(layer "B.Fab")
			(hide yes)
			(effects
				(font
					(size 1 1)
					(thickness 0.15)
				)
				(justify mirror)
			)
		)
		(property "Voltage" ""
			(at 0 0 0)
			(layer "B.Fab")
			(hide yes)
			(effects
				(font
					(size 1 1)
					(thickness 0.15)
				)
				(justify mirror)
			)
		)
		(sheetname "/FPGA banks 13-16/")
		(sheetfile "fpga-banks-13-16.kicad_sch")
		(attr smd)
		(fp_rect
			(start -0.925 0.47)
			(end 0.925 -0.47)
			(stroke
				(width 0.05)
				(type default)
			)
			(fill no)
			(layer "B.CrtYd")
		)
		(fp_line
			(start -0.494 -0.248)
			(end -0.494 0.25)
			(stroke
				(width 0.15)
				(type solid)
			)
			(layer "B.Fab")
		)
		(fp_line
			(start -0.494 0.25)
			(end 0.504 0.25)
			(stroke
				(width 0.15)
				(type solid)
			)
			(layer "B.Fab")
		)
		(fp_line
			(start 0.504 -0.248)
			(end -0.494 -0.248)
			(stroke
				(width 0.15)
				(type solid)
			)
			(layer "B.Fab")
		)
		(fp_line
			(start 0.504 0.25)
			(end 0.504 -0.248)
			(stroke
				(width 0.15)
				(type solid)
			)
			(layer "B.Fab")
		)
		(pad "1" smd roundrect
			(at -0.48 0)
			(size 0.59 0.64)
			(layers "B.Cu" "B.Mask" "B.Paste")
			(roundrect_rratio 0.25)
			(net 1 "GND")
			(pintype "passive")
		)
		(pad "2" smd roundrect
			(at 0.48 0)
			(size 0.59 0.64)
			(layers "B.Cu" "B.Mask" "B.Paste")
			(roundrect_rratio 0.25)
			(net 2 "VCC3V3")
			(pintype "passive")
		)
	)
	(footprint "antmicro-footprints:C_0402_1005Metric"
		(layer "B.Cu")
		(at 98.775 109.675)
		(descr "Capacitor SMD 0402")
		(tags "capacitor SMD 0402")
		(property "Reference" "C112"
			(at -0.875 -0.575 0)
			(layer "B.SilkS")
			(effects
				(font
					(size 0.7 0.7)
					(thickness 0.15)
				)
				(justify right bottom mirror)
			)
		)
		(property "Value" "C_470n_0402"
			(at 0 -1.4 0)
			(layer "B.Fab")
			(effects
				(font
					(size 0.7 0.7)
					(thickness 0.15)
				)
				(justify right bottom mirror)
			)
		)
		(property "Datasheet" "https://product.tdk.com/en/search/capacitor/ceramic/mlcc/info?part_no=C1005X5R1E474M050BB"
			(at 0 0 0)
			(layer "F.Fab")
			(hide yes)
			(effects
				(font
					(size 1.27 1.27)
					(thickness 0.15)
				)
			)
		)
		(property "Description" "SMD Multilayer Ceramic Capacitor, 0.47 µF, 25 V, 0402 [1005 Metric], ± 20%, X5R, C"
			(at 0 0 0)
			(layer "F.Fab")
			(hide yes)
			(effects
				(font
					(size 1.27 1.27)
					(thickness 0.15)
				)
			)
		)
		(property "Author" "Antmicro"
			(at 0 0 0)
			(layer "B.Fab")
			(hide yes)
			(effects
				(font
					(size 1 1)
					(thickness 0.15)
				)
				(justify mirror)
			)
		)
		(property "Dielectric" ""
			(at 0 0 0)
			(layer "B.Fab")
			(hide yes)
			(effects
				(font
					(size 1 1)
					(thickness 0.15)
				)
				(justify mirror)
			)
		)
		(property "License" "Apache-2.0"
			(at 0 0 0)
			(layer "B.Fab")
			(hide yes)
			(effects
				(font
					(size 1 1)
					(thickness 0.15)
				)
				(justify mirror)
			)
		)
		(property "MPN" "C1005X5R1E474M050BB"
			(at 0 0 0)
			(layer "B.Fab")
			(hide yes)
			(effects
				(font
					(size 1 1)
					(thickness 0.15)
				)
				(justify mirror)
			)
		)
		(property "Manufacturer" "TDK"
			(at 0 0 0)
			(layer "B.Fab")
			(hide yes)
			(effects
				(font
					(size 1 1)
					(thickness 0.15)
				)
				(justify mirror)
			)
		)
		(property "Val" "470n"
			(at 0 0 0)
			(layer "B.Fab")
			(hide yes)
			(effects
				(font
					(size 1 1)
					(thickness 0.15)
				)
				(justify mirror)
			)
		)
		(property "Voltage" ""
			(at 0 0 0)
			(layer "B.Fab")
			(hide yes)
			(effects
				(font
					(size 1 1)
					(thickness 0.15)
				)
				(justify mirror)
			)
		)
		(property "DNP" ""
			(at 0 0 0)
			(unlocked yes)
			(layer "B.Fab")
			(hide yes)
			(effects
				(font
					(size 1 1)
					(thickness 0.15)
				)
				(justify mirror)
			)
		)
		(sheetname "/FPGA banks 13-16/")
		(sheetfile "fpga-banks-13-16.kicad_sch")
		(attr smd)
		(fp_rect
			(start -0.925 0.47)
			(end 0.925 -0.47)
			(stroke
				(width 0.05)
				(type default)
			)
			(fill no)
			(layer "B.CrtYd")
		)
		(fp_line
			(start -0.494 -0.248)
			(end -0.494 0.25)
			(stroke
				(width 0.15)
				(type solid)
			)
			(layer "B.Fab")
		)
		(fp_line
			(start -0.494 0.25)
			(end 0.504 0.25)
			(stroke
				(width 0.15)
				(type solid)
			)
			(layer "B.Fab")
		)
		(fp_line
			(start 0.504 -0.248)
			(end -0.494 -0.248)
			(stroke
				(width 0.15)
				(type solid)
			)
			(layer "B.Fab")
		)
		(fp_line
			(start 0.504 0.25)
			(end 0.504 -0.248)
			(stroke
				(width 0.15)
				(type solid)
			)
			(layer "B.Fab")
		)
		(pad "1" smd roundrect
			(at -0.48 0)
			(size 0.59 0.64)
			(layers "B.Cu" "B.Mask" "B.Paste")
			(roundrect_rratio 0.25)
			(net 1 "GND")
			(pintype "passive")
		)
		(pad "2" smd roundrect
			(at 0.48 0)
			(size 0.59 0.64)
			(layers "B.Cu" "B.Mask" "B.Paste")
			(roundrect_rratio 0.25)
			(net 2 "VCC3V3")
			(pintype "passive")
		)
	)
	(footprint "antmicro-footprints:C_0402_1005Metric"
		(layer "B.Cu")
		(at 111.325 120.725 180)
		(descr "Capacitor SMD 0402")
		(tags "capacitor SMD 0402")
		(property "Reference" "C118"
			(at -3.623 -0.425 0)
			(layer "B.SilkS")
			(effects
				(font
					(size 0.7 0.7)
					(thickness 0.15)
				)
				(justify left bottom mirror)
			)
		)
		(property "Value" "C_470n_0402"
			(at 0 -1.4 0)
			(layer "B.Fab")
			(effects
				(font
					(size 0.7 0.7)
					(thickness 0.15)
				)
				(justify left bottom mirror)
			)
		)
		(property "Datasheet" "https://product.tdk.com/en/search/capacitor/ceramic/mlcc/info?part_no=C1005X5R1E474M050BB"
			(at 0 0 180)
			(layer "F.Fab")
			(hide yes)
			(effects
				(font
					(size 1.27 1.27)
					(thickness 0.15)
				)
			)
		)
		(property "Description" "SMD Multilayer Ceramic Capacitor, 0.47 µF, 25 V, 0402 [1005 Metric], ± 20%, X5R, C"
			(at 0 0 180)
			(layer "F.Fab")
			(hide yes)
			(effects
				(font
					(size 1.27 1.27)
					(thickness 0.15)
				)
			)
		)
		(property "Author" "Antmicro"
			(at 222.65 241.45 0)
			(layer "B.Fab")
			(hide yes)
			(effects
				(font
					(size 1 1)
					(thickness 0.15)
				)
				(justify mirror)
			)
		)
		(property "Dielectric" ""
			(at 222.65 241.45 0)
			(layer "B.Fab")
			(hide yes)
			(effects
				(font
					(size 1 1)
					(thickness 0.15)
				)
				(justify mirror)
			)
		)
		(property "License" "Apache-2.0"
			(at 222.65 241.45 0)
			(layer "B.Fab")
			(hide yes)
			(effects
				(font
					(size 1 1)
					(thickness 0.15)
				)
				(justify mirror)
			)
		)
		(property "MPN" "C1005X5R1E474M050BB"
			(at 222.65 241.45 0)
			(layer "B.Fab")
			(hide yes)
			(effects
				(font
					(size 1 1)
					(thickness 0.15)
				)
				(justify mirror)
			)
		)
		(property "Manufacturer" "TDK"
			(at 222.65 241.45 0)
			(layer "B.Fab")
			(hide yes)
			(effects
				(font
					(size 1 1)
					(thickness 0.15)
				)
				(justify mirror)
			)
		)
		(property "Val" "470n"
			(at 222.65 241.45 0)
			(layer "B.Fab")
			(hide yes)
			(effects
				(font
					(size 1 1)
					(thickness 0.15)
				)
				(justify mirror)
			)
		)
		(property "Voltage" ""
			(at 222.65 241.45 0)
			(layer "B.Fab")
			(hide yes)
			(effects
				(font
					(size 1 1)
					(thickness 0.15)
				)
				(justify mirror)
			)
		)
		(property "DNP" ""
			(at 0 0 180)
			(unlocked yes)
			(layer "B.Fab")
			(hide yes)
			(effects
				(font
					(size 1 1)
					(thickness 0.15)
				)
				(justify mirror)
			)
		)
		(sheetname "/FPGA banks 13-16/")
		(sheetfile "fpga-banks-13-16.kicad_sch")
		(attr smd)
		(fp_rect
			(start -0.925 0.47)
			(end 0.925 -0.47)
			(stroke
				(width 0.05)
				(type default)
			)
			(fill no)
			(layer "B.CrtYd")
		)
		(fp_line
			(start 0.504 0.25)
			(end 0.504 -0.248)
			(stroke
				(width 0.15)
				(type solid)
			)
			(layer "B.Fab")
		)
		(fp_line
			(start 0.504 -0.248)
			(end -0.494 -0.248)
			(stroke
				(width 0.15)
				(type solid)
			)
			(layer "B.Fab")
		)
		(fp_line
			(start -0.494 0.25)
			(end 0.504 0.25)
			(stroke
				(width 0.15)
				(type solid)
			)
			(layer "B.Fab")
		)
		(fp_line
			(start -0.494 -0.248)
			(end -0.494 0.25)
			(stroke
				(width 0.15)
				(type solid)
			)
			(layer "B.Fab")
		)
		(pad "1" smd roundrect
			(at -0.48 0 180)
			(size 0.59 0.64)
			(layers "B.Cu" "B.Mask" "B.Paste")
			(roundrect_rratio 0.25)
			(net 1 "GND")
			(pintype "passive")
		)
		(pad "2" smd roundrect
			(at 0.48 0 180)
			(size 0.59 0.64)
			(layers "B.Cu" "B.Mask" "B.Paste")
			(roundrect_rratio 0.25)
			(net 2 "VCC3V3")
			(pintype "passive")
		)
	)
	(footprint "antmicro-footprints:C_0402_1005Metric"
		(layer "B.Cu")
		(at 97.775 111.675 180)
		(descr "Capacitor SMD 0402")
		(tags "capacitor SMD 0402")
		(property "Reference" "C124"
			(at -1.425 0.475 0)
			(layer "B.SilkS")
			(effects
				(font
					(size 0.7 0.7)
					(thickness 0.15)
				)
				(justify left bottom mirror)
			)
		)
		(property "Value" "C_470n_0402"
			(at 0 -1.4 0)
			(layer "B.Fab")
			(effects
				(font
					(size 0.7 0.7)
					(thickness 0.15)
				)
				(justify left bottom mirror)
			)
		)
		(property "Datasheet" "https://product.tdk.com/en/search/capacitor/ceramic/mlcc/info?part_no=C1005X5R1E474M050BB"
			(at 0 0 180)
			(layer "F.Fab")
			(hide yes)
			(effects
				(font
					(size 1.27 1.27)
					(thickness 0.15)
				)
			)
		)
		(property "Description" "SMD Multilayer Ceramic Capacitor, 0.47 µF, 25 V, 0402 [1005 Metric], ± 20%, X5R, C"
			(at 0 0 180)
			(layer "F.Fab")
			(hide yes)
			(effects
				(font
					(size 1.27 1.27)
					(thickness 0.15)
				)
			)
		)
		(property "Author" "Antmicro"
			(at 195.55 223.35 0)
			(layer "B.Fab")
			(hide yes)
			(effects
				(font
					(size 1 1)
					(thickness 0.15)
				)
				(justify mirror)
			)
		)
		(property "Dielectric" ""
			(at 195.55 223.35 0)
			(layer "B.Fab")
			(hide yes)
			(effects
				(font
					(size 1 1)
					(thickness 0.15)
				)
				(justify mirror)
			)
		)
		(property "License" "Apache-2.0"
			(at 195.55 223.35 0)
			(layer "B.Fab")
			(hide yes)
			(effects
				(font
					(size 1 1)
					(thickness 0.15)
				)
				(justify mirror)
			)
		)
		(property "MPN" "C1005X5R1E474M050BB"
			(at 195.55 223.35 0)
			(layer "B.Fab")
			(hide yes)
			(effects
				(font
					(size 1 1)
					(thickness 0.15)
				)
				(justify mirror)
			)
		)
		(property "Manufacturer" "TDK"
			(at 195.55 223.35 0)
			(layer "B.Fab")
			(hide yes)
			(effects
				(font
					(size 1 1)
					(thickness 0.15)
				)
				(justify mirror)
			)
		)
		(property "Val" "470n"
			(at 195.55 223.35 0)
			(layer "B.Fab")
			(hide yes)
			(effects
				(font
					(size 1 1)
					(thickness 0.15)
				)
				(justify mirror)
			)
		)
		(property "Voltage" ""
			(at 195.55 223.35 0)
			(layer "B.Fab")
			(hide yes)
			(effects
				(font
					(size 1 1)
					(thickness 0.15)
				)
				(justify mirror)
			)
		)
		(property "DNP" ""
			(at 0 0 180)
			(unlocked yes)
			(layer "B.Fab")
			(hide yes)
			(effects
				(font
					(size 1 1)
					(thickness 0.15)
				)
				(justify mirror)
			)
		)
		(sheetname "/FPGA banks 13-16/")
		(sheetfile "fpga-banks-13-16.kicad_sch")
		(attr smd)
		(fp_rect
			(start -0.925 0.47)
			(end 0.925 -0.47)
			(stroke
				(width 0.05)
				(type default)
			)
			(fill no)
			(layer "B.CrtYd")
		)
		(fp_line
			(start 0.504 0.25)
			(end 0.504 -0.248)
			(stroke
				(width 0.15)
				(type solid)
			)
			(layer "B.Fab")
		)
		(fp_line
			(start 0.504 -0.248)
			(end -0.494 -0.248)
			(stroke
				(width 0.15)
				(type solid)
			)
			(layer "B.Fab")
		)
		(fp_line
			(start -0.494 0.25)
			(end 0.504 0.25)
			(stroke
				(width 0.15)
				(type solid)
			)
			(layer "B.Fab")
		)
		(fp_line
			(start -0.494 -0.248)
			(end -0.494 0.25)
			(stroke
				(width 0.15)
				(type solid)
			)
			(layer "B.Fab")
		)
		(pad "1" smd roundrect
			(at -0.48 0 180)
			(size 0.59 0.64)
			(layers "B.Cu" "B.Mask" "B.Paste")
			(roundrect_rratio 0.25)
			(net 1 "GND")
			(pintype "passive")
		)
		(pad "2" smd roundrect
			(at 0.48 0 180)
			(size 0.59 0.64)
			(layers "B.Cu" "B.Mask" "B.Paste")
			(roundrect_rratio 0.25)
			(net 2 "VCC3V3")
			(pintype "passive")
		)
	)
	(footprint "antmicro-footprints:C_0402_1005Metric"
		(layer "B.Cu")
		(at 107.775 125.525 180)
		(descr "Capacitor SMD 0402")
		(tags "capacitor SMD 0402")
		(property "Reference" "C113"
			(at -1.625 -4.375 0)
			(layer "B.SilkS")
			(effects
				(font
					(size 0.7 0.7)
					(thickness 0.15)
				)
				(justify left bottom mirror)
			)
		)
		(property "Value" "C_470n_0402"
			(at 0 -1.4 0)
			(layer "B.Fab")
			(effects
				(font
					(size 0.7 0.7)
					(thickness 0.15)
				)
				(justify left bottom mirror)
			)
		)
		(property "Datasheet" "https://product.tdk.com/en/search/capacitor/ceramic/mlcc/info?part_no=C1005X5R1E474M050BB"
			(at 0 0 180)
			(layer "F.Fab")
			(hide yes)
			(effects
				(font
					(size 1.27 1.27)
					(thickness 0.15)
				)
			)
		)
		(property "Description" "SMD Multilayer Ceramic Capacitor, 0.47 µF, 25 V, 0402 [1005 Metric], ± 20%, X5R, C"
			(at 0 0 180)
			(layer "F.Fab")
			(hide yes)
			(effects
				(font
					(size 1.27 1.27)
					(thickness 0.15)
				)
			)
		)
		(property "Author" "Antmicro"
			(at 215.55 251.05 0)
			(layer "B.Fab")
			(hide yes)
			(effects
				(font
					(size 1 1)
					(thickness 0.15)
				)
				(justify mirror)
			)
		)
		(property "Dielectric" ""
			(at 215.55 251.05 0)
			(layer "B.Fab")
			(hide yes)
			(effects
				(font
					(size 1 1)
					(thickness 0.15)
				)
				(justify mirror)
			)
		)
		(property "License" "Apache-2.0"
			(at 215.55 251.05 0)
			(layer "B.Fab")
			(hide yes)
			(effects
				(font
					(size 1 1)
					(thickness 0.15)
				)
				(justify mirror)
			)
		)
		(property "MPN" "C1005X5R1E474M050BB"
			(at 215.55 251.05 0)
			(layer "B.Fab")
			(hide yes)
			(effects
				(font
					(size 1 1)
					(thickness 0.15)
				)
				(justify mirror)
			)
		)
		(property "Manufacturer" "TDK"
			(at 215.55 251.05 0)
			(layer "B.Fab")
			(hide yes)
			(effects
				(font
					(size 1 1)
					(thickness 0.15)
				)
				(justify mirror)
			)
		)
		(property "Val" "470n"
			(at 215.55 251.05 0)
			(layer "B.Fab")
			(hide yes)
			(effects
				(font
					(size 1 1)
					(thickness 0.15)
				)
				(justify mirror)
			)
		)
		(property "Voltage" ""
			(at 215.55 251.05 0)
			(layer "B.Fab")
			(hide yes)
			(effects
				(font
					(size 1 1)
					(thickness 0.15)
				)
				(justify mirror)
			)
		)
		(sheetname "/FPGA banks 13-16/")
		(sheetfile "fpga-banks-13-16.kicad_sch")
		(attr smd)
		(fp_rect
			(start -0.925 0.47)
			(end 0.925 -0.47)
			(stroke
				(width 0.05)
				(type default)
			)
			(fill no)
			(layer "B.CrtYd")
		)
		(fp_line
			(start 0.504 0.25)
			(end 0.504 -0.248)
			(stroke
				(width 0.15)
				(type solid)
			)
			(layer "B.Fab")
		)
		(fp_line
			(start 0.504 -0.248)
			(end -0.494 -0.248)
			(stroke
				(width 0.15)
				(type solid)
			)
			(layer "B.Fab")
		)
		(fp_line
			(start -0.494 0.25)
			(end 0.504 0.25)
			(stroke
				(width 0.15)
				(type solid)
			)
			(layer "B.Fab")
		)
		(fp_line
			(start -0.494 -0.248)
			(end -0.494 0.25)
			(stroke
				(width 0.15)
				(type solid)
			)
			(layer "B.Fab")
		)
		(pad "1" smd roundrect
			(at -0.48 0 180)
			(size 0.59 0.64)
			(layers "B.Cu" "B.Mask" "B.Paste")
			(roundrect_rratio 0.25)
			(net 1 "GND")
			(pintype "passive")
		)
		(pad "2" smd roundrect
			(at 0.48 0 180)
			(size 0.59 0.64)
			(layers "B.Cu" "B.Mask" "B.Paste")
			(roundrect_rratio 0.25)
			(net 2 "VCC3V3")
			(pintype "passive")
		)
	)
	(footprint "antmicro-footprints:C_0402_1005Metric"
		(layer "B.Cu")
		(at 107.8 126.6 180)
		(descr "Capacitor SMD 0402")
		(tags "capacitor SMD 0402")
		(property "Reference" "C125"
			(at -1.6 -4.4 0)
			(layer "B.SilkS")
			(effects
				(font
					(size 0.7 0.7)
					(thickness 0.15)
				)
				(justify left bottom mirror)
			)
		)
		(property "Value" "C_470n_0402"
			(at 0 -1.4 0)
			(layer "B.Fab")
			(effects
				(font
					(size 0.7 0.7)
					(thickness 0.15)
				)
				(justify left bottom mirror)
			)
		)
		(property "Datasheet" "https://product.tdk.com/en/search/capacitor/ceramic/mlcc/info?part_no=C1005X5R1E474M050BB"
			(at 0 0 180)
			(layer "F.Fab")
			(hide yes)
			(effects
				(font
					(size 1.27 1.27)
					(thickness 0.15)
				)
			)
		)
		(property "Description" "SMD Multilayer Ceramic Capacitor, 0.47 µF, 25 V, 0402 [1005 Metric], ± 20%, X5R, C"
			(at 0 0 180)
			(layer "F.Fab")
			(hide yes)
			(effects
				(font
					(size 1.27 1.27)
					(thickness 0.15)
				)
			)
		)
		(property "Author" "Antmicro"
			(at 215.6 253.2 0)
			(layer "B.Fab")
			(hide yes)
			(effects
				(font
					(size 1 1)
					(thickness 0.15)
				)
				(justify mirror)
			)
		)
		(property "Dielectric" ""
			(at 215.6 253.2 0)
			(layer "B.Fab")
			(hide yes)
			(effects
				(font
					(size 1 1)
					(thickness 0.15)
				)
				(justify mirror)
			)
		)
		(property "License" "Apache-2.0"
			(at 215.6 253.2 0)
			(layer "B.Fab")
			(hide yes)
			(effects
				(font
					(size 1 1)
					(thickness 0.15)
				)
				(justify mirror)
			)
		)
		(property "MPN" "C1005X5R1E474M050BB"
			(at 215.6 253.2 0)
			(layer "B.Fab")
			(hide yes)
			(effects
				(font
					(size 1 1)
					(thickness 0.15)
				)
				(justify mirror)
			)
		)
		(property "Manufacturer" "TDK"
			(at 215.6 253.2 0)
			(layer "B.Fab")
			(hide yes)
			(effects
				(font
					(size 1 1)
					(thickness 0.15)
				)
				(justify mirror)
			)
		)
		(property "Val" "470n"
			(at 215.6 253.2 0)
			(layer "B.Fab")
			(hide yes)
			(effects
				(font
					(size 1 1)
					(thickness 0.15)
				)
				(justify mirror)
			)
		)
		(property "Voltage" ""
			(at 215.6 253.2 0)
			(layer "B.Fab")
			(hide yes)
			(effects
				(font
					(size 1 1)
					(thickness 0.15)
				)
				(justify mirror)
			)
		)
		(sheetname "/FPGA banks 13-16/")
		(sheetfile "fpga-banks-13-16.kicad_sch")
		(attr smd)
		(fp_rect
			(start -0.925 0.47)
			(end 0.925 -0.47)
			(stroke
				(width 0.05)
				(type default)
			)
			(fill no)
			(layer "B.CrtYd")
		)
		(fp_line
			(start 0.504 0.25)
			(end 0.504 -0.248)
			(stroke
				(width 0.15)
				(type solid)
			)
			(layer "B.Fab")
		)
		(fp_line
			(start 0.504 -0.248)
			(end -0.494 -0.248)
			(stroke
				(width 0.15)
				(type solid)
			)
			(layer "B.Fab")
		)
		(fp_line
			(start -0.494 0.25)
			(end 0.504 0.25)
			(stroke
				(width 0.15)
				(type solid)
			)
			(layer "B.Fab")
		)
		(fp_line
			(start -0.494 -0.248)
			(end -0.494 0.25)
			(stroke
				(width 0.15)
				(type solid)
			)
			(layer "B.Fab")
		)
		(pad "1" smd roundrect
			(at -0.48 0 180)
			(size 0.59 0.64)
			(layers "B.Cu" "B.Mask" "B.Paste")
			(roundrect_rratio 0.25)
			(net 1 "GND")
			(pintype "passive")
		)
		(pad "2" smd roundrect
			(at 0.48 0 180)
			(size 0.59 0.64)
			(layers "B.Cu" "B.Mask" "B.Paste")
			(roundrect_rratio 0.25)
			(net 2 "VCC3V3")
			(pintype "passive")
		)
	)
	(footprint "antmicro-footprints:C_0402_1005Metric"
		(layer "B.Cu")
		(at 105.5 126.7)
		(descr "Capacitor SMD 0402")
		(tags "capacitor SMD 0402")
		(property "Reference" "C131"
			(at -1.8 4.3 0)
			(layer "B.SilkS")
			(effects
				(font
					(size 0.7 0.7)
					(thickness 0.15)
				)
				(justify right bottom mirror)
			)
		)
		(property "Value" "C_470n_0402"
			(at 0 -1.4 0)
			(layer "B.Fab")
			(effects
				(font
					(size 0.7 0.7)
					(thickness 0.15)
				)
				(justify right bottom mirror)
			)
		)
		(property "Datasheet" "https://product.tdk.com/en/search/capacitor/ceramic/mlcc/info?part_no=C1005X5R1E474M050BB"
			(at 0 0 0)
			(layer "F.Fab")
			(hide yes)
			(effects
				(font
					(size 1.27 1.27)
					(thickness 0.15)
				)
			)
		)
		(property "Description" "SMD Multilayer Ceramic Capacitor, 0.47 µF, 25 V, 0402 [1005 Metric], ± 20%, X5R, C"
			(at 0 0 0)
			(layer "F.Fab")
			(hide yes)
			(effects
				(font
					(size 1.27 1.27)
					(thickness 0.15)
				)
			)
		)
		(property "Author" "Antmicro"
			(at 0 0 0)
			(layer "B.Fab")
			(hide yes)
			(effects
				(font
					(size 1 1)
					(thickness 0.15)
				)
				(justify mirror)
			)
		)
		(property "Dielectric" ""
			(at 0 0 0)
			(layer "B.Fab")
			(hide yes)
			(effects
				(font
					(size 1 1)
					(thickness 0.15)
				)
				(justify mirror)
			)
		)
		(property "License" "Apache-2.0"
			(at 0 0 0)
			(layer "B.Fab")
			(hide yes)
			(effects
				(font
					(size 1 1)
					(thickness 0.15)
				)
				(justify mirror)
			)
		)
		(property "MPN" "C1005X5R1E474M050BB"
			(at 0 0 0)
			(layer "B.Fab")
			(hide yes)
			(effects
				(font
					(size 1 1)
					(thickness 0.15)
				)
				(justify mirror)
			)
		)
		(property "Manufacturer" "TDK"
			(at 0 0 0)
			(layer "B.Fab")
			(hide yes)
			(effects
				(font
					(size 1 1)
					(thickness 0.15)
				)
				(justify mirror)
			)
		)
		(property "Val" "470n"
			(at 0 0 0)
			(layer "B.Fab")
			(hide yes)
			(effects
				(font
					(size 1 1)
					(thickness 0.15)
				)
				(justify mirror)
			)
		)
		(property "Voltage" ""
			(at 0 0 0)
			(layer "B.Fab")
			(hide yes)
			(effects
				(font
					(size 1 1)
					(thickness 0.15)
				)
				(justify mirror)
			)
		)
		(sheetname "/FPGA banks 13-16/")
		(sheetfile "fpga-banks-13-16.kicad_sch")
		(attr smd)
		(fp_rect
			(start -0.925 0.47)
			(end 0.925 -0.47)
			(stroke
				(width 0.05)
				(type default)
			)
			(fill no)
			(layer "B.CrtYd")
		)
		(fp_line
			(start -0.494 -0.248)
			(end -0.494 0.25)
			(stroke
				(width 0.15)
				(type solid)
			)
			(layer "B.Fab")
		)
		(fp_line
			(start -0.494 0.25)
			(end 0.504 0.25)
			(stroke
				(width 0.15)
				(type solid)
			)
			(layer "B.Fab")
		)
		(fp_line
			(start 0.504 -0.248)
			(end -0.494 -0.248)
			(stroke
				(width 0.15)
				(type solid)
			)
			(layer "B.Fab")
		)
		(fp_line
			(start 0.504 0.25)
			(end 0.504 -0.248)
			(stroke
				(width 0.15)
				(type solid)
			)
			(layer "B.Fab")
		)
		(pad "1" smd roundrect
			(at -0.48 0)
			(size 0.59 0.64)
			(layers "B.Cu" "B.Mask" "B.Paste")
			(roundrect_rratio 0.25)
			(net 1 "GND")
			(pintype "passive")
		)
		(pad "2" smd roundrect
			(at 0.48 0)
			(size 0.59 0.64)
			(layers "B.Cu" "B.Mask" "B.Paste")
			(roundrect_rratio 0.25)
			(net 2 "VCC3V3")
			(pintype "passive")
		)
	)
	(footprint "antmicro-footprints:SOT-23-3"
		(layer "B.Cu")
		(at 71.04 80.74 90)
		(property "Reference" "Q13"
			(at 1.04 -2.64 180)
			(layer "B.SilkS")
			(effects
				(font
					(size 0.7 0.7)
					(thickness 0.15)
				)
				(justify right bottom mirror)
			)
		)
		(property "Value" "2N7002_SOT-23-3"
			(at -1.9 -2.7 90)
			(layer "B.Fab")
			(effects
				(font
					(size 0.7 0.7)
					(thickness 0.15)
				)
				(justify right bottom mirror)
			)
		)
		(property "Datasheet" "https://www.onsemi.com/pub/Collateral/NDS7002A-D.PDF"
			(at 0 0 90)
			(layer "F.Fab")
			(hide yes)
			(effects
				(font
					(size 1.27 1.27)
					(thickness 0.15)
				)
			)
		)
		(property "Description" "Power MOSFET, N Channel, 60 V, 115 mA, 1.2 ohm, SOT-23, Surface Mount"
			(at 0 0 90)
			(layer "F.Fab")
			(hide yes)
			(effects
				(font
					(size 1.27 1.27)
					(thickness 0.15)
				)
			)
		)
		(property "Author" "Antmicro"
			(at 151.78 9.7 0)
			(layer "B.Fab")
			(hide yes)
			(effects
				(font
					(size 1 1)
					(thickness 0.15)
				)
				(justify mirror)
			)
		)
		(property "License" "Apache-2.0"
			(at 151.78 9.7 0)
			(layer "B.Fab")
			(hide yes)
			(effects
				(font
					(size 1 1)
					(thickness 0.15)
				)
				(justify mirror)
			)
		)
		(property "MPN" "2N7002"
			(at 151.78 9.7 0)
			(layer "B.Fab")
			(hide yes)
			(effects
				(font
					(size 1 1)
					(thickness 0.15)
				)
				(justify mirror)
			)
		)
		(property "Manufacturer" "ON Semiconductor"
			(at 151.78 9.7 0)
			(layer "B.Fab")
			(hide yes)
			(effects
				(font
					(size 1 1)
					(thickness 0.15)
				)
				(justify mirror)
			)
		)
		(sheetname "/FPGA banks 34-35 & CFG/")
		(sheetfile "fpga-banks-34-25-cfg.kicad_sch")
		(attr smd)
		(fp_line
			(start 0.7 -1.5)
			(end -0.7 -1.5)
			(stroke
				(width 0.15)
				(type solid)
			)
			(layer "B.SilkS")
		)
		(fp_line
			(start -0.7 -1.5)
			(end -0.7 -1.35)
			(stroke
				(width 0.15)
				(type solid)
			)
			(layer "B.SilkS")
		)
		(fp_line
			(start 0.7 -0.4)
			(end 0.7 -1.5)
			(stroke
				(width 0.15)
				(type solid)
			)
			(layer "B.SilkS")
		)
		(fp_line
			(start 0.7 0.4)
			(end 0.7 1.5)
			(stroke
				(width 0.15)
				(type solid)
			)
			(layer "B.SilkS")
		)
		(fp_line
			(start -0.85 1.35)
			(end -0.7 1.5)
			(stroke
				(width 0.15)
				(type solid)
			)
			(layer "B.SilkS")
		)
		(fp_line
			(start -1.45 1.35)
			(end -0.85 1.35)
			(stroke
				(width 0.15)
				(type solid)
			)
			(layer "B.SilkS")
		)
		(fp_line
			(start 0.7 1.5)
			(end -0.7 1.5)
			(stroke
				(width 0.15)
				(type solid)
			)
			(layer "B.SilkS")
		)
		(fp_line
			(start 0.85 -1.65)
			(end -0.85 -1.65)
			(stroke
				(width 0.05)
				(type solid)
			)
			(layer "B.CrtYd")
		)
		(fp_line
			(start -0.85 -1.65)
			(end -0.85 -1.4)
			(stroke
				(width 0.05)
				(type solid)
			)
			(layer "B.CrtYd")
		)
		(fp_line
			(start -0.85 -1.4)
			(end -1.75 -1.4)
			(stroke
				(width 0.05)
				(type solid)
			)
			(layer "B.CrtYd")
		)
		(fp_line
			(start -1.75 -1.4)
			(end -1.75 -0.5)
			(stroke
				(width 0.05)
				(type solid)
			)
			(layer "B.CrtYd")
		)
		(fp_line
			(start -0.85 -0.5)
			(end -0.85 0.5)
			(stroke
				(width 0.05)
				(type solid)
			)
			(layer "B.CrtYd")
		)
		(fp_line
			(start -1.75 -0.5)
			(end -0.85 -0.5)
			(stroke
				(width 0.05)
				(type solid)
			)
			(layer "B.CrtYd")
		)
		(fp_line
			(start 1.75 -0.45)
			(end 0.85 -0.45)
			(stroke
				(width 0.05)
				(type solid)
			)
			(layer "B.CrtYd")
		)
		(fp_line
			(start 0.85 -0.45)
			(end 0.85 -1.65)
			(stroke
				(width 0.05)
				(type solid)
			)
			(layer "B.CrtYd")
		)
		(fp_line
			(start 1.75 0.45)
			(end 1.75 -0.45)
			(stroke
				(width 0.05)
				(type solid)
			)
			(layer "B.CrtYd")
		)
		(fp_line
			(start 0.825 0.45)
			(end 1.75 0.45)
			(stroke
				(width 0.05)
				(type solid)
			)
			(layer "B.CrtYd")
		)
		(fp_line
			(start -0.85 0.5)
			(end -1.75 0.5)
			(stroke
				(width 0.05)
				(type solid)
			)
			(layer "B.CrtYd")
		)
		(fp_line
			(start -1.75 0.5)
			(end -1.75 1.4)
			(stroke
				(width 0.05)
				(type solid)
			)
			(layer "B.CrtYd")
		)
		(fp_line
			(start -0.9 1.4)
			(end -1.75 1.4)
			(stroke
				(width 0.05)
				(type solid)
			)
			(layer "B.CrtYd")
		)
		(fp_line
			(start 0.825 1.6)
			(end 0.825 0.45)
			(stroke
				(width 0.05)
				(type solid)
			)
			(layer "B.CrtYd")
		)
		(fp_line
			(start -0.9 1.6)
			(end -0.9 1.4)
			(stroke
				(width 0.05)
				(type solid)
			)
			(layer "B.CrtYd")
		)
		(fp_line
			(start -0.9 1.6)
			(end 0.825 1.6)
			(stroke
				(width 0.05)
				(type solid)
			)
			(layer "B.CrtYd")
		)
		(fp_line
			(start 0.688 -1.519)
			(end 0.688 1.52)
			(stroke
				(width 0.15)
				(type solid)
			)
			(layer "B.Fab")
		)
		(fp_line
			(start -0.712 -1.519)
			(end 0.688 -1.519)
			(stroke
				(width 0.15)
				(type solid)
			)
			(layer "B.Fab")
		)
		(fp_line
			(start -0.712 1.325)
			(end -0.712 -1.523)
			(stroke
				(width 0.15)
				(type solid)
			)
			(layer "B.Fab")
		)
		(fp_line
			(start -0.437 1.526)
			(end -0.712 1.325)
			(stroke
				(width 0.15)
				(type solid)
			)
			(layer "B.Fab")
		)
		(fp_line
			(start -0.437 1.526)
			(end 0.688 1.526)
			(stroke
				(width 0.15)
				(type solid)
			)
			(layer "B.Fab")
		)
		(pad "1" smd roundrect
			(at -1.1 0.951 90)
			(size 1 0.6)
			(layers "B.Cu" "B.Mask" "B.Paste")
			(roundrect_rratio 0.15)
			(net 220 "DONE")
			(pinfunction "G")
			(pintype "input")
		)
		(pad "2" smd roundrect
			(at -1.1 -0.949 90)
			(size 1 0.6)
			(layers "B.Cu" "B.Mask" "B.Paste")
			(roundrect_rratio 0.15)
			(net 1 "GND")
			(pinfunction "S")
			(pintype "passive")
		)
		(pad "3" smd roundrect
			(at 1.1 0.0005 90)
			(size 1 0.6)
			(layers "B.Cu" "B.Mask" "B.Paste")
			(roundrect_rratio 0.15)
			(net 281 "Net-(D10-C)")
			(pinfunction "D")
			(pintype "passive")
		)
	)
	(footprint "antmicro-footprints:R_0402_1005Metric"
		(layer "B.Cu")
		(at 106.835 107.215 -90)
		(descr "Resistor SMD 0402")
		(tags "resistor SMD 0402")
		(property "Reference" "R1"
			(at 0.785 -0.365 90)
			(layer "B.SilkS")
			(effects
				(font
					(size 0.7 0.7)
					(thickness 0.15)
				)
				(justify left bottom mirror)
			)
		)
		(property "Value" "R_1k_0402"
			(at 0 -1.4 90)
			(layer "B.Fab")
			(effects
				(font
					(size 0.7 0.7)
					(thickness 0.15)
				)
				(justify left bottom mirror)
			)
		)
		(property "Datasheet" "https://www.bourns.com/docs/product-datasheets/cr.pdf"
			(at 0 0 270)
			(layer "F.Fab")
			(hide yes)
			(effects
				(font
					(size 1.27 1.27)
					(thickness 0.15)
				)
			)
		)
		(property "Description" "SMD Chip Resistor, 1 kohm, ± 1%, 63 mW, 0402 [1005 Metric], Thick Film, General Purpose"
			(at 0 0 270)
			(layer "F.Fab")
			(hide yes)
			(effects
				(font
					(size 1.27 1.27)
					(thickness 0.15)
				)
			)
		)
		(property "Author" "Antmicro"
			(at -0.38 214.05 0)
			(layer "B.Fab")
			(hide yes)
			(effects
				(font
					(size 1 1)
					(thickness 0.15)
				)
				(justify mirror)
			)
		)
		(property "License" "Apache-2.0"
			(at -0.38 214.05 0)
			(layer "B.Fab")
			(hide yes)
			(effects
				(font
					(size 1 1)
					(thickness 0.15)
				)
				(justify mirror)
			)
		)
		(property "MPN" "CR0402-FX-1001GLF"
			(at -0.38 214.05 0)
			(layer "B.Fab")
			(hide yes)
			(effects
				(font
					(size 1 1)
					(thickness 0.15)
				)
				(justify mirror)
			)
		)
		(property "Manufacturer" "Bourns"
			(at -0.38 214.05 0)
			(layer "B.Fab")
			(hide yes)
			(effects
				(font
					(size 1 1)
					(thickness 0.15)
				)
				(justify mirror)
			)
		)
		(property "Tolerance" "1%"
			(at -0.38 214.05 0)
			(layer "B.Fab")
			(hide yes)
			(effects
				(font
					(size 1 1)
					(thickness 0.15)
				)
				(justify mirror)
			)
		)
		(property "Val" "1k"
			(at -0.38 214.05 0)
			(layer "B.Fab")
			(hide yes)
			(effects
				(font
					(size 1 1)
					(thickness 0.15)
				)
				(justify mirror)
			)
		)
		(sheetname "/FPGA banks 13-16/")
		(sheetfile "fpga-banks-13-16.kicad_sch")
		(attr smd)
		(fp_rect
			(start -0.925 0.47)
			(end 0.925 -0.47)
			(stroke
				(width 0.05)
				(type default)
			)
			(fill no)
			(layer "B.CrtYd")
		)
		(fp_rect
			(start -0.5 0.25)
			(end 0.5 -0.25)
			(stroke
				(width 0.15)
				(type solid)
			)
			(fill no)
			(layer "B.Fab")
		)
		(pad "1" smd roundrect
			(at -0.48 0 270)
			(size 0.59 0.64)
			(layers "B.Cu" "B.Mask" "B.Paste")
			(roundrect_rratio 0.25)
			(net 2 "VCC3V3")
			(pintype "passive")
		)
		(pad "2" smd roundrect
			(at 0.48 0 270)
			(size 0.59 0.64)
			(layers "B.Cu" "B.Mask" "B.Paste")
			(roundrect_rratio 0.25)
			(net 260 "/FPGA banks 13-16/PUDC_B")
			(pintype "passive")
		)
	)
	(footprint "antmicro-footprints:R_0402_1005Metric"
		(layer "B.Cu")
		(at 107.855 107.225 90)
		(descr "Resistor SMD 0402")
		(tags "resistor SMD 0402")
		(property "Reference" "R2"
			(at -2.275 0.345 90)
			(layer "B.SilkS")
			(effects
				(font
					(size 0.7 0.7)
					(thickness 0.15)
				)
				(justify right bottom mirror)
			)
		)
		(property "Value" "R_1k_0402"
			(at 0 -1.4 90)
			(layer "B.Fab")
			(effects
				(font
					(size 0.7 0.7)
					(thickness 0.15)
				)
				(justify right bottom mirror)
			)
		)
		(property "Datasheet" "https://www.bourns.com/docs/product-datasheets/cr.pdf"
			(at 0 0 90)
			(layer "F.Fab")
			(hide yes)
			(effects
				(font
					(size 1.27 1.27)
					(thickness 0.15)
				)
			)
		)
		(property "Description" "SMD Chip Resistor, 1 kohm, ± 1%, 63 mW, 0402 [1005 Metric], Thick Film, General Purpose"
			(at 0 0 90)
			(layer "F.Fab")
			(hide yes)
			(effects
				(font
					(size 1.27 1.27)
					(thickness 0.15)
				)
			)
		)
		(property "Author" "Antmicro"
			(at 215.08 -0.63 0)
			(layer "B.Fab")
			(hide yes)
			(effects
				(font
					(size 1 1)
					(thickness 0.15)
				)
				(justify mirror)
			)
		)
		(property "License" "Apache-2.0"
			(at 215.08 -0.63 0)
			(layer "B.Fab")
			(hide yes)
			(effects
				(font
					(size 1 1)
					(thickness 0.15)
				)
				(justify mirror)
			)
		)
		(property "MPN" "CR0402-FX-1001GLF"
			(at 215.08 -0.63 0)
			(layer "B.Fab")
			(hide yes)
			(effects
				(font
					(size 1 1)
					(thickness 0.15)
				)
				(justify mirror)
			)
		)
		(property "Manufacturer" "Bourns"
			(at 215.08 -0.63 0)
			(layer "B.Fab")
			(hide yes)
			(effects
				(font
					(size 1 1)
					(thickness 0.15)
				)
				(justify mirror)
			)
		)
		(property "Tolerance" "1%"
			(at 215.08 -0.63 0)
			(layer "B.Fab")
			(hide yes)
			(effects
				(font
					(size 1 1)
					(thickness 0.15)
				)
				(justify mirror)
			)
		)
		(property "Val" "1k"
			(at 215.08 -0.63 0)
			(layer "B.Fab")
			(hide yes)
			(effects
				(font
					(size 1 1)
					(thickness 0.15)
				)
				(justify mirror)
			)
		)
		(property "DNP" ""
			(at 0 0 90)
			(unlocked yes)
			(layer "B.Fab")
			(hide yes)
			(effects
				(font
					(size 1 1)
					(thickness 0.15)
				)
				(justify mirror)
			)
		)
		(sheetname "/FPGA banks 13-16/")
		(sheetfile "fpga-banks-13-16.kicad_sch")
		(attr smd)
		(fp_rect
			(start -0.925 0.47)
			(end 0.925 -0.47)
			(stroke
				(width 0.05)
				(type default)
			)
			(fill no)
			(layer "B.CrtYd")
		)
		(fp_rect
			(start -0.5 0.25)
			(end 0.5 -0.25)
			(stroke
				(width 0.15)
				(type solid)
			)
			(fill no)
			(layer "B.Fab")
		)
		(pad "1" smd roundrect
			(at -0.48 0 90)
			(size 0.59 0.64)
			(layers "B.Cu" "B.Mask" "B.Paste")
			(roundrect_rratio 0.25)
			(net 260 "/FPGA banks 13-16/PUDC_B")
			(pintype "passive")
		)
		(pad "2" smd roundrect
			(at 0.48 0 90)
			(size 0.59 0.64)
			(layers "B.Cu" "B.Mask" "B.Paste")
			(roundrect_rratio 0.25)
			(net 1 "GND")
			(pintype "passive")
		)
	)
	(footprint "antmicro-footprints:R_0402_1005Metric"
		(layer "B.Cu")
		(at 68.09 87.315)
		(descr "Resistor SMD 0402")
		(tags "resistor SMD 0402")
		(property "Reference" "R128"
			(at -3.59 0.36 0)
			(layer "B.SilkS")
			(effects
				(font
					(size 0.7 0.7)
					(thickness 0.15)
				)
				(justify right bottom mirror)
			)
		)
		(property "Value" "R_1k_0402"
			(at 0 -1.4 0)
			(layer "B.Fab")
			(effects
				(font
					(size 0.7 0.7)
					(thickness 0.15)
				)
				(justify right bottom mirror)
			)
		)
		(property "Datasheet" "https://www.bourns.com/docs/product-datasheets/cr.pdf"
			(at 0 0 0)
			(layer "F.Fab")
			(hide yes)
			(effects
				(font
					(size 1.27 1.27)
					(thickness 0.15)
				)
			)
		)
		(property "Description" "SMD Chip Resistor, 1 kohm, ± 1%, 63 mW, 0402 [1005 Metric], Thick Film, General Purpose"
			(at 0 0 0)
			(layer "F.Fab")
			(hide yes)
			(effects
				(font
					(size 1.27 1.27)
					(thickness 0.15)
				)
			)
		)
		(property "Author" "Antmicro"
			(at 0 0 0)
			(layer "B.Fab")
			(hide yes)
			(effects
				(font
					(size 1 1)
					(thickness 0.15)
				)
				(justify mirror)
			)
		)
		(property "License" "Apache-2.0"
			(at 0 0 0)
			(layer "B.Fab")
			(hide yes)
			(effects
				(font
					(size 1 1)
					(thickness 0.15)
				)
				(justify mirror)
			)
		)
		(property "MPN" "CR0402-FX-1001GLF"
			(at 0 0 0)
			(layer "B.Fab")
			(hide yes)
			(effects
				(font
					(size 1 1)
					(thickness 0.15)
				)
				(justify mirror)
			)
		)
		(property "Manufacturer" "Bourns"
			(at 0 0 0)
			(layer "B.Fab")
			(hide yes)
			(effects
				(font
					(size 1 1)
					(thickness 0.15)
				)
				(justify mirror)
			)
		)
		(property "Tolerance" "1%"
			(at 0 0 0)
			(layer "B.Fab")
			(hide yes)
			(effects
				(font
					(size 1 1)
					(thickness 0.15)
				)
				(justify mirror)
			)
		)
		(property "Val" "1k"
			(at 0 0 0)
			(layer "B.Fab")
			(hide yes)
			(effects
				(font
					(size 1 1)
					(thickness 0.15)
				)
				(justify mirror)
			)
		)
		(sheetname "/FPGA banks 34-35 & CFG/")
		(sheetfile "fpga-banks-34-25-cfg.kicad_sch")
		(attr smd)
		(fp_rect
			(start -0.925 0.47)
			(end 0.925 -0.47)
			(stroke
				(width 0.05)
				(type default)
			)
			(fill no)
			(layer "B.CrtYd")
		)
		(fp_rect
			(start -0.5 0.25)
			(end 0.5 -0.25)
			(stroke
				(width 0.15)
				(type solid)
			)
			(fill no)
			(layer "B.Fab")
		)
		(pad "1" smd roundrect
			(at -0.48 0)
			(size 0.59 0.64)
			(layers "B.Cu" "B.Mask" "B.Paste")
			(roundrect_rratio 0.25)
			(net 279 "Net-(D9-A)")
			(pintype "passive")
		)
		(pad "2" smd roundrect
			(at 0.48 0)
			(size 0.59 0.64)
			(layers "B.Cu" "B.Mask" "B.Paste")
			(roundrect_rratio 0.25)
			(net 2 "VCC3V3")
			(pintype "passive")
		)
	)
	(footprint "antmicro-footprints:R_0402_1005Metric"
		(layer "B.Cu")
		(at 68.09 85.24)
		(descr "Resistor SMD 0402")
		(tags "resistor SMD 0402")
		(property "Reference" "R129"
			(at -3.59 0.36 0)
			(layer "B.SilkS")
			(effects
				(font
					(size 0.7 0.7)
					(thickness 0.15)
				)
				(justify right bottom mirror)
			)
		)
		(property "Value" "R_1k_0402"
			(at 0 -1.4 0)
			(layer "B.Fab")
			(effects
				(font
					(size 0.7 0.7)
					(thickness 0.15)
				)
				(justify right bottom mirror)
			)
		)
		(property "Datasheet" "https://www.bourns.com/docs/product-datasheets/cr.pdf"
			(at 0 0 0)
			(layer "F.Fab")
			(hide yes)
			(effects
				(font
					(size 1.27 1.27)
					(thickness 0.15)
				)
			)
		)
		(property "Description" "SMD Chip Resistor, 1 kohm, ± 1%, 63 mW, 0402 [1005 Metric], Thick Film, General Purpose"
			(at 0 0 0)
			(layer "F.Fab")
			(hide yes)
			(effects
				(font
					(size 1.27 1.27)
					(thickness 0.15)
				)
			)
		)
		(property "Author" "Antmicro"
			(at 0 0 0)
			(layer "B.Fab")
			(hide yes)
			(effects
				(font
					(size 1 1)
					(thickness 0.15)
				)
				(justify mirror)
			)
		)
		(property "License" "Apache-2.0"
			(at 0 0 0)
			(layer "B.Fab")
			(hide yes)
			(effects
				(font
					(size 1 1)
					(thickness 0.15)
				)
				(justify mirror)
			)
		)
		(property "MPN" "CR0402-FX-1001GLF"
			(at 0 0 0)
			(layer "B.Fab")
			(hide yes)
			(effects
				(font
					(size 1 1)
					(thickness 0.15)
				)
				(justify mirror)
			)
		)
		(property "Manufacturer" "Bourns"
			(at 0 0 0)
			(layer "B.Fab")
			(hide yes)
			(effects
				(font
					(size 1 1)
					(thickness 0.15)
				)
				(justify mirror)
			)
		)
		(property "Tolerance" "1%"
			(at 0 0 0)
			(layer "B.Fab")
			(hide yes)
			(effects
				(font
					(size 1 1)
					(thickness 0.15)
				)
				(justify mirror)
			)
		)
		(property "Val" "1k"
			(at 0 0 0)
			(layer "B.Fab")
			(hide yes)
			(effects
				(font
					(size 1 1)
					(thickness 0.15)
				)
				(justify mirror)
			)
		)
		(sheetname "/FPGA banks 34-35 & CFG/")
		(sheetfile "fpga-banks-34-25-cfg.kicad_sch")
		(attr smd)
		(fp_rect
			(start -0.925 0.47)
			(end 0.925 -0.47)
			(stroke
				(width 0.05)
				(type default)
			)
			(fill no)
			(layer "B.CrtYd")
		)
		(fp_rect
			(start -0.5 0.25)
			(end 0.5 -0.25)
			(stroke
				(width 0.15)
				(type solid)
			)
			(fill no)
			(layer "B.Fab")
		)
		(pad "1" smd roundrect
			(at -0.48 0)
			(size 0.59 0.64)
			(layers "B.Cu" "B.Mask" "B.Paste")
			(roundrect_rratio 0.25)
			(net 283 "Net-(D10-A)")
			(pintype "passive")
		)
		(pad "2" smd roundrect
			(at 0.48 0)
			(size 0.59 0.64)
			(layers "B.Cu" "B.Mask" "B.Paste")
			(roundrect_rratio 0.25)
			(net 2 "VCC3V3")
			(pintype "passive")
		)
	)
	(footprint "antmicro-footprints:R_0402_1005Metric"
		(layer "B.Cu")
		(at 75.575 158.475 90)
		(descr "Resistor SMD 0402")
		(tags "resistor SMD 0402")
		(property "Reference" "R135"
			(at -3.625 0.425 90)
			(layer "B.SilkS")
			(effects
				(font
					(size 0.7 0.7)
					(thickness 0.15)
				)
				(justify right bottom mirror)
			)
		)
		(property "Value" "R_4k7_0402"
			(at 0 -1.4 90)
			(layer "B.Fab")
			(effects
				(font
					(size 0.7 0.7)
					(thickness 0.15)
				)
				(justify right bottom mirror)
			)
		)
		(property "Datasheet" "https://www.bourns.com/docs/product-datasheets/cr.pdf"
			(at 0 0 90)
			(layer "F.Fab")
			(hide yes)
			(effects
				(font
					(size 1.27 1.27)
					(thickness 0.15)
				)
			)
		)
		(property "Description" "SMD Chip Resistor, 4.7 kohm, ± 1%, 62.5 mW, 0402 [1005 Metric], Thick Film, General Purpose"
			(at 0 0 90)
			(layer "F.Fab")
			(hide yes)
			(effects
				(font
					(size 1.27 1.27)
					(thickness 0.15)
				)
			)
		)
		(property "Author" "Antmicro"
			(at 234.05 82.9 0)
			(layer "B.Fab")
			(hide yes)
			(effects
				(font
					(size 1 1)
					(thickness 0.15)
				)
				(justify mirror)
			)
		)
		(property "License" "Apache-2.0"
			(at 234.05 82.9 0)
			(layer "B.Fab")
			(hide yes)
			(effects
				(font
					(size 1 1)
					(thickness 0.15)
				)
				(justify mirror)
			)
		)
		(property "MPN" "CR0402-FX-4701GLF"
			(at 234.05 82.9 0)
			(layer "B.Fab")
			(hide yes)
			(effects
				(font
					(size 1 1)
					(thickness 0.15)
				)
				(justify mirror)
			)
		)
		(property "Manufacturer" "Bourns"
			(at 234.05 82.9 0)
			(layer "B.Fab")
			(hide yes)
			(effects
				(font
					(size 1 1)
					(thickness 0.15)
				)
				(justify mirror)
			)
		)
		(property "Tolerance" "1%"
			(at 234.05 82.9 0)
			(layer "B.Fab")
			(hide yes)
			(effects
				(font
					(size 1 1)
					(thickness 0.15)
				)
				(justify mirror)
			)
		)
		(property "Val" "4k7"
			(at 234.05 82.9 0)
			(layer "B.Fab")
			(hide yes)
			(effects
				(font
					(size 1 1)
					(thickness 0.15)
				)
				(justify mirror)
			)
		)
		(property "DNP" ""
			(at 0 0 90)
			(unlocked yes)
			(layer "B.Fab")
			(hide yes)
			(effects
				(font
					(size 1 1)
					(thickness 0.15)
				)
				(justify mirror)
			)
		)
		(sheetname "/FPGA banks 13-16/")
		(sheetfile "fpga-banks-13-16.kicad_sch")
		(attr smd)
		(fp_rect
			(start -0.925 0.47)
			(end 0.925 -0.47)
			(stroke
				(width 0.05)
				(type default)
			)
			(fill no)
			(layer "B.CrtYd")
		)
		(fp_rect
			(start -0.5 0.25)
			(end 0.5 -0.25)
			(stroke
				(width 0.15)
				(type solid)
			)
			(fill no)
			(layer "B.Fab")
		)
		(pad "1" smd roundrect
			(at -0.48 0 90)
			(size 0.59 0.64)
			(layers "B.Cu" "B.Mask" "B.Paste")
			(roundrect_rratio 0.25)
			(net 2 "VCC3V3")
			(pintype "passive")
		)
		(pad "2" smd roundrect
			(at 0.48 0 90)
			(size 0.59 0.64)
			(layers "B.Cu" "B.Mask" "B.Paste")
			(roundrect_rratio 0.25)
			(net 333 "ROT_QSPI_DQ3")
			(pintype "passive")
		)
	)
	(footprint "antmicro-footprints:C_0402_1005Metric"
		(layer "B.Cu")
		(at 101.775 127.025 180)
		(descr "Capacitor SMD 0402")
		(tags "capacitor SMD 0402")
		(property "Reference" "C114"
			(at -1.325 -1.275 0)
			(layer "B.SilkS")
			(effects
				(font
					(size 0.7 0.7)
					(thickness 0.15)
				)
				(justify left bottom mirror)
			)
		)
		(property "Value" "C_470n_0402"
			(at 0 -1.4 0)
			(layer "B.Fab")
			(effects
				(font
					(size 0.7 0.7)
					(thickness 0.15)
				)
				(justify left bottom mirror)
			)
		)
		(property "Datasheet" "https://product.tdk.com/en/search/capacitor/ceramic/mlcc/info?part_no=C1005X5R1E474M050BB"
			(at 0 0 180)
			(layer "F.Fab")
			(hide yes)
			(effects
				(font
					(size 1.27 1.27)
					(thickness 0.15)
				)
			)
		)
		(property "Description" "SMD Multilayer Ceramic Capacitor, 0.47 µF, 25 V, 0402 [1005 Metric], ± 20%, X5R, C"
			(at 0 0 180)
			(layer "F.Fab")
			(hide yes)
			(effects
				(font
					(size 1.27 1.27)
					(thickness 0.15)
				)
			)
		)
		(property "Author" "Antmicro"
			(at 203.55 254.05 0)
			(layer "B.Fab")
			(hide yes)
			(effects
				(font
					(size 1 1)
					(thickness 0.15)
				)
				(justify mirror)
			)
		)
		(property "Dielectric" ""
			(at 203.55 254.05 0)
			(layer "B.Fab")
			(hide yes)
			(effects
				(font
					(size 1 1)
					(thickness 0.15)
				)
				(justify mirror)
			)
		)
		(property "License" "Apache-2.0"
			(at 203.55 254.05 0)
			(layer "B.Fab")
			(hide yes)
			(effects
				(font
					(size 1 1)
					(thickness 0.15)
				)
				(justify mirror)
			)
		)
		(property "MPN" "C1005X5R1E474M050BB"
			(at 203.55 254.05 0)
			(layer "B.Fab")
			(hide yes)
			(effects
				(font
					(size 1 1)
					(thickness 0.15)
				)
				(justify mirror)
			)
		)
		(property "Manufacturer" "TDK"
			(at 203.55 254.05 0)
			(layer "B.Fab")
			(hide yes)
			(effects
				(font
					(size 1 1)
					(thickness 0.15)
				)
				(justify mirror)
			)
		)
		(property "Val" "470n"
			(at 203.55 254.05 0)
			(layer "B.Fab")
			(hide yes)
			(effects
				(font
					(size 1 1)
					(thickness 0.15)
				)
				(justify mirror)
			)
		)
		(property "Voltage" ""
			(at 203.55 254.05 0)
			(layer "B.Fab")
			(hide yes)
			(effects
				(font
					(size 1 1)
					(thickness 0.15)
				)
				(justify mirror)
			)
		)
		(property "DNP" ""
			(at 0 0 180)
			(unlocked yes)
			(layer "B.Fab")
			(hide yes)
			(effects
				(font
					(size 1 1)
					(thickness 0.15)
				)
				(justify mirror)
			)
		)
		(sheetname "/FPGA banks 34-35 & CFG/")
		(sheetfile "fpga-banks-34-25-cfg.kicad_sch")
		(attr smd)
		(fp_rect
			(start -0.925 0.47)
			(end 0.925 -0.47)
			(stroke
				(width 0.05)
				(type default)
			)
			(fill no)
			(layer "B.CrtYd")
		)
		(fp_line
			(start 0.504 0.25)
			(end 0.504 -0.248)
			(stroke
				(width 0.15)
				(type solid)
			)
			(layer "B.Fab")
		)
		(fp_line
			(start 0.504 -0.248)
			(end -0.494 -0.248)
			(stroke
				(width 0.15)
				(type solid)
			)
			(layer "B.Fab")
		)
		(fp_line
			(start -0.494 0.25)
			(end 0.504 0.25)
			(stroke
				(width 0.15)
				(type solid)
			)
			(layer "B.Fab")
		)
		(fp_line
			(start -0.494 -0.248)
			(end -0.494 0.25)
			(stroke
				(width 0.15)
				(type solid)
			)
			(layer "B.Fab")
		)
		(pad "1" smd roundrect
			(at -0.48 0 180)
			(size 0.59 0.64)
			(layers "B.Cu" "B.Mask" "B.Paste")
			(roundrect_rratio 0.25)
			(net 1 "GND")
			(pintype "passive")
		)
		(pad "2" smd roundrect
			(at 0.48 0 180)
			(size 0.59 0.64)
			(layers "B.Cu" "B.Mask" "B.Paste")
			(roundrect_rratio 0.25)
			(net 3 "VCC1V35")
			(pintype "passive")
		)
	)
	(footprint "antmicro-footprints:C_0402_1005Metric"
		(layer "B.Cu")
		(at 95.225 128.425 -90)
		(descr "Capacitor SMD 0402")
		(tags "capacitor SMD 0402")
		(property "Reference" "C120"
			(at -1.025 0.525 90)
			(layer "B.SilkS")
			(effects
				(font
					(size 0.7 0.7)
					(thickness 0.15)
				)
				(justify left bottom mirror)
			)
		)
		(property "Value" "C_470n_0402"
			(at 0 -1.4 90)
			(layer "B.Fab")
			(effects
				(font
					(size 0.7 0.7)
					(thickness 0.15)
				)
				(justify left bottom mirror)
			)
		)
		(property "Datasheet" "https://product.tdk.com/en/search/capacitor/ceramic/mlcc/info?part_no=C1005X5R1E474M050BB"
			(at 0 0 270)
			(layer "F.Fab")
			(hide yes)
			(effects
				(font
					(size 1.27 1.27)
					(thickness 0.15)
				)
			)
		)
		(property "Description" "SMD Multilayer Ceramic Capacitor, 0.47 µF, 25 V, 0402 [1005 Metric], ± 20%, X5R, C"
			(at 0 0 270)
			(layer "F.Fab")
			(hide yes)
			(effects
				(font
					(size 1.27 1.27)
					(thickness 0.15)
				)
			)
		)
		(property "Author" "Antmicro"
			(at -33.2 223.65 0)
			(layer "B.Fab")
			(hide yes)
			(effects
				(font
					(size 1 1)
					(thickness 0.15)
				)
				(justify mirror)
			)
		)
		(property "Dielectric" ""
			(at -33.2 223.65 0)
			(layer "B.Fab")
			(hide yes)
			(effects
				(font
					(size 1 1)
					(thickness 0.15)
				)
				(justify mirror)
			)
		)
		(property "License" "Apache-2.0"
			(at -33.2 223.65 0)
			(layer "B.Fab")
			(hide yes)
			(effects
				(font
					(size 1 1)
					(thickness 0.15)
				)
				(justify mirror)
			)
		)
		(property "MPN" "C1005X5R1E474M050BB"
			(at -33.2 223.65 0)
			(layer "B.Fab")
			(hide yes)
			(effects
				(font
					(size 1 1)
					(thickness 0.15)
				)
				(justify mirror)
			)
		)
		(property "Manufacturer" "TDK"
			(at -33.2 223.65 0)
			(layer "B.Fab")
			(hide yes)
			(effects
				(font
					(size 1 1)
					(thickness 0.15)
				)
				(justify mirror)
			)
		)
		(property "Val" "470n"
			(at -33.2 223.65 0)
			(layer "B.Fab")
			(hide yes)
			(effects
				(font
					(size 1 1)
					(thickness 0.15)
				)
				(justify mirror)
			)
		)
		(property "Voltage" ""
			(at -33.2 223.65 0)
			(layer "B.Fab")
			(hide yes)
			(effects
				(font
					(size 1 1)
					(thickness 0.15)
				)
				(justify mirror)
			)
		)
		(property "DNP" ""
			(at 0 0 270)
			(unlocked yes)
			(layer "B.Fab")
			(hide yes)
			(effects
				(font
					(size 1 1)
					(thickness 0.15)
				)
				(justify mirror)
			)
		)
		(sheetname "/FPGA banks 34-35 & CFG/")
		(sheetfile "fpga-banks-34-25-cfg.kicad_sch")
		(attr smd)
		(fp_rect
			(start -0.925 0.47)
			(end 0.925 -0.47)
			(stroke
				(width 0.05)
				(type default)
			)
			(fill no)
			(layer "B.CrtYd")
		)
		(fp_line
			(start -0.494 0.25)
			(end 0.504 0.25)
			(stroke
				(width 0.15)
				(type solid)
			)
			(layer "B.Fab")
		)
		(fp_line
			(start 0.504 0.25)
			(end 0.504 -0.248)
			(stroke
				(width 0.15)
				(type solid)
			)
			(layer "B.Fab")
		)
		(fp_line
			(start -0.494 -0.248)
			(end -0.494 0.25)
			(stroke
				(width 0.15)
				(type solid)
			)
			(layer "B.Fab")
		)
		(fp_line
			(start 0.504 -0.248)
			(end -0.494 -0.248)
			(stroke
				(width 0.15)
				(type solid)
			)
			(layer "B.Fab")
		)
		(pad "1" smd roundrect
			(at -0.48 0 270)
			(size 0.59 0.64)
			(layers "B.Cu" "B.Mask" "B.Paste")
			(roundrect_rratio 0.25)
			(net 1 "GND")
			(pintype "passive")
		)
		(pad "2" smd roundrect
			(at 0.48 0 270)
			(size 0.59 0.64)
			(layers "B.Cu" "B.Mask" "B.Paste")
			(roundrect_rratio 0.25)
			(net 3 "VCC1V35")
			(pintype "passive")
		)
	)
	(footprint "antmicro-footprints:C_0402_1005Metric"
		(layer "B.Cu")
		(at 96.825 126.575)
		(descr "Capacitor SMD 0402")
		(tags "capacitor SMD 0402")
		(property "Reference" "C126"
			(at -1.625 -0.475 0)
			(layer "B.SilkS")
			(effects
				(font
					(size 0.7 0.7)
					(thickness 0.15)
				)
				(justify right bottom mirror)
			)
		)
		(property "Value" "C_470n_0402"
			(at 0 -1.4 0)
			(layer "B.Fab")
			(effects
				(font
					(size 0.7 0.7)
					(thickness 0.15)
				)
				(justify right bottom mirror)
			)
		)
		(property "Datasheet" "https://product.tdk.com/en/search/capacitor/ceramic/mlcc/info?part_no=C1005X5R1E474M050BB"
			(at 0 0 0)
			(layer "F.Fab")
			(hide yes)
			(effects
				(font
					(size 1.27 1.27)
					(thickness 0.15)
				)
			)
		)
		(property "Description" "SMD Multilayer Ceramic Capacitor, 0.47 µF, 25 V, 0402 [1005 Metric], ± 20%, X5R, C"
			(at 0 0 0)
			(layer "F.Fab")
			(hide yes)
			(effects
				(font
					(size 1.27 1.27)
					(thickness 0.15)
				)
			)
		)
		(property "Author" "Antmicro"
			(at 0 0 0)
			(layer "B.Fab")
			(hide yes)
			(effects
				(font
					(size 1 1)
					(thickness 0.15)
				)
				(justify mirror)
			)
		)
		(property "Dielectric" ""
			(at 0 0 0)
			(layer "B.Fab")
			(hide yes)
			(effects
				(font
					(size 1 1)
					(thickness 0.15)
				)
				(justify mirror)
			)
		)
		(property "License" "Apache-2.0"
			(at 0 0 0)
			(layer "B.Fab")
			(hide yes)
			(effects
				(font
					(size 1 1)
					(thickness 0.15)
				)
				(justify mirror)
			)
		)
		(property "MPN" "C1005X5R1E474M050BB"
			(at 0 0 0)
			(layer "B.Fab")
			(hide yes)
			(effects
				(font
					(size 1 1)
					(thickness 0.15)
				)
				(justify mirror)
			)
		)
		(property "Manufacturer" "TDK"
			(at 0 0 0)
			(layer "B.Fab")
			(hide yes)
			(effects
				(font
					(size 1 1)
					(thickness 0.15)
				)
				(justify mirror)
			)
		)
		(property "Val" "470n"
			(at 0 0 0)
			(layer "B.Fab")
			(hide yes)
			(effects
				(font
					(size 1 1)
					(thickness 0.15)
				)
				(justify mirror)
			)
		)
		(property "Voltage" ""
			(at 0 0 0)
			(layer "B.Fab")
			(hide yes)
			(effects
				(font
					(size 1 1)
					(thickness 0.15)
				)
				(justify mirror)
			)
		)
		(property "DNP" ""
			(at 0 0 0)
			(unlocked yes)
			(layer "B.Fab")
			(hide yes)
			(effects
				(font
					(size 1 1)
					(thickness 0.15)
				)
				(justify mirror)
			)
		)
		(sheetname "/FPGA banks 34-35 & CFG/")
		(sheetfile "fpga-banks-34-25-cfg.kicad_sch")
		(attr smd)
		(fp_rect
			(start -0.925 0.47)
			(end 0.925 -0.47)
			(stroke
				(width 0.05)
				(type default)
			)
			(fill no)
			(layer "B.CrtYd")
		)
		(fp_line
			(start -0.494 -0.248)
			(end -0.494 0.25)
			(stroke
				(width 0.15)
				(type solid)
			)
			(layer "B.Fab")
		)
		(fp_line
			(start -0.494 0.25)
			(end 0.504 0.25)
			(stroke
				(width 0.15)
				(type solid)
			)
			(layer "B.Fab")
		)
		(fp_line
			(start 0.504 -0.248)
			(end -0.494 -0.248)
			(stroke
				(width 0.15)
				(type solid)
			)
			(layer "B.Fab")
		)
		(fp_line
			(start 0.504 0.25)
			(end 0.504 -0.248)
			(stroke
				(width 0.15)
				(type solid)
			)
			(layer "B.Fab")
		)
		(pad "1" smd roundrect
			(at -0.48 0)
			(size 0.59 0.64)
			(layers "B.Cu" "B.Mask" "B.Paste")
			(roundrect_rratio 0.25)
			(net 1 "GND")
			(pintype "passive")
		)
		(pad "2" smd roundrect
			(at 0.48 0)
			(size 0.59 0.64)
			(layers "B.Cu" "B.Mask" "B.Paste")
			(roundrect_rratio 0.25)
			(net 3 "VCC1V35")
			(pintype "passive")
		)
	)
	(footprint "antmicro-footprints:C_0402_1005Metric"
		(layer "B.Cu")
		(at 93.025 129.125 -90)
		(descr "Capacitor SMD 0402")
		(tags "capacitor SMD 0402")
		(property "Reference" "C132"
			(at -1.025 0.525 90)
			(layer "B.SilkS")
			(effects
				(font
					(size 0.7 0.7)
					(thickness 0.15)
				)
				(justify left bottom mirror)
			)
		)
		(property "Value" "C_470n_0402"
			(at 0 -1.4 90)
			(layer "B.Fab")
			(effects
				(font
					(size 0.7 0.7)
					(thickness 0.15)
				)
				(justify left bottom mirror)
			)
		)
		(property "Datasheet" "https://product.tdk.com/en/search/capacitor/ceramic/mlcc/info?part_no=C1005X5R1E474M050BB"
			(at 0 0 270)
			(layer "F.Fab")
			(hide yes)
			(effects
				(font
					(size 1.27 1.27)
					(thickness 0.15)
				)
			)
		)
		(property "Description" "SMD Multilayer Ceramic Capacitor, 0.47 µF, 25 V, 0402 [1005 Metric], ± 20%, X5R, C"
			(at 0 0 270)
			(layer "F.Fab")
			(hide yes)
			(effects
				(font
					(size 1.27 1.27)
					(thickness 0.15)
				)
			)
		)
		(property "Author" "Antmicro"
			(at -36.1 222.15 0)
			(layer "B.Fab")
			(hide yes)
			(effects
				(font
					(size 1 1)
					(thickness 0.15)
				)
				(justify mirror)
			)
		)
		(property "Dielectric" ""
			(at -36.1 222.15 0)
			(layer "B.Fab")
			(hide yes)
			(effects
				(font
					(size 1 1)
					(thickness 0.15)
				)
				(justify mirror)
			)
		)
		(property "License" "Apache-2.0"
			(at -36.1 222.15 0)
			(layer "B.Fab")
			(hide yes)
			(effects
				(font
					(size 1 1)
					(thickness 0.15)
				)
				(justify mirror)
			)
		)
		(property "MPN" "C1005X5R1E474M050BB"
			(at -36.1 222.15 0)
			(layer "B.Fab")
			(hide yes)
			(effects
				(font
					(size 1 1)
					(thickness 0.15)
				)
				(justify mirror)
			)
		)
		(property "Manufacturer" "TDK"
			(at -36.1 222.15 0)
			(layer "B.Fab")
			(hide yes)
			(effects
				(font
					(size 1 1)
					(thickness 0.15)
				)
				(justify mirror)
			)
		)
		(property "Val" "470n"
			(at -36.1 222.15 0)
			(layer "B.Fab")
			(hide yes)
			(effects
				(font
					(size 1 1)
					(thickness 0.15)
				)
				(justify mirror)
			)
		)
		(property "Voltage" ""
			(at -36.1 222.15 0)
			(layer "B.Fab")
			(hide yes)
			(effects
				(font
					(size 1 1)
					(thickness 0.15)
				)
				(justify mirror)
			)
		)
		(property "DNP" ""
			(at 0 0 270)
			(unlocked yes)
			(layer "B.Fab")
			(hide yes)
			(effects
				(font
					(size 1 1)
					(thickness 0.15)
				)
				(justify mirror)
			)
		)
		(sheetname "/FPGA banks 34-35 & CFG/")
		(sheetfile "fpga-banks-34-25-cfg.kicad_sch")
		(attr smd)
		(fp_rect
			(start -0.925 0.47)
			(end 0.925 -0.47)
			(stroke
				(width 0.05)
				(type default)
			)
			(fill no)
			(layer "B.CrtYd")
		)
		(fp_line
			(start -0.494 0.25)
			(end 0.504 0.25)
			(stroke
				(width 0.15)
				(type solid)
			)
			(layer "B.Fab")
		)
		(fp_line
			(start 0.504 0.25)
			(end 0.504 -0.248)
			(stroke
				(width 0.15)
				(type solid)
			)
			(layer "B.Fab")
		)
		(fp_line
			(start -0.494 -0.248)
			(end -0.494 0.25)
			(stroke
				(width 0.15)
				(type solid)
			)
			(layer "B.Fab")
		)
		(fp_line
			(start 0.504 -0.248)
			(end -0.494 -0.248)
			(stroke
				(width 0.15)
				(type solid)
			)
			(layer "B.Fab")
		)
		(pad "1" smd roundrect
			(at -0.48 0 270)
			(size 0.59 0.64)
			(layers "B.Cu" "B.Mask" "B.Paste")
			(roundrect_rratio 0.25)
			(net 1 "GND")
			(pintype "passive")
		)
		(pad "2" smd roundrect
			(at 0.48 0 270)
			(size 0.59 0.64)
			(layers "B.Cu" "B.Mask" "B.Paste")
			(roundrect_rratio 0.25)
			(net 3 "VCC1V35")
			(pintype "passive")
		)
	)
	(footprint "antmicro-footprints:C_0201"
		(layer "B.Cu")
		(at 96.375 121.675)
		(descr "Capacitor SMD 0201")
		(tags "capacitor SMD 0201")
		(property "Reference" "C152"
			(at -23.375 0.825 0)
			(layer "B.SilkS")
			(effects
				(font
					(size 0.7 0.7)
					(thickness 0.15)
				)
				(justify right bottom mirror)
			)
		)
		(property "Value" "C_470n_0201"
			(at 0 -1.4 0)
			(layer "B.Fab")
			(effects
				(font
					(size 0.7 0.7)
					(thickness 0.15)
				)
				(justify right bottom mirror)
			)
		)
		(property "Datasheet" "https://product.tdk.com/en/search/capacitor/ceramic/mlcc/info?part_no=C0603X5R1A474M030BC"
			(at 0 0 0)
			(layer "F.Fab")
			(hide yes)
			(effects
				(font
					(size 1.27 1.27)
					(thickness 0.15)
				)
			)
		)
		(property "Description" "SMD Multilayer Ceramic Capacitor, 0.47 µF, 10 V, 0201 [0603 Metric], ± 20%, X5R, C"
			(at 0 0 0)
			(layer "F.Fab")
			(hide yes)
			(effects
				(font
					(size 1.27 1.27)
					(thickness 0.15)
				)
			)
		)
		(property "Author" "Antmicro"
			(at 0 0 0)
			(layer "B.Fab")
			(hide yes)
			(effects
				(font
					(size 1 1)
					(thickness 0.15)
				)
				(justify mirror)
			)
		)
		(property "Dielectric" ""
			(at 0 0 0)
			(layer "B.Fab")
			(hide yes)
			(effects
				(font
					(size 1 1)
					(thickness 0.15)
				)
				(justify mirror)
			)
		)
		(property "License" "Apache-2.0"
			(at 0 0 0)
			(layer "B.Fab")
			(hide yes)
			(effects
				(font
					(size 1 1)
					(thickness 0.15)
				)
				(justify mirror)
			)
		)
		(property "MPN" "C0603X5R1A474M030BC"
			(at 0 0 0)
			(layer "B.Fab")
			(hide yes)
			(effects
				(font
					(size 1 1)
					(thickness 0.15)
				)
				(justify mirror)
			)
		)
		(property "Manufacturer" "TDK"
			(at 0 0 0)
			(layer "B.Fab")
			(hide yes)
			(effects
				(font
					(size 1 1)
					(thickness 0.15)
				)
				(justify mirror)
			)
		)
		(property "Public" "False"
			(at 0 0 0)
			(layer "B.Fab")
			(hide yes)
			(effects
				(font
					(size 1 1)
					(thickness 0.15)
				)
				(justify mirror)
			)
		)
		(property "Val" "470n"
			(at 0 0 0)
			(layer "B.Fab")
			(hide yes)
			(effects
				(font
					(size 1 1)
					(thickness 0.15)
				)
				(justify mirror)
			)
		)
		(property "Voltage" ""
			(at 0 0 0)
			(layer "B.Fab")
			(hide yes)
			(effects
				(font
					(size 1 1)
					(thickness 0.15)
				)
				(justify mirror)
			)
		)
		(property "DNP" ""
			(at 0 0 0)
			(unlocked yes)
			(layer "B.Fab")
			(hide yes)
			(effects
				(font
					(size 1 1)
					(thickness 0.15)
				)
				(justify mirror)
			)
		)
		(sheetname "/FPGA power supply/")
		(sheetfile "fpga-power-supply.kicad_sch")
		(attr smd)
		(fp_rect
			(start -0.7 0.35)
			(end 0.7 -0.35)
			(stroke
				(width 0.05)
				(type default)
			)
			(fill no)
			(layer "B.CrtYd")
		)
		(fp_rect
			(start 0.3 -0.15)
			(end -0.301 0.149)
			(stroke
				(width 0.15)
				(type solid)
			)
			(fill no)
			(layer "B.Fab")
		)
		(pad "" smd roundrect
			(at -0.349 0.002)
			(size 0.318 0.36)
			(layers "B.Paste")
			(roundrect_rratio 0.25)
		)
		(pad "" smd roundrect
			(at 0.341 0.002)
			(size 0.318 0.36)
			(layers "B.Paste")
			(roundrect_rratio 0.25)
		)
		(pad "1" smd roundrect
			(at -0.321 0.002)
			(size 0.46 0.4)
			(layers "B.Cu" "B.Mask")
			(roundrect_rratio 0.25)
			(net 1 "GND")
			(pintype "passive")
		)
		(pad "2" smd roundrect
			(at 0.32 0.002)
			(size 0.46 0.4)
			(layers "B.Cu" "B.Mask")
			(roundrect_rratio 0.25)
			(net 6 "VCC1V0")
			(pintype "passive")
		)
	)
	(footprint "antmicro-footprints:C_0201"
		(layer "B.Cu")
		(at 100.325 120.675)
		(descr "Capacitor SMD 0201")
		(tags "capacitor SMD 0201")
		(property "Reference" "C138"
			(at -21.525 0.625 0)
			(layer "B.SilkS")
			(effects
				(font
					(size 0.7 0.7)
					(thickness 0.15)
				)
				(justify right bottom mirror)
			)
		)
		(property "Value" "C_470n_0201"
			(at 0 -1.4 0)
			(layer "B.Fab")
			(effects
				(font
					(size 0.7 0.7)
					(thickness 0.15)
				)
				(justify right bottom mirror)
			)
		)
		(property "Datasheet" "https://product.tdk.com/en/search/capacitor/ceramic/mlcc/info?part_no=C0603X5R1A474M030BC"
			(at 0 0 0)
			(layer "F.Fab")
			(hide yes)
			(effects
				(font
					(size 1.27 1.27)
					(thickness 0.15)
				)
			)
		)
		(property "Description" "SMD Multilayer Ceramic Capacitor, 0.47 µF, 10 V, 0201 [0603 Metric], ± 20%, X5R, C"
			(at 0 0 0)
			(layer "F.Fab")
			(hide yes)
			(effects
				(font
					(size 1.27 1.27)
					(thickness 0.15)
				)
			)
		)
		(property "Author" "Antmicro"
			(at 0 0 0)
			(layer "B.Fab")
			(hide yes)
			(effects
				(font
					(size 1 1)
					(thickness 0.15)
				)
				(justify mirror)
			)
		)
		(property "Dielectric" ""
			(at 0 0 0)
			(layer "B.Fab")
			(hide yes)
			(effects
				(font
					(size 1 1)
					(thickness 0.15)
				)
				(justify mirror)
			)
		)
		(property "License" "Apache-2.0"
			(at 0 0 0)
			(layer "B.Fab")
			(hide yes)
			(effects
				(font
					(size 1 1)
					(thickness 0.15)
				)
				(justify mirror)
			)
		)
		(property "MPN" "C0603X5R1A474M030BC"
			(at 0 0 0)
			(layer "B.Fab")
			(hide yes)
			(effects
				(font
					(size 1 1)
					(thickness 0.15)
				)
				(justify mirror)
			)
		)
		(property "Manufacturer" "TDK"
			(at 0 0 0)
			(layer "B.Fab")
			(hide yes)
			(effects
				(font
					(size 1 1)
					(thickness 0.15)
				)
				(justify mirror)
			)
		)
		(property "Public" "False"
			(at 0 0 0)
			(layer "B.Fab")
			(hide yes)
			(effects
				(font
					(size 1 1)
					(thickness 0.15)
				)
				(justify mirror)
			)
		)
		(property "Val" "470n"
			(at 0 0 0)
			(layer "B.Fab")
			(hide yes)
			(effects
				(font
					(size 1 1)
					(thickness 0.15)
				)
				(justify mirror)
			)
		)
		(property "Voltage" ""
			(at 0 0 0)
			(layer "B.Fab")
			(hide yes)
			(effects
				(font
					(size 1 1)
					(thickness 0.15)
				)
				(justify mirror)
			)
		)
		(property "DNP" ""
			(at 0 0 0)
			(unlocked yes)
			(layer "B.Fab")
			(hide yes)
			(effects
				(font
					(size 1 1)
					(thickness 0.15)
				)
				(justify mirror)
			)
		)
		(sheetname "/FPGA power supply/")
		(sheetfile "fpga-power-supply.kicad_sch")
		(attr smd)
		(fp_rect
			(start -0.7 0.35)
			(end 0.7 -0.35)
			(stroke
				(width 0.05)
				(type default)
			)
			(fill no)
			(layer "B.CrtYd")
		)
		(fp_rect
			(start 0.3 -0.15)
			(end -0.301 0.149)
			(stroke
				(width 0.15)
				(type solid)
			)
			(fill no)
			(layer "B.Fab")
		)
		(pad "" smd roundrect
			(at -0.349 0.002)
			(size 0.318 0.36)
			(layers "B.Paste")
			(roundrect_rratio 0.25)
		)
		(pad "" smd roundrect
			(at 0.341 0.002)
			(size 0.318 0.36)
			(layers "B.Paste")
			(roundrect_rratio 0.25)
		)
		(pad "1" smd roundrect
			(at -0.321 0.002)
			(size 0.46 0.4)
			(layers "B.Cu" "B.Mask")
			(roundrect_rratio 0.25)
			(net 1 "GND")
			(pintype "passive")
		)
		(pad "2" smd roundrect
			(at 0.32 0.002)
			(size 0.46 0.4)
			(layers "B.Cu" "B.Mask")
			(roundrect_rratio 0.25)
			(net 6 "VCC1V0")
			(pintype "passive")
		)
	)
	(footprint "antmicro-footprints:C_0402_1005Metric"
		(layer "B.Cu")
		(at 98.775 125.275)
		(descr "Capacitor SMD 0402")
		(tags "capacitor SMD 0402")
		(property "Reference" "C167"
			(at -1.375 -0.475 0)
			(layer "B.SilkS")
			(effects
				(font
					(size 0.7 0.7)
					(thickness 0.15)
				)
				(justify right bottom mirror)
			)
		)
		(property "Value" "C_470n_0402"
			(at 0 -1.4 0)
			(layer "B.Fab")
			(effects
				(font
					(size 0.7 0.7)
					(thickness 0.15)
				)
				(justify right bottom mirror)
			)
		)
		(property "Datasheet" "https://product.tdk.com/en/search/capacitor/ceramic/mlcc/info?part_no=C1005X5R1E474M050BB"
			(at 0 0 0)
			(layer "F.Fab")
			(hide yes)
			(effects
				(font
					(size 1.27 1.27)
					(thickness 0.15)
				)
			)
		)
		(property "Description" "SMD Multilayer Ceramic Capacitor, 0.47 µF, 25 V, 0402 [1005 Metric], ± 20%, X5R, C"
			(at 0 0 0)
			(layer "F.Fab")
			(hide yes)
			(effects
				(font
					(size 1.27 1.27)
					(thickness 0.15)
				)
			)
		)
		(property "Author" "Antmicro"
			(at 0 0 0)
			(layer "B.Fab")
			(hide yes)
			(effects
				(font
					(size 1 1)
					(thickness 0.15)
				)
				(justify mirror)
			)
		)
		(property "Dielectric" ""
			(at 0 0 0)
			(layer "B.Fab")
			(hide yes)
			(effects
				(font
					(size 1 1)
					(thickness 0.15)
				)
				(justify mirror)
			)
		)
		(property "License" "Apache-2.0"
			(at 0 0 0)
			(layer "B.Fab")
			(hide yes)
			(effects
				(font
					(size 1 1)
					(thickness 0.15)
				)
				(justify mirror)
			)
		)
		(property "MPN" "C1005X5R1E474M050BB"
			(at 0 0 0)
			(layer "B.Fab")
			(hide yes)
			(effects
				(font
					(size 1 1)
					(thickness 0.15)
				)
				(justify mirror)
			)
		)
		(property "Manufacturer" "TDK"
			(at 0 0 0)
			(layer "B.Fab")
			(hide yes)
			(effects
				(font
					(size 1 1)
					(thickness 0.15)
				)
				(justify mirror)
			)
		)
		(property "Val" "470n"
			(at 0 0 0)
			(layer "B.Fab")
			(hide yes)
			(effects
				(font
					(size 1 1)
					(thickness 0.15)
				)
				(justify mirror)
			)
		)
		(property "Voltage" ""
			(at 0 0 0)
			(layer "B.Fab")
			(hide yes)
			(effects
				(font
					(size 1 1)
					(thickness 0.15)
				)
				(justify mirror)
			)
		)
		(property "DNP" ""
			(at 0 0 0)
			(unlocked yes)
			(layer "B.Fab")
			(hide yes)
			(effects
				(font
					(size 1 1)
					(thickness 0.15)
				)
				(justify mirror)
			)
		)
		(sheetname "/FPGA power supply/")
		(sheetfile "fpga-power-supply.kicad_sch")
		(attr smd)
		(fp_rect
			(start -0.925 0.47)
			(end 0.925 -0.47)
			(stroke
				(width 0.05)
				(type default)
			)
			(fill no)
			(layer "B.CrtYd")
		)
		(fp_line
			(start -0.494 -0.248)
			(end -0.494 0.25)
			(stroke
				(width 0.15)
				(type solid)
			)
			(layer "B.Fab")
		)
		(fp_line
			(start -0.494 0.25)
			(end 0.504 0.25)
			(stroke
				(width 0.15)
				(type solid)
			)
			(layer "B.Fab")
		)
		(fp_line
			(start 0.504 -0.248)
			(end -0.494 -0.248)
			(stroke
				(width 0.15)
				(type solid)
			)
			(layer "B.Fab")
		)
		(fp_line
			(start 0.504 0.25)
			(end 0.504 -0.248)
			(stroke
				(width 0.15)
				(type solid)
			)
			(layer "B.Fab")
		)
		(pad "1" smd roundrect
			(at -0.48 0)
			(size 0.59 0.64)
			(layers "B.Cu" "B.Mask" "B.Paste")
			(roundrect_rratio 0.25)
			(net 1 "GND")
			(pintype "passive")
		)
		(pad "2" smd roundrect
			(at 0.48 0)
			(size 0.59 0.64)
			(layers "B.Cu" "B.Mask" "B.Paste")
			(roundrect_rratio 0.25)
			(net 6 "VCC1V0")
			(pintype "passive")
		)
	)
	(footprint "antmicro-footprints:C_0402_1005Metric"
		(layer "B.Cu")
		(at 104.275 118.675 -90)
		(descr "Capacitor SMD 0402")
		(tags "capacitor SMD 0402")
		(property "Reference" "C141"
			(at -1.575 0.475 90)
			(layer "B.SilkS")
			(effects
				(font
					(size 0.7 0.7)
					(thickness 0.15)
				)
				(justify left bottom mirror)
			)
		)
		(property "Value" "C_470n_0402"
			(at 0 -1.4 90)
			(layer "B.Fab")
			(effects
				(font
					(size 0.7 0.7)
					(thickness 0.15)
				)
				(justify left bottom mirror)
			)
		)
		(property "Datasheet" "https://product.tdk.com/en/search/capacitor/ceramic/mlcc/info?part_no=C1005X5R1E474M050BB"
			(at 0 0 270)
			(layer "F.Fab")
			(hide yes)
			(effects
				(font
					(size 1.27 1.27)
					(thickness 0.15)
				)
			)
		)
		(property "Description" "SMD Multilayer Ceramic Capacitor, 0.47 µF, 25 V, 0402 [1005 Metric], ± 20%, X5R, C"
			(at 0 0 270)
			(layer "F.Fab")
			(hide yes)
			(effects
				(font
					(size 1.27 1.27)
					(thickness 0.15)
				)
			)
		)
		(property "Author" "Antmicro"
			(at -14.4 222.95 0)
			(layer "B.Fab")
			(hide yes)
			(effects
				(font
					(size 1 1)
					(thickness 0.15)
				)
				(justify mirror)
			)
		)
		(property "Dielectric" ""
			(at -14.4 222.95 0)
			(layer "B.Fab")
			(hide yes)
			(effects
				(font
					(size 1 1)
					(thickness 0.15)
				)
				(justify mirror)
			)
		)
		(property "License" "Apache-2.0"
			(at -14.4 222.95 0)
			(layer "B.Fab")
			(hide yes)
			(effects
				(font
					(size 1 1)
					(thickness 0.15)
				)
				(justify mirror)
			)
		)
		(property "MPN" "C1005X5R1E474M050BB"
			(at -14.4 222.95 0)
			(layer "B.Fab")
			(hide yes)
			(effects
				(font
					(size 1 1)
					(thickness 0.15)
				)
				(justify mirror)
			)
		)
		(property "Manufacturer" "TDK"
			(at -14.4 222.95 0)
			(layer "B.Fab")
			(hide yes)
			(effects
				(font
					(size 1 1)
					(thickness 0.15)
				)
				(justify mirror)
			)
		)
		(property "Val" "470n"
			(at -14.4 222.95 0)
			(layer "B.Fab")
			(hide yes)
			(effects
				(font
					(size 1 1)
					(thickness 0.15)
				)
				(justify mirror)
			)
		)
		(property "Voltage" ""
			(at -14.4 222.95 0)
			(layer "B.Fab")
			(hide yes)
			(effects
				(font
					(size 1 1)
					(thickness 0.15)
				)
				(justify mirror)
			)
		)
		(sheetname "/FPGA power supply/")
		(sheetfile "fpga-power-supply.kicad_sch")
		(attr smd)
		(fp_rect
			(start -0.925 0.47)
			(end 0.925 -0.47)
			(stroke
				(width 0.05)
				(type default)
			)
			(fill no)
			(layer "B.CrtYd")
		)
		(fp_line
			(start -0.494 0.25)
			(end 0.504 0.25)
			(stroke
				(width 0.15)
				(type solid)
			)
			(layer "B.Fab")
		)
		(fp_line
			(start 0.504 0.25)
			(end 0.504 -0.248)
			(stroke
				(width 0.15)
				(type solid)
			)
			(layer "B.Fab")
		)
		(fp_line
			(start -0.494 -0.248)
			(end -0.494 0.25)
			(stroke
				(width 0.15)
				(type solid)
			)
			(layer "B.Fab")
		)
		(fp_line
			(start 0.504 -0.248)
			(end -0.494 -0.248)
			(stroke
				(width 0.15)
				(type solid)
			)
			(layer "B.Fab")
		)
		(pad "1" smd roundrect
			(at -0.48 0 270)
			(size 0.59 0.64)
			(layers "B.Cu" "B.Mask" "B.Paste")
			(roundrect_rratio 0.25)
			(net 1 "GND")
			(pintype "passive")
		)
		(pad "2" smd roundrect
			(at 0.48 0 270)
			(size 0.59 0.64)
			(layers "B.Cu" "B.Mask" "B.Paste")
			(roundrect_rratio 0.25)
			(net 5 "VCC1V8")
			(pintype "passive")
		)
	)
	(footprint "antmicro-footprints:C_0402_1005Metric"
		(layer "B.Cu")
		(at 98.275 118.475 -90)
		(descr "Capacitor SMD 0402")
		(tags "capacitor SMD 0402")
		(property "Reference" "C143"
			(at -1.575 0.475 90)
			(layer "B.SilkS")
			(effects
				(font
					(size 0.7 0.7)
					(thickness 0.15)
				)
				(justify left bottom mirror)
			)
		)
		(property "Value" "C_470n_0402"
			(at 0 -1.4 90)
			(layer "B.Fab")
			(effects
				(font
					(size 0.7 0.7)
					(thickness 0.15)
				)
				(justify left bottom mirror)
			)
		)
		(property "Datasheet" "https://product.tdk.com/en/search/capacitor/ceramic/mlcc/info?part_no=C1005X5R1E474M050BB"
			(at 0 0 270)
			(layer "F.Fab")
			(hide yes)
			(effects
				(font
					(size 1.27 1.27)
					(thickness 0.15)
				)
			)
		)
		(property "Description" "SMD Multilayer Ceramic Capacitor, 0.47 µF, 25 V, 0402 [1005 Metric], ± 20%, X5R, C"
			(at 0 0 270)
			(layer "F.Fab")
			(hide yes)
			(effects
				(font
					(size 1.27 1.27)
					(thickness 0.15)
				)
			)
		)
		(property "Author" "Antmicro"
			(at -20.2 216.75 0)
			(layer "B.Fab")
			(hide yes)
			(effects
				(font
					(size 1 1)
					(thickness 0.15)
				)
				(justify mirror)
			)
		)
		(property "Dielectric" ""
			(at -20.2 216.75 0)
			(layer "B.Fab")
			(hide yes)
			(effects
				(font
					(size 1 1)
					(thickness 0.15)
				)
				(justify mirror)
			)
		)
		(property "License" "Apache-2.0"
			(at -20.2 216.75 0)
			(layer "B.Fab")
			(hide yes)
			(effects
				(font
					(size 1 1)
					(thickness 0.15)
				)
				(justify mirror)
			)
		)
		(property "MPN" "C1005X5R1E474M050BB"
			(at -20.2 216.75 0)
			(layer "B.Fab")
			(hide yes)
			(effects
				(font
					(size 1 1)
					(thickness 0.15)
				)
				(justify mirror)
			)
		)
		(property "Manufacturer" "TDK"
			(at -20.2 216.75 0)
			(layer "B.Fab")
			(hide yes)
			(effects
				(font
					(size 1 1)
					(thickness 0.15)
				)
				(justify mirror)
			)
		)
		(property "Val" "470n"
			(at -20.2 216.75 0)
			(layer "B.Fab")
			(hide yes)
			(effects
				(font
					(size 1 1)
					(thickness 0.15)
				)
				(justify mirror)
			)
		)
		(property "Voltage" ""
			(at -20.2 216.75 0)
			(layer "B.Fab")
			(hide yes)
			(effects
				(font
					(size 1 1)
					(thickness 0.15)
				)
				(justify mirror)
			)
		)
		(sheetname "/FPGA power supply/")
		(sheetfile "fpga-power-supply.kicad_sch")
		(attr smd)
		(fp_rect
			(start -0.925 0.47)
			(end 0.925 -0.47)
			(stroke
				(width 0.05)
				(type default)
			)
			(fill no)
			(layer "B.CrtYd")
		)
		(fp_line
			(start -0.494 0.25)
			(end 0.504 0.25)
			(stroke
				(width 0.15)
				(type solid)
			)
			(layer "B.Fab")
		)
		(fp_line
			(start 0.504 0.25)
			(end 0.504 -0.248)
			(stroke
				(width 0.15)
				(type solid)
			)
			(layer "B.Fab")
		)
		(fp_line
			(start -0.494 -0.248)
			(end -0.494 0.25)
			(stroke
				(width 0.15)
				(type solid)
			)
			(layer "B.Fab")
		)
		(fp_line
			(start 0.504 -0.248)
			(end -0.494 -0.248)
			(stroke
				(width 0.15)
				(type solid)
			)
			(layer "B.Fab")
		)
		(pad "1" smd roundrect
			(at -0.48 0 270)
			(size 0.59 0.64)
			(layers "B.Cu" "B.Mask" "B.Paste")
			(roundrect_rratio 0.25)
			(net 1 "GND")
			(pintype "passive")
		)
		(pad "2" smd roundrect
			(at 0.48 0 270)
			(size 0.59 0.64)
			(layers "B.Cu" "B.Mask" "B.Paste")
			(roundrect_rratio 0.25)
			(net 5 "VCC1V8")
			(pintype "passive")
		)
	)
	(footprint "antmicro-footprints:R_0402_1005Metric"
		(layer "B.Cu")
		(at 91.975 160.875 180)
		(descr "Resistor SMD 0402")
		(tags "resistor SMD 0402")
		(property "Reference" "R115"
			(at 0.775 -0.325 0)
			(layer "B.SilkS")
			(effects
				(font
					(size 0.7 0.7)
					(thickness 0.15)
				)
				(justify left bottom mirror)
			)
		)
		(property "Value" "R_0R_0402"
			(at 0 -1.4 0)
			(layer "B.Fab")
			(effects
				(font
					(size 0.7 0.7)
					(thickness 0.15)
				)
				(justify left bottom mirror)
			)
		)
		(property "Datasheet" "https://industrial.panasonic.com/cdbs/www-data/pdf/RDA0000/AOA0000C301.pdf"
			(at 0 0 180)
			(layer "F.Fab")
			(hide yes)
			(effects
				(font
					(size 1.27 1.27)
					(thickness 0.15)
				)
			)
		)
		(property "Description" "SMD Chip Resistor, Jumper, 0 ohm, 100 mW, 0402 [1005 Metric], Thick Film, General Purpose"
			(at 0 0 180)
			(layer "F.Fab")
			(hide yes)
			(effects
				(font
					(size 1.27 1.27)
					(thickness 0.15)
				)
			)
		)
		(property "Author" "Antmicro"
			(at 183.95 321.75 0)
			(layer "B.Fab")
			(hide yes)
			(effects
				(font
					(size 1 1)
					(thickness 0.15)
				)
				(justify mirror)
			)
		)
		(property "Current" "1A"
			(at 183.95 321.75 0)
			(layer "B.Fab")
			(hide yes)
			(effects
				(font
					(size 1 1)
					(thickness 0.15)
				)
				(justify mirror)
			)
		)
		(property "License" "Apache-2.0"
			(at 183.95 321.75 0)
			(layer "B.Fab")
			(hide yes)
			(effects
				(font
					(size 1 1)
					(thickness 0.15)
				)
				(justify mirror)
			)
		)
		(property "MPN" "ERJ2GE0R00X"
			(at 183.95 321.75 0)
			(layer "B.Fab")
			(hide yes)
			(effects
				(font
					(size 1 1)
					(thickness 0.15)
				)
				(justify mirror)
			)
		)
		(property "Manufacturer" "Panasonic"
			(at 183.95 321.75 0)
			(layer "B.Fab")
			(hide yes)
			(effects
				(font
					(size 1 1)
					(thickness 0.15)
				)
				(justify mirror)
			)
		)
		(property "Tolerance" "~"
			(at 183.95 321.75 0)
			(layer "B.Fab")
			(hide yes)
			(effects
				(font
					(size 1 1)
					(thickness 0.15)
				)
				(justify mirror)
			)
		)
		(property "Val" "0R"
			(at 183.95 321.75 0)
			(layer "B.Fab")
			(hide yes)
			(effects
				(font
					(size 1 1)
					(thickness 0.15)
				)
				(justify mirror)
			)
		)
		(sheetname "/Edge connector/")
		(sheetfile "edge-connector.kicad_sch")
		(attr smd)
		(fp_rect
			(start -0.925 0.47)
			(end 0.925 -0.47)
			(stroke
				(width 0.05)
				(type default)
			)
			(fill no)
			(layer "B.CrtYd")
		)
		(fp_rect
			(start -0.5 0.25)
			(end 0.5 -0.25)
			(stroke
				(width 0.15)
				(type solid)
			)
			(fill no)
			(layer "B.Fab")
		)
		(pad "1" smd roundrect
			(at -0.48 0 180)
			(size 0.59 0.64)
			(layers "B.Cu" "B.Mask" "B.Paste")
			(roundrect_rratio 0.25)
			(net 522 "VIRTUAL_RESEAT_R")
			(pintype "passive")
		)
		(pad "2" smd roundrect
			(at 0.48 0 180)
			(size 0.59 0.64)
			(layers "B.Cu" "B.Mask" "B.Paste")
			(roundrect_rratio 0.25)
			(net 244 "/Edge connector/VIRTUAL_RESEAT")
			(pintype "passive")
		)
	)
	(footprint "antmicro-footprints:R_0402_1005Metric"
		(layer "B.Cu")
		(at 95.25 91.055 -90)
		(descr "Resistor SMD 0402")
		(tags "resistor SMD 0402")
		(property "Reference" "R166"
			(at -3.965 0.565 90)
			(layer "B.SilkS")
			(effects
				(font
					(size 0.7 0.7)
					(thickness 0.15)
				)
				(justify left bottom mirror)
			)
		)
		(property "Value" "R_220R_0402"
			(at 0 -1.4 90)
			(layer "B.Fab")
			(effects
				(font
					(size 0.7 0.7)
					(thickness 0.15)
				)
				(justify left bottom mirror)
			)
		)
		(property "Datasheet" "https://www.bourns.com/docs/product-datasheets/cr.pdf"
			(at 0 0 270)
			(layer "F.Fab")
			(hide yes)
			(effects
				(font
					(size 1.27 1.27)
					(thickness 0.15)
				)
			)
		)
		(property "Description" "SMD Chip Resistor, 220 ohm, ± 1%, 62.5 mW, 0402 [1005 Metric], Thick Film, General Purpose"
			(at 0 0 270)
			(layer "F.Fab")
			(hide yes)
			(effects
				(font
					(size 1.27 1.27)
					(thickness 0.15)
				)
			)
		)
		(property "Author" "Antmicro"
			(at 4.195 186.305 0)
			(layer "B.Fab")
			(hide yes)
			(effects
				(font
					(size 1 1)
					(thickness 0.15)
				)
				(justify mirror)
			)
		)
		(property "License" "Apache-2.0"
			(at 4.195 186.305 0)
			(layer "B.Fab")
			(hide yes)
			(effects
				(font
					(size 1 1)
					(thickness 0.15)
				)
				(justify mirror)
			)
		)
		(property "MPN" "CR0402-FX-2200GLF"
			(at 4.195 186.305 0)
			(layer "B.Fab")
			(hide yes)
			(effects
				(font
					(size 1 1)
					(thickness 0.15)
				)
				(justify mirror)
			)
		)
		(property "Manufacturer" "Bourns"
			(at 4.195 186.305 0)
			(layer "B.Fab")
			(hide yes)
			(effects
				(font
					(size 1 1)
					(thickness 0.15)
				)
				(justify mirror)
			)
		)
		(property "Tolerance" "1%"
			(at 4.195 186.305 0)
			(layer "B.Fab")
			(hide yes)
			(effects
				(font
					(size 1 1)
					(thickness 0.15)
				)
				(justify mirror)
			)
		)
		(property "Val" "220R"
			(at 4.195 186.305 0)
			(layer "B.Fab")
			(hide yes)
			(effects
				(font
					(size 1 1)
					(thickness 0.15)
				)
				(justify mirror)
			)
		)
		(sheetname "/Ethernet/")
		(sheetfile "ethernet.kicad_sch")
		(attr smd)
		(fp_rect
			(start -0.925 0.47)
			(end 0.925 -0.47)
			(stroke
				(width 0.05)
				(type default)
			)
			(fill no)
			(layer "B.CrtYd")
		)
		(fp_rect
			(start -0.5 0.25)
			(end 0.5 -0.25)
			(stroke
				(width 0.15)
				(type solid)
			)
			(fill no)
			(layer "B.Fab")
		)
		(pad "1" smd roundrect
			(at -0.48 0 270)
			(size 0.59 0.64)
			(layers "B.Cu" "B.Mask" "B.Paste")
			(roundrect_rratio 0.25)
			(net 574 "Net-(J1-Pad15)")
			(pintype "passive")
		)
		(pad "2" smd roundrect
			(at 0.48 0 270)
			(size 0.59 0.64)
			(layers "B.Cu" "B.Mask" "B.Paste")
			(roundrect_rratio 0.25)
			(net 416 "/Ethernet/ETH_LED2")
			(pintype "passive")
		)
	)
	(footprint "antmicro-footprints:R_0402_1005Metric"
		(layer "B.Cu")
		(at 76.675 158.475 90)
		(descr "Resistor SMD 0402")
		(tags "resistor SMD 0402")
		(property "Reference" "R134"
			(at -3.625 0.425 90)
			(layer "B.SilkS")
			(effects
				(font
					(size 0.7 0.7)
					(thickness 0.15)
				)
				(justify right bottom mirror)
			)
		)
		(property "Value" "R_4k7_0402"
			(at 0 -1.4 90)
			(layer "B.Fab")
			(effects
				(font
					(size 0.7 0.7)
					(thickness 0.15)
				)
				(justify right bottom mirror)
			)
		)
		(property "Datasheet" "https://www.bourns.com/docs/product-datasheets/cr.pdf"
			(at 0 0 90)
			(layer "F.Fab")
			(hide yes)
			(effects
				(font
					(size 1.27 1.27)
					(thickness 0.15)
				)
			)
		)
		(property "Description" "SMD Chip Resistor, 4.7 kohm, ± 1%, 62.5 mW, 0402 [1005 Metric], Thick Film, General Purpose"
			(at 0 0 90)
			(layer "F.Fab")
			(hide yes)
			(effects
				(font
					(size 1.27 1.27)
					(thickness 0.15)
				)
			)
		)
		(property "Author" "Antmicro"
			(at 235.15 81.8 0)
			(layer "B.Fab")
			(hide yes)
			(effects
				(font
					(size 1 1)
					(thickness 0.15)
				)
				(justify mirror)
			)
		)
		(property "License" "Apache-2.0"
			(at 235.15 81.8 0)
			(layer "B.Fab")
			(hide yes)
			(effects
				(font
					(size 1 1)
					(thickness 0.15)
				)
				(justify mirror)
			)
		)
		(property "MPN" "CR0402-FX-4701GLF"
			(at 235.15 81.8 0)
			(layer "B.Fab")
			(hide yes)
			(effects
				(font
					(size 1 1)
					(thickness 0.15)
				)
				(justify mirror)
			)
		)
		(property "Manufacturer" "Bourns"
			(at 235.15 81.8 0)
			(layer "B.Fab")
			(hide yes)
			(effects
				(font
					(size 1 1)
					(thickness 0.15)
				)
				(justify mirror)
			)
		)
		(property "Tolerance" "1%"
			(at 235.15 81.8 0)
			(layer "B.Fab")
			(hide yes)
			(effects
				(font
					(size 1 1)
					(thickness 0.15)
				)
				(justify mirror)
			)
		)
		(property "Val" "4k7"
			(at 235.15 81.8 0)
			(layer "B.Fab")
			(hide yes)
			(effects
				(font
					(size 1 1)
					(thickness 0.15)
				)
				(justify mirror)
			)
		)
		(sheetname "/FPGA banks 13-16/")
		(sheetfile "fpga-banks-13-16.kicad_sch")
		(attr smd)
		(fp_rect
			(start -0.925 0.47)
			(end 0.925 -0.47)
			(stroke
				(width 0.05)
				(type default)
			)
			(fill no)
			(layer "B.CrtYd")
		)
		(fp_rect
			(start -0.5 0.25)
			(end 0.5 -0.25)
			(stroke
				(width 0.15)
				(type solid)
			)
			(fill no)
			(layer "B.Fab")
		)
		(pad "1" smd roundrect
			(at -0.48 0 90)
			(size 0.59 0.64)
			(layers "B.Cu" "B.Mask" "B.Paste")
			(roundrect_rratio 0.25)
			(net 2 "VCC3V3")
			(pintype "passive")
		)
		(pad "2" smd roundrect
			(at 0.48 0 90)
			(size 0.59 0.64)
			(layers "B.Cu" "B.Mask" "B.Paste")
			(roundrect_rratio 0.25)
			(net 332 "ROT_QSPI_DQ2")
			(pintype "passive")
		)
	)
	(footprint "antmicro-footprints:C_0402_1005Metric"
		(layer "B.Cu")
		(at 93.775 124.375)
		(descr "Capacitor SMD 0402")
		(tags "capacitor SMD 0402")
		(property "Reference" "C134"
			(at -1.375 1.325 0)
			(layer "B.SilkS")
			(effects
				(font
					(size 0.7 0.7)
					(thickness 0.15)
				)
				(justify right bottom mirror)
			)
		)
		(property "Value" "C_100n_6V3_0402"
			(at 0 -1.4 0)
			(layer "B.Fab")
			(effects
				(font
					(size 0.7 0.7)
					(thickness 0.15)
				)
				(justify right bottom mirror)
			)
		)
		(property "Datasheet" "https://www.passivecomponent.com/wp-content/uploads/datasheet/WTC_MLCC_General_Purpose.pdf"
			(at 0 0 0)
			(layer "F.Fab")
			(hide yes)
			(effects
				(font
					(size 1.27 1.27)
					(thickness 0.15)
				)
			)
		)
		(property "Description" "SMT Multilayer Ceramic Capacitor, 0.1 µF, 6.3 V, 0402 [1005 Metric], ± 10%, X5R, Walsin MLCC"
			(at 0 0 0)
			(layer "F.Fab")
			(hide yes)
			(effects
				(font
					(size 1.27 1.27)
					(thickness 0.15)
				)
			)
		)
		(property "Author" "Antmicro"
			(at 0 0 0)
			(layer "B.Fab")
			(hide yes)
			(effects
				(font
					(size 1 1)
					(thickness 0.15)
				)
				(justify mirror)
			)
		)
		(property "Dielectric" ""
			(at 0 0 0)
			(layer "B.Fab")
			(hide yes)
			(effects
				(font
					(size 1 1)
					(thickness 0.15)
				)
				(justify mirror)
			)
		)
		(property "License" "Apache-2.0"
			(at 0 0 0)
			(layer "B.Fab")
			(hide yes)
			(effects
				(font
					(size 1 1)
					(thickness 0.15)
				)
				(justify mirror)
			)
		)
		(property "MPN" "0402X104K6R3CT"
			(at 0 0 0)
			(layer "B.Fab")
			(hide yes)
			(effects
				(font
					(size 1 1)
					(thickness 0.15)
				)
				(justify mirror)
			)
		)
		(property "Manufacturer" "Walsin"
			(at 0 0 0)
			(layer "B.Fab")
			(hide yes)
			(effects
				(font
					(size 1 1)
					(thickness 0.15)
				)
				(justify mirror)
			)
		)
		(property "Public" "False"
			(at 0 0 0)
			(layer "B.Fab")
			(hide yes)
			(effects
				(font
					(size 1 1)
					(thickness 0.15)
				)
				(justify mirror)
			)
		)
		(property "Val" "100n"
			(at 0 0 0)
			(layer "B.Fab")
			(hide yes)
			(effects
				(font
					(size 1 1)
					(thickness 0.15)
				)
				(justify mirror)
			)
		)
		(property "Voltage" ""
			(at 0 0 0)
			(layer "B.Fab")
			(hide yes)
			(effects
				(font
					(size 1 1)
					(thickness 0.15)
				)
				(justify mirror)
			)
		)
		(sheetname "/Interfaces/")
		(sheetfile "interfaces.kicad_sch")
		(attr smd)
		(fp_rect
			(start -0.925 0.47)
			(end 0.925 -0.47)
			(stroke
				(width 0.05)
				(type default)
			)
			(fill no)
			(layer "B.CrtYd")
		)
		(fp_line
			(start -0.494 -0.248)
			(end -0.494 0.25)
			(stroke
				(width 0.15)
				(type solid)
			)
			(layer "B.Fab")
		)
		(fp_line
			(start -0.494 0.25)
			(end 0.504 0.25)
			(stroke
				(width 0.15)
				(type solid)
			)
			(layer "B.Fab")
		)
		(fp_line
			(start 0.504 -0.248)
			(end -0.494 -0.248)
			(stroke
				(width 0.15)
				(type solid)
			)
			(layer "B.Fab")
		)
		(fp_line
			(start 0.504 0.25)
			(end 0.504 -0.248)
			(stroke
				(width 0.15)
				(type solid)
			)
			(layer "B.Fab")
		)
		(pad "1" smd roundrect
			(at -0.48 0)
			(size 0.59 0.64)
			(layers "B.Cu" "B.Mask" "B.Paste")
			(roundrect_rratio 0.25)
			(net 1 "GND")
			(pintype "passive")
		)
		(pad "2" smd roundrect
			(at 0.48 0)
			(size 0.59 0.64)
			(layers "B.Cu" "B.Mask" "B.Paste")
			(roundrect_rratio 0.25)
			(net 6 "VCC1V0")
			(pintype "passive")
		)
	)
	(footprint "antmicro-footprints:C_0402_1005Metric"
		(layer "B.Cu")
		(at 93.775 126.375)
		(descr "Capacitor SMD 0402")
		(tags "capacitor SMD 0402")
		(property "Reference" "C136"
			(at -3.675 0.325 0)
			(layer "B.SilkS")
			(effects
				(font
					(size 0.7 0.7)
					(thickness 0.15)
				)
				(justify right bottom mirror)
			)
		)
		(property "Value" "C_100n_6V3_0402"
			(at 0 -1.4 0)
			(layer "B.Fab")
			(effects
				(font
					(size 0.7 0.7)
					(thickness 0.15)
				)
				(justify right bottom mirror)
			)
		)
		(property "Datasheet" "https://www.passivecomponent.com/wp-content/uploads/datasheet/WTC_MLCC_General_Purpose.pdf"
			(at 0 0 0)
			(layer "F.Fab")
			(hide yes)
			(effects
				(font
					(size 1.27 1.27)
					(thickness 0.15)
				)
			)
		)
		(property "Description" "SMT Multilayer Ceramic Capacitor, 0.1 µF, 6.3 V, 0402 [1005 Metric], ± 10%, X5R, Walsin MLCC"
			(at 0 0 0)
			(layer "F.Fab")
			(hide yes)
			(effects
				(font
					(size 1.27 1.27)
					(thickness 0.15)
				)
			)
		)
		(property "Author" "Antmicro"
			(at 0 0 0)
			(layer "B.Fab")
			(hide yes)
			(effects
				(font
					(size 1 1)
					(thickness 0.15)
				)
				(justify mirror)
			)
		)
		(property "Dielectric" ""
			(at 0 0 0)
			(layer "B.Fab")
			(hide yes)
			(effects
				(font
					(size 1 1)
					(thickness 0.15)
				)
				(justify mirror)
			)
		)
		(property "License" "Apache-2.0"
			(at 0 0 0)
			(layer "B.Fab")
			(hide yes)
			(effects
				(font
					(size 1 1)
					(thickness 0.15)
				)
				(justify mirror)
			)
		)
		(property "MPN" "0402X104K6R3CT"
			(at 0 0 0)
			(layer "B.Fab")
			(hide yes)
			(effects
				(font
					(size 1 1)
					(thickness 0.15)
				)
				(justify mirror)
			)
		)
		(property "Manufacturer" "Walsin"
			(at 0 0 0)
			(layer "B.Fab")
			(hide yes)
			(effects
				(font
					(size 1 1)
					(thickness 0.15)
				)
				(justify mirror)
			)
		)
		(property "Public" "False"
			(at 0 0 0)
			(layer "B.Fab")
			(hide yes)
			(effects
				(font
					(size 1 1)
					(thickness 0.15)
				)
				(justify mirror)
			)
		)
		(property "Val" "100n"
			(at 0 0 0)
			(layer "B.Fab")
			(hide yes)
			(effects
				(font
					(size 1 1)
					(thickness 0.15)
				)
				(justify mirror)
			)
		)
		(property "Voltage" ""
			(at 0 0 0)
			(layer "B.Fab")
			(hide yes)
			(effects
				(font
					(size 1 1)
					(thickness 0.15)
				)
				(justify mirror)
			)
		)
		(sheetname "/Interfaces/")
		(sheetfile "interfaces.kicad_sch")
		(attr smd)
		(fp_rect
			(start -0.925 0.47)
			(end 0.925 -0.47)
			(stroke
				(width 0.05)
				(type default)
			)
			(fill no)
			(layer "B.CrtYd")
		)
		(fp_line
			(start -0.494 -0.248)
			(end -0.494 0.25)
			(stroke
				(width 0.15)
				(type solid)
			)
			(layer "B.Fab")
		)
		(fp_line
			(start -0.494 0.25)
			(end 0.504 0.25)
			(stroke
				(width 0.15)
				(type solid)
			)
			(layer "B.Fab")
		)
		(fp_line
			(start 0.504 -0.248)
			(end -0.494 -0.248)
			(stroke
				(width 0.15)
				(type solid)
			)
			(layer "B.Fab")
		)
		(fp_line
			(start 0.504 0.25)
			(end 0.504 -0.248)
			(stroke
				(width 0.15)
				(type solid)
			)
			(layer "B.Fab")
		)
		(pad "1" smd roundrect
			(at -0.48 0)
			(size 0.59 0.64)
			(layers "B.Cu" "B.Mask" "B.Paste")
			(roundrect_rratio 0.25)
			(net 1 "GND")
			(pintype "passive")
		)
		(pad "2" smd roundrect
			(at 0.48 0)
			(size 0.59 0.64)
			(layers "B.Cu" "B.Mask" "B.Paste")
			(roundrect_rratio 0.25)
			(net 6 "VCC1V0")
			(pintype "passive")
		)
	)
	(footprint "antmicro-footprints:C_0603_1608Metric"
		(layer "B.Cu")
		(at 93.575 120.675)
		(descr "Capacitor SMD 0603")
		(tags "capacitor 0603")
		(property "Reference" "C190"
			(at -1.575 -2.275 0)
			(layer "B.SilkS")
			(effects
				(font
					(size 0.7 0.7)
					(thickness 0.15)
				)
				(justify right bottom mirror)
			)
		)
		(property "Value" "C_4u7_0603"
			(at 0 -1.6 0)
			(layer "B.Fab")
			(effects
				(font
					(size 0.7 0.7)
					(thickness 0.15)
				)
				(justify right bottom mirror)
			)
		)
		(property "Datasheet" "https://product.tdk.com/en/search/capacitor/ceramic/mlcc/info?part_no=C1608X5R1V475M080AC"
			(at 0 0 0)
			(layer "F.Fab")
			(hide yes)
			(effects
				(font
					(size 1.27 1.27)
					(thickness 0.15)
				)
			)
		)
		(property "Description" "SMD Multilayer Ceramic Capacitor, 4.7 µF, 35 V, 0603 [1608 Metric], ± 20%, X5R, C"
			(at 0 0 0)
			(layer "F.Fab")
			(hide yes)
			(effects
				(font
					(size 1.27 1.27)
					(thickness 0.15)
				)
			)
		)
		(property "Author" "Antmicro"
			(at 0 0 0)
			(layer "B.Fab")
			(hide yes)
			(effects
				(font
					(size 1 1)
					(thickness 0.15)
				)
				(justify mirror)
			)
		)
		(property "Dielectric" ""
			(at 0 0 0)
			(layer "B.Fab")
			(hide yes)
			(effects
				(font
					(size 1 1)
					(thickness 0.15)
				)
				(justify mirror)
			)
		)
		(property "License" "Apache-2.0"
			(at 0 0 0)
			(layer "B.Fab")
			(hide yes)
			(effects
				(font
					(size 1 1)
					(thickness 0.15)
				)
				(justify mirror)
			)
		)
		(property "MPN" "C1608X5R1V475M080AC"
			(at 0 0 0)
			(layer "B.Fab")
			(hide yes)
			(effects
				(font
					(size 1 1)
					(thickness 0.15)
				)
				(justify mirror)
			)
		)
		(property "Manufacturer" "TDK"
			(at 0 0 0)
			(layer "B.Fab")
			(hide yes)
			(effects
				(font
					(size 1 1)
					(thickness 0.15)
				)
				(justify mirror)
			)
		)
		(property "Val" "4u7"
			(at 0 0 0)
			(layer "B.Fab")
			(hide yes)
			(effects
				(font
					(size 1 1)
					(thickness 0.15)
				)
				(justify mirror)
			)
		)
		(property "Voltage" ""
			(at 0 0 0)
			(layer "B.Fab")
			(hide yes)
			(effects
				(font
					(size 1 1)
					(thickness 0.15)
				)
				(justify mirror)
			)
		)
		(sheetname "/Interfaces/")
		(sheetfile "interfaces.kicad_sch")
		(attr smd)
		(fp_line
			(start -0.15 -0.4)
			(end 0.15 -0.4)
			(stroke
				(width 0.15)
				(type solid)
			)
			(layer "B.SilkS")
		)
		(fp_line
			(start -0.15 0.4)
			(end 0.15 0.4)
			(stroke
				(width 0.15)
				(type solid)
			)
			(layer "B.SilkS")
		)
		(fp_rect
			(start -1.25 0.65)
			(end 1.25 -0.65)
			(stroke
				(width 0.05)
				(type solid)
			)
			(fill no)
			(layer "B.CrtYd")
		)
		(fp_rect
			(start -0.8 0.4)
			(end 0.8 -0.4)
			(stroke
				(width 0.15)
				(type solid)
			)
			(fill no)
			(layer "B.Fab")
		)
		(pad "1" smd roundrect
			(at -0.7 0)
			(size 0.8 1)
			(layers "B.Cu" "B.Mask" "B.Paste")
			(roundrect_rratio 0.2)
			(net 1 "GND")
			(pintype "passive")
		)
		(pad "2" smd roundrect
			(at 0.7 0)
			(size 0.8 1)
			(layers "B.Cu" "B.Mask" "B.Paste")
			(roundrect_rratio 0.2)
			(net 6 "VCC1V0")
			(pintype "passive")
		)
	)
	(footprint "antmicro-footprints:C_0603_1608Metric"
		(layer "B.Cu")
		(at 115.8 126.4 -90)
		(descr "Capacitor SMD 0603")
		(tags "capacitor 0603")
		(property "Reference" "C191"
			(at -1.4 0.6 90)
			(layer "B.SilkS")
			(effects
				(font
					(size 0.7 0.7)
					(thickness 0.15)
				)
				(justify left bottom mirror)
			)
		)
		(property "Value" "C_4u7_0603"
			(at 0 -1.6 90)
			(layer "B.Fab")
			(effects
				(font
					(size 0.7 0.7)
					(thickness 0.15)
				)
				(justify left bottom mirror)
			)
		)
		(property "Datasheet" "https://product.tdk.com/en/search/capacitor/ceramic/mlcc/info?part_no=C1608X5R1V475M080AC"
			(at 0 0 270)
			(layer "F.Fab")
			(hide yes)
			(effects
				(font
					(size 1.27 1.27)
					(thickness 0.15)
				)
			)
		)
		(property "Description" "SMD Multilayer Ceramic Capacitor, 4.7 µF, 35 V, 0603 [1608 Metric], ± 20%, X5R, C"
			(at 0 0 270)
			(layer "F.Fab")
			(hide yes)
			(effects
				(font
					(size 1.27 1.27)
					(thickness 0.15)
				)
			)
		)
		(property "Author" "Antmicro"
			(at -10.6 242.2 0)
			(layer "B.Fab")
			(hide yes)
			(effects
				(font
					(size 1 1)
					(thickness 0.15)
				)
				(justify mirror)
			)
		)
		(property "Dielectric" ""
			(at -10.6 242.2 0)
			(layer "B.Fab")
			(hide yes)
			(effects
				(font
					(size 1 1)
					(thickness 0.15)
				)
				(justify mirror)
			)
		)
		(property "License" "Apache-2.0"
			(at -10.6 242.2 0)
			(layer "B.Fab")
			(hide yes)
			(effects
				(font
					(size 1 1)
					(thickness 0.15)
				)
				(justify mirror)
			)
		)
		(property "MPN" "C1608X5R1V475M080AC"
			(at -10.6 242.2 0)
			(layer "B.Fab")
			(hide yes)
			(effects
				(font
					(size 1 1)
					(thickness 0.15)
				)
				(justify mirror)
			)
		)
		(property "Manufacturer" "TDK"
			(at -10.6 242.2 0)
			(layer "B.Fab")
			(hide yes)
			(effects
				(font
					(size 1 1)
					(thickness 0.15)
				)
				(justify mirror)
			)
		)
		(property "Val" "4u7"
			(at -10.6 242.2 0)
			(layer "B.Fab")
			(hide yes)
			(effects
				(font
					(size 1 1)
					(thickness 0.15)
				)
				(justify mirror)
			)
		)
		(property "Voltage" ""
			(at -10.6 242.2 0)
			(layer "B.Fab")
			(hide yes)
			(effects
				(font
					(size 1 1)
					(thickness 0.15)
				)
				(justify mirror)
			)
		)
		(sheetname "/Interfaces/")
		(sheetfile "interfaces.kicad_sch")
		(attr smd)
		(fp_line
			(start -0.15 0.4)
			(end 0.15 0.4)
			(stroke
				(width 0.15)
				(type solid)
			)
			(layer "B.SilkS")
		)
		(fp_line
			(start -0.15 -0.4)
			(end 0.15 -0.4)
			(stroke
				(width 0.15)
				(type solid)
			)
			(layer "B.SilkS")
		)
		(fp_rect
			(start -1.25 0.65)
			(end 1.25 -0.65)
			(stroke
				(width 0.05)
				(type solid)
			)
			(fill no)
			(layer "B.CrtYd")
		)
		(fp_rect
			(start -0.8 0.4)
			(end 0.8 -0.4)
			(stroke
				(width 0.15)
				(type solid)
			)
			(fill no)
			(layer "B.Fab")
		)
		(pad "1" smd roundrect
			(at -0.7 0 270)
			(size 0.8 1)
			(layers "B.Cu" "B.Mask" "B.Paste")
			(roundrect_rratio 0.2)
			(net 1 "GND")
			(pintype "passive")
		)
		(pad "2" smd roundrect
			(at 0.7 0 270)
			(size 0.8 1)
			(layers "B.Cu" "B.Mask" "B.Paste")
			(roundrect_rratio 0.2)
			(net 339 "VCC1V2")
			(pintype "passive")
		)
	)
	(footprint "antmicro-footprints:C_0402_1005Metric"
		(layer "B.Cu")
		(at 91.175 121.675)
		(descr "Capacitor SMD 0402")
		(tags "capacitor SMD 0402")
		(property "Reference" "C192"
			(at -3.675 0.325 0)
			(layer "B.SilkS")
			(effects
				(font
					(size 0.7 0.7)
					(thickness 0.15)
				)
				(justify right bottom mirror)
			)
		)
		(property "Value" "C_100n_6V3_0402"
			(at 0 -1.4 0)
			(layer "B.Fab")
			(effects
				(font
					(size 0.7 0.7)
					(thickness 0.15)
				)
				(justify right bottom mirror)
			)
		)
		(property "Datasheet" "https://www.passivecomponent.com/wp-content/uploads/datasheet/WTC_MLCC_General_Purpose.pdf"
			(at 0 0 0)
			(layer "F.Fab")
			(hide yes)
			(effects
				(font
					(size 1.27 1.27)
					(thickness 0.15)
				)
			)
		)
		(property "Description" "SMT Multilayer Ceramic Capacitor, 0.1 µF, 6.3 V, 0402 [1005 Metric], ± 10%, X5R, Walsin MLCC"
			(at 0 0 0)
			(layer "F.Fab")
			(hide yes)
			(effects
				(font
					(size 1.27 1.27)
					(thickness 0.15)
				)
			)
		)
		(property "Author" "Antmicro"
			(at 0 0 0)
			(layer "B.Fab")
			(hide yes)
			(effects
				(font
					(size 1 1)
					(thickness 0.15)
				)
				(justify mirror)
			)
		)
		(property "Dielectric" ""
			(at 0 0 0)
			(layer "B.Fab")
			(hide yes)
			(effects
				(font
					(size 1 1)
					(thickness 0.15)
				)
				(justify mirror)
			)
		)
		(property "License" "Apache-2.0"
			(at 0 0 0)
			(layer "B.Fab")
			(hide yes)
			(effects
				(font
					(size 1 1)
					(thickness 0.15)
				)
				(justify mirror)
			)
		)
		(property "MPN" "0402X104K6R3CT"
			(at 0 0 0)
			(layer "B.Fab")
			(hide yes)
			(effects
				(font
					(size 1 1)
					(thickness 0.15)
				)
				(justify mirror)
			)
		)
		(property "Manufacturer" "Walsin"
			(at 0 0 0)
			(layer "B.Fab")
			(hide yes)
			(effects
				(font
					(size 1 1)
					(thickness 0.15)
				)
				(justify mirror)
			)
		)
		(property "Public" "False"
			(at 0 0 0)
			(layer "B.Fab")
			(hide yes)
			(effects
				(font
					(size 1 1)
					(thickness 0.15)
				)
				(justify mirror)
			)
		)
		(property "Val" "100n"
			(at 0 0 0)
			(layer "B.Fab")
			(hide yes)
			(effects
				(font
					(size 1 1)
					(thickness 0.15)
				)
				(justify mirror)
			)
		)
		(property "Voltage" ""
			(at 0 0 0)
			(layer "B.Fab")
			(hide yes)
			(effects
				(font
					(size 1 1)
					(thickness 0.15)
				)
				(justify mirror)
			)
		)
		(sheetname "/Interfaces/")
		(sheetfile "interfaces.kicad_sch")
		(attr smd)
		(fp_rect
			(start -0.925 0.47)
			(end 0.925 -0.47)
			(stroke
				(width 0.05)
				(type default)
			)
			(fill no)
			(layer "B.CrtYd")
		)
		(fp_line
			(start -0.494 -0.248)
			(end -0.494 0.25)
			(stroke
				(width 0.15)
				(type solid)
			)
			(layer "B.Fab")
		)
		(fp_line
			(start -0.494 0.25)
			(end 0.504 0.25)
			(stroke
				(width 0.15)
				(type solid)
			)
			(layer "B.Fab")
		)
		(fp_line
			(start 0.504 -0.248)
			(end -0.494 -0.248)
			(stroke
				(width 0.15)
				(type solid)
			)
			(layer "B.Fab")
		)
		(fp_line
			(start 0.504 0.25)
			(end 0.504 -0.248)
			(stroke
				(width 0.15)
				(type solid)
			)
			(layer "B.Fab")
		)
		(pad "1" smd roundrect
			(at -0.48 0)
			(size 0.59 0.64)
			(layers "B.Cu" "B.Mask" "B.Paste")
			(roundrect_rratio 0.25)
			(net 1 "GND")
			(pintype "passive")
		)
		(pad "2" smd roundrect
			(at 0.48 0)
			(size 0.59 0.64)
			(layers "B.Cu" "B.Mask" "B.Paste")
			(roundrect_rratio 0.25)
			(net 339 "VCC1V2")
			(pintype "passive")
		)
	)
	(footprint "antmicro-footprints:C_0402_1005Metric"
		(layer "B.Cu")
		(at 95.925 162.485 90)
		(descr "Capacitor SMD 0402")
		(tags "capacitor SMD 0402")
		(property "Reference" "C194"
			(at -3.715 0.375 90)
			(layer "B.SilkS")
			(effects
				(font
					(size 0.7 0.7)
					(thickness 0.15)
				)
				(justify right bottom mirror)
			)
		)
		(property "Value" "C_100n_6V3_0402"
			(at 0 -1.4 90)
			(layer "B.Fab")
			(effects
				(font
					(size 0.7 0.7)
					(thickness 0.15)
				)
				(justify right bottom mirror)
			)
		)
		(property "Datasheet" "https://www.passivecomponent.com/wp-content/uploads/datasheet/WTC_MLCC_General_Purpose.pdf"
			(at 0 0 90)
			(layer "F.Fab")
			(hide yes)
			(effects
				(font
					(size 1.27 1.27)
					(thickness 0.15)
				)
			)
		)
		(property "Description" "SMT Multilayer Ceramic Capacitor, 0.1 µF, 6.3 V, 0402 [1005 Metric], ± 10%, X5R, Walsin MLCC"
			(at 0 0 90)
			(layer "F.Fab")
			(hide yes)
			(effects
				(font
					(size 1.27 1.27)
					(thickness 0.15)
				)
			)
		)
		(property "Author" "Antmicro"
			(at 258.41 66.56 0)
			(layer "B.Fab")
			(hide yes)
			(effects
				(font
					(size 1 1)
					(thickness 0.15)
				)
				(justify mirror)
			)
		)
		(property "Dielectric" ""
			(at 258.41 66.56 0)
			(layer "B.Fab")
			(hide yes)
			(effects
				(font
					(size 1 1)
					(thickness 0.15)
				)
				(justify mirror)
			)
		)
		(property "License" "Apache-2.0"
			(at 258.41 66.56 0)
			(layer "B.Fab")
			(hide yes)
			(effects
				(font
					(size 1 1)
					(thickness 0.15)
				)
				(justify mirror)
			)
		)
		(property "MPN" "0402X104K6R3CT"
			(at 258.41 66.56 0)
			(layer "B.Fab")
			(hide yes)
			(effects
				(font
					(size 1 1)
					(thickness 0.15)
				)
				(justify mirror)
			)
		)
		(property "Manufacturer" "Walsin"
			(at 258.41 66.56 0)
			(layer "B.Fab")
			(hide yes)
			(effects
				(font
					(size 1 1)
					(thickness 0.15)
				)
				(justify mirror)
			)
		)
		(property "Public" "False"
			(at 258.41 66.56 0)
			(layer "B.Fab")
			(hide yes)
			(effects
				(font
					(size 1 1)
					(thickness 0.15)
				)
				(justify mirror)
			)
		)
		(property "Val" "100n"
			(at 258.41 66.56 0)
			(layer "B.Fab")
			(hide yes)
			(effects
				(font
					(size 1 1)
					(thickness 0.15)
				)
				(justify mirror)
			)
		)
		(property "Voltage" ""
			(at 258.41 66.56 0)
			(layer "B.Fab")
			(hide yes)
			(effects
				(font
					(size 1 1)
					(thickness 0.15)
				)
				(justify mirror)
			)
		)
		(sheetname "/Interfaces/")
		(sheetfile "interfaces.kicad_sch")
		(attr smd)
		(fp_rect
			(start -0.925 0.47)
			(end 0.925 -0.47)
			(stroke
				(width 0.05)
				(type default)
			)
			(fill no)
			(layer "B.CrtYd")
		)
		(fp_line
			(start 0.504 -0.248)
			(end -0.494 -0.248)
			(stroke
				(width 0.15)
				(type solid)
			)
			(layer "B.Fab")
		)
		(fp_line
			(start -0.494 -0.248)
			(end -0.494 0.25)
			(stroke
				(width 0.15)
				(type solid)
			)
			(layer "B.Fab")
		)
		(fp_line
			(start 0.504 0.25)
			(end 0.504 -0.248)
			(stroke
				(width 0.15)
				(type solid)
			)
			(layer "B.Fab")
		)
		(fp_line
			(start -0.494 0.25)
			(end 0.504 0.25)
			(stroke
				(width 0.15)
				(type solid)
			)
			(layer "B.Fab")
		)
		(pad "1" smd roundrect
			(at -0.48 0 90)
			(size 0.59 0.64)
			(layers "B.Cu" "B.Mask" "B.Paste")
			(roundrect_rratio 0.25)
			(net 377 "PCIE_BMC_TX_N")
			(pintype "passive")
		)
		(pad "2" smd roundrect
			(at 0.48 0 90)
			(size 0.59 0.64)
			(layers "B.Cu" "B.Mask" "B.Paste")
			(roundrect_rratio 0.25)
			(net 489 "/Interfaces/PCIE_BMC_TX_C_N")
			(pintype "passive")
		)
	)
	(footprint "antmicro-footprints:C_0402_1005Metric"
		(layer "B.Cu")
		(at 105.76 98.12 -90)
		(descr "Capacitor SMD 0402")
		(tags "capacitor SMD 0402")
		(property "Reference" "C198"
			(at -3.62 -0.36 90)
			(layer "B.SilkS")
			(effects
				(font
					(size 0.7 0.7)
					(thickness 0.15)
				)
				(justify left bottom mirror)
			)
		)
		(property "Value" "C_4u7_0402"
			(at 0 -1.4 90)
			(layer "B.Fab")
			(effects
				(font
					(size 0.7 0.7)
					(thickness 0.15)
				)
				(justify left bottom mirror)
			)
		)
		(property "Datasheet" "https://www.murata.com/products/productdetail?partno=GRM155R61A475MEAA%23"
			(at 0 0 270)
			(layer "F.Fab")
			(hide yes)
			(effects
				(font
					(size 1.27 1.27)
					(thickness 0.15)
				)
			)
		)
		(property "Description" "SMD Multilayer Ceramic Capacitor, 4.7 µF, 10 V, 0402 [1005 Metric], ± 20%, X5R, GRM Series"
			(at 0 0 270)
			(layer "F.Fab")
			(hide yes)
			(effects
				(font
					(size 1.27 1.27)
					(thickness 0.15)
				)
			)
		)
		(property "Author" "Antmicro"
			(at 7.64 203.88 0)
			(layer "B.Fab")
			(hide yes)
			(effects
				(font
					(size 1 1)
					(thickness 0.15)
				)
				(justify mirror)
			)
		)
		(property "Dielectric" ""
			(at 7.64 203.88 0)
			(layer "B.Fab")
			(hide yes)
			(effects
				(font
					(size 1 1)
					(thickness 0.15)
				)
				(justify mirror)
			)
		)
		(property "License" "Apache-2.0"
			(at 7.64 203.88 0)
			(layer "B.Fab")
			(hide yes)
			(effects
				(font
					(size 1 1)
					(thickness 0.15)
				)
				(justify mirror)
			)
		)
		(property "MPN" "GRM155R61A475MEAAD"
			(at 7.64 203.88 0)
			(layer "B.Fab")
			(hide yes)
			(effects
				(font
					(size 1 1)
					(thickness 0.15)
				)
				(justify mirror)
			)
		)
		(property "Manufacturer" "Murata"
			(at 7.64 203.88 0)
			(layer "B.Fab")
			(hide yes)
			(effects
				(font
					(size 1 1)
					(thickness 0.15)
				)
				(justify mirror)
			)
		)
		(property "Val" "4u7"
			(at 7.64 203.88 0)
			(layer "B.Fab")
			(hide yes)
			(effects
				(font
					(size 1 1)
					(thickness 0.15)
				)
				(justify mirror)
			)
		)
		(property "Voltage" ""
			(at 7.64 203.88 0)
			(layer "B.Fab")
			(hide yes)
			(effects
				(font
					(size 1 1)
					(thickness 0.15)
				)
				(justify mirror)
			)
		)
		(sheetname "/Ethernet/")
		(sheetfile "ethernet.kicad_sch")
		(attr smd)
		(fp_rect
			(start -0.925 0.47)
			(end 0.925 -0.47)
			(stroke
				(width 0.05)
				(type default)
			)
			(fill no)
			(layer "B.CrtYd")
		)
		(fp_line
			(start -0.494 0.25)
			(end 0.504 0.25)
			(stroke
				(width 0.15)
				(type solid)
			)
			(layer "B.Fab")
		)
		(fp_line
			(start 0.504 0.25)
			(end 0.504 -0.248)
			(stroke
				(width 0.15)
				(type solid)
			)
			(layer "B.Fab")
		)
		(fp_line
			(start -0.494 -0.248)
			(end -0.494 0.25)
			(stroke
				(width 0.15)
				(type solid)
			)
			(layer "B.Fab")
		)
		(fp_line
			(start 0.504 -0.248)
			(end -0.494 -0.248)
			(stroke
				(width 0.15)
				(type solid)
			)
			(layer "B.Fab")
		)
		(pad "1" smd roundrect
			(at -0.48 0 270)
			(size 0.59 0.64)
			(layers "B.Cu" "B.Mask" "B.Paste")
			(roundrect_rratio 0.25)
			(net 1 "GND")
			(pintype "passive")
		)
		(pad "2" smd roundrect
			(at 0.48 0 270)
			(size 0.59 0.64)
			(layers "B.Cu" "B.Mask" "B.Paste")
			(roundrect_rratio 0.25)
			(net 2 "VCC3V3")
			(pintype "passive")
		)
	)
	(footprint "antmicro-footprints:C_0402_1005Metric"
		(layer "B.Cu")
		(at 102.75 90.765 -90)
		(descr "Capacitor SMD 0402")
		(tags "capacitor SMD 0402")
		(property "Reference" "C200"
			(at -3.649 -0.4 90)
			(layer "B.SilkS")
			(effects
				(font
					(size 0.7 0.7)
					(thickness 0.15)
				)
				(justify left bottom mirror)
			)
		)
		(property "Value" "C_4u7_0402"
			(at 0 -1.4 90)
			(layer "B.Fab")
			(effects
				(font
					(size 0.7 0.7)
					(thickness 0.15)
				)
				(justify left bottom mirror)
			)
		)
		(property "Datasheet" "https://www.murata.com/products/productdetail?partno=GRM155R61A475MEAA%23"
			(at 0 0 270)
			(layer "F.Fab")
			(hide yes)
			(effects
				(font
					(size 1.27 1.27)
					(thickness 0.15)
				)
			)
		)
		(property "Description" "SMD Multilayer Ceramic Capacitor, 4.7 µF, 10 V, 0402 [1005 Metric], ± 20%, X5R, GRM Series"
			(at 0 0 270)
			(layer "F.Fab")
			(hide yes)
			(effects
				(font
					(size 1.27 1.27)
					(thickness 0.15)
				)
			)
		)
		(property "Author" "Antmicro"
			(at 11.985 193.515 0)
			(layer "B.Fab")
			(hide yes)
			(effects
				(font
					(size 1 1)
					(thickness 0.15)
				)
				(justify mirror)
			)
		)
		(property "Dielectric" ""
			(at 11.985 193.515 0)
			(layer "B.Fab")
			(hide yes)
			(effects
				(font
					(size 1 1)
					(thickness 0.15)
				)
				(justify mirror)
			)
		)
		(property "License" "Apache-2.0"
			(at 11.985 193.515 0)
			(layer "B.Fab")
			(hide yes)
			(effects
				(font
					(size 1 1)
					(thickness 0.15)
				)
				(justify mirror)
			)
		)
		(property "MPN" "GRM155R61A475MEAAD"
			(at 11.985 193.515 0)
			(layer "B.Fab")
			(hide yes)
			(effects
				(font
					(size 1 1)
					(thickness 0.15)
				)
				(justify mirror)
			)
		)
		(property "Manufacturer" "Murata"
			(at 11.985 193.515 0)
			(layer "B.Fab")
			(hide yes)
			(effects
				(font
					(size 1 1)
					(thickness 0.15)
				)
				(justify mirror)
			)
		)
		(property "Val" "4u7"
			(at 11.985 193.515 0)
			(layer "B.Fab")
			(hide yes)
			(effects
				(font
					(size 1 1)
					(thickness 0.15)
				)
				(justify mirror)
			)
		)
		(property "Voltage" ""
			(at 11.985 193.515 0)
			(layer "B.Fab")
			(hide yes)
			(effects
				(font
					(size 1 1)
					(thickness 0.15)
				)
				(justify mirror)
			)
		)
		(sheetname "/Ethernet/")
		(sheetfile "ethernet.kicad_sch")
		(attr smd)
		(fp_rect
			(start -0.925 0.47)
			(end 0.925 -0.47)
			(stroke
				(width 0.05)
				(type default)
			)
			(fill no)
			(layer "B.CrtYd")
		)
		(fp_line
			(start -0.494 0.25)
			(end 0.504 0.25)
			(stroke
				(width 0.15)
				(type solid)
			)
			(layer "B.Fab")
		)
		(fp_line
			(start 0.504 0.25)
			(end 0.504 -0.248)
			(stroke
				(width 0.15)
				(type solid)
			)
			(layer "B.Fab")
		)
		(fp_line
			(start -0.494 -0.248)
			(end -0.494 0.25)
			(stroke
				(width 0.15)
				(type solid)
			)
			(layer "B.Fab")
		)
		(fp_line
			(start 0.504 -0.248)
			(end -0.494 -0.248)
			(stroke
				(width 0.15)
				(type solid)
			)
			(layer "B.Fab")
		)
		(pad "1" smd roundrect
			(at -0.48 0 270)
			(size 0.59 0.64)
			(layers "B.Cu" "B.Mask" "B.Paste")
			(roundrect_rratio 0.25)
			(net 1 "GND")
			(pintype "passive")
		)
		(pad "2" smd roundrect
			(at 0.48 0 270)
			(size 0.59 0.64)
			(layers "B.Cu" "B.Mask" "B.Paste")
			(roundrect_rratio 0.25)
			(net 405 "/Ethernet/AVDDL")
			(pintype "passive")
		)
	)
	(footprint "antmicro-footprints:C_0402_1005Metric"
		(layer "B.Cu")
		(at 100.845 90.765 -90)
		(descr "Capacitor SMD 0402")
		(tags "capacitor SMD 0402")
		(property "Reference" "C204"
			(at -3.649 -0.4 90)
			(layer "B.SilkS")
			(effects
				(font
					(size 0.7 0.7)
					(thickness 0.15)
				)
				(justify left bottom mirror)
			)
		)
		(property "Value" "C_470n_0402"
			(at 0 -1.4 90)
			(layer "B.Fab")
			(effects
				(font
					(size 0.7 0.7)
					(thickness 0.15)
				)
				(justify left bottom mirror)
			)
		)
		(property "Datasheet" "https://product.tdk.com/en/search/capacitor/ceramic/mlcc/info?part_no=C1005X5R1E474M050BB"
			(at 0 0 270)
			(layer "F.Fab")
			(hide yes)
			(effects
				(font
					(size 1.27 1.27)
					(thickness 0.15)
				)
			)
		)
		(property "Description" "SMD Multilayer Ceramic Capacitor, 0.47 µF, 25 V, 0402 [1005 Metric], ± 20%, X5R, C"
			(at 0 0 270)
			(layer "F.Fab")
			(hide yes)
			(effects
				(font
					(size 1.27 1.27)
					(thickness 0.15)
				)
			)
		)
		(property "Author" "Antmicro"
			(at 10.08 191.61 0)
			(layer "B.Fab")
			(hide yes)
			(effects
				(font
					(size 1 1)
					(thickness 0.15)
				)
				(justify mirror)
			)
		)
		(property "Dielectric" ""
			(at 10.08 191.61 0)
			(layer "B.Fab")
			(hide yes)
			(effects
				(font
					(size 1 1)
					(thickness 0.15)
				)
				(justify mirror)
			)
		)
		(property "License" "Apache-2.0"
			(at 10.08 191.61 0)
			(layer "B.Fab")
			(hide yes)
			(effects
				(font
					(size 1 1)
					(thickness 0.15)
				)
				(justify mirror)
			)
		)
		(property "MPN" "C1005X5R1E474M050BB"
			(at 10.08 191.61 0)
			(layer "B.Fab")
			(hide yes)
			(effects
				(font
					(size 1 1)
					(thickness 0.15)
				)
				(justify mirror)
			)
		)
		(property "Manufacturer" "TDK"
			(at 10.08 191.61 0)
			(layer "B.Fab")
			(hide yes)
			(effects
				(font
					(size 1 1)
					(thickness 0.15)
				)
				(justify mirror)
			)
		)
		(property "Val" "470n"
			(at 10.08 191.61 0)
			(layer "B.Fab")
			(hide yes)
			(effects
				(font
					(size 1 1)
					(thickness 0.15)
				)
				(justify mirror)
			)
		)
		(property "Voltage" ""
			(at 10.08 191.61 0)
			(layer "B.Fab")
			(hide yes)
			(effects
				(font
					(size 1 1)
					(thickness 0.15)
				)
				(justify mirror)
			)
		)
		(sheetname "/Ethernet/")
		(sheetfile "ethernet.kicad_sch")
		(attr smd)
		(fp_rect
			(start -0.925 0.47)
			(end 0.925 -0.47)
			(stroke
				(width 0.05)
				(type default)
			)
			(fill no)
			(layer "B.CrtYd")
		)
		(fp_line
			(start -0.494 0.25)
			(end 0.504 0.25)
			(stroke
				(width 0.15)
				(type solid)
			)
			(layer "B.Fab")
		)
		(fp_line
			(start 0.504 0.25)
			(end 0.504 -0.248)
			(stroke
				(width 0.15)
				(type solid)
			)
			(layer "B.Fab")
		)
		(fp_line
			(start -0.494 -0.248)
			(end -0.494 0.25)
			(stroke
				(width 0.15)
				(type solid)
			)
			(layer "B.Fab")
		)
		(fp_line
			(start 0.504 -0.248)
			(end -0.494 -0.248)
			(stroke
				(width 0.15)
				(type solid)
			)
			(layer "B.Fab")
		)
		(pad "1" smd roundrect
			(at -0.48 0 270)
			(size 0.59 0.64)
			(layers "B.Cu" "B.Mask" "B.Paste")
			(roundrect_rratio 0.25)
			(net 1 "GND")
			(pintype "passive")
		)
		(pad "2" smd roundrect
			(at 0.48 0 270)
			(size 0.59 0.64)
			(layers "B.Cu" "B.Mask" "B.Paste")
			(roundrect_rratio 0.25)
			(net 405 "/Ethernet/AVDDL")
			(pintype "passive")
		)
	)
	(footprint "antmicro-footprints:C_0402_1005Metric"
		(layer "B.Cu")
		(at 101.14 98.12 -90)
		(descr "Capacitor SMD 0402")
		(tags "capacitor SMD 0402")
		(property "Reference" "C205"
			(at -3.62 -0.36 90)
			(layer "B.SilkS")
			(effects
				(font
					(size 0.7 0.7)
					(thickness 0.15)
				)
				(justify left bottom mirror)
			)
		)
		(property "Value" "C_470n_0402"
			(at 0 -1.4 90)
			(layer "B.Fab")
			(effects
				(font
					(size 0.7 0.7)
					(thickness 0.15)
				)
				(justify left bottom mirror)
			)
		)
		(property "Datasheet" "https://product.tdk.com/en/search/capacitor/ceramic/mlcc/info?part_no=C1005X5R1E474M050BB"
			(at 0 0 270)
			(layer "F.Fab")
			(hide yes)
			(effects
				(font
					(size 1.27 1.27)
					(thickness 0.15)
				)
			)
		)
		(property "Description" "SMD Multilayer Ceramic Capacitor, 0.47 µF, 25 V, 0402 [1005 Metric], ± 20%, X5R, C"
			(at 0 0 270)
			(layer "F.Fab")
			(hide yes)
			(effects
				(font
					(size 1.27 1.27)
					(thickness 0.15)
				)
			)
		)
		(property "Author" "Antmicro"
			(at 3.02 199.26 0)
			(layer "B.Fab")
			(hide yes)
			(effects
				(font
					(size 1 1)
					(thickness 0.15)
				)
				(justify mirror)
			)
		)
		(property "Dielectric" ""
			(at 3.02 199.26 0)
			(layer "B.Fab")
			(hide yes)
			(effects
				(font
					(size 1 1)
					(thickness 0.15)
				)
				(justify mirror)
			)
		)
		(property "License" "Apache-2.0"
			(at 3.02 199.26 0)
			(layer "B.Fab")
			(hide yes)
			(effects
				(font
					(size 1 1)
					(thickness 0.15)
				)
				(justify mirror)
			)
		)
		(property "MPN" "C1005X5R1E474M050BB"
			(at 3.02 199.26 0)
			(layer "B.Fab")
			(hide yes)
			(effects
				(font
					(size 1 1)
					(thickness 0.15)
				)
				(justify mirror)
			)
		)
		(property "Manufacturer" "TDK"
			(at 3.02 199.26 0)
			(layer "B.Fab")
			(hide yes)
			(effects
				(font
					(size 1 1)
					(thickness 0.15)
				)
				(justify mirror)
			)
		)
		(property "Val" "470n"
			(at 3.02 199.26 0)
			(layer "B.Fab")
			(hide yes)
			(effects
				(font
					(size 1 1)
					(thickness 0.15)
				)
				(justify mirror)
			)
		)
		(property "Voltage" ""
			(at 3.02 199.26 0)
			(layer "B.Fab")
			(hide yes)
			(effects
				(font
					(size 1 1)
					(thickness 0.15)
				)
				(justify mirror)
			)
		)
		(sheetname "/Ethernet/")
		(sheetfile "ethernet.kicad_sch")
		(attr smd)
		(fp_rect
			(start -0.925 0.47)
			(end 0.925 -0.47)
			(stroke
				(width 0.05)
				(type default)
			)
			(fill no)
			(layer "B.CrtYd")
		)
		(fp_line
			(start -0.494 0.25)
			(end 0.504 0.25)
			(stroke
				(width 0.15)
				(type solid)
			)
			(layer "B.Fab")
		)
		(fp_line
			(start 0.504 0.25)
			(end 0.504 -0.248)
			(stroke
				(width 0.15)
				(type solid)
			)
			(layer "B.Fab")
		)
		(fp_line
			(start -0.494 -0.248)
			(end -0.494 0.25)
			(stroke
				(width 0.15)
				(type solid)
			)
			(layer "B.Fab")
		)
		(fp_line
			(start 0.504 -0.248)
			(end -0.494 -0.248)
			(stroke
				(width 0.15)
				(type solid)
			)
			(layer "B.Fab")
		)
		(pad "1" smd roundrect
			(at -0.48 0 270)
			(size 0.59 0.64)
			(layers "B.Cu" "B.Mask" "B.Paste")
			(roundrect_rratio 0.25)
			(net 1 "GND")
			(pintype "passive")
		)
		(pad "2" smd roundrect
			(at 0.48 0 270)
			(size 0.59 0.64)
			(layers "B.Cu" "B.Mask" "B.Paste")
			(roundrect_rratio 0.25)
			(net 339 "VCC1V2")
			(pintype "passive")
		)
	)
	(footprint "antmicro-footprints:C_0402_1005Metric"
		(layer "B.Cu")
		(at 98.419 90.78 -90)
		(descr "Capacitor SMD 0402")
		(tags "capacitor SMD 0402")
		(property "Reference" "C206"
			(at -3.68 1.519 90)
			(layer "B.SilkS")
			(effects
				(font
					(size 0.7 0.7)
					(thickness 0.15)
				)
				(justify left bottom mirror)
			)
		)
		(property "Value" "C_4u7_0402"
			(at 0 -1.4 90)
			(layer "B.Fab")
			(effects
				(font
					(size 0.7 0.7)
					(thickness 0.15)
				)
				(justify left bottom mirror)
			)
		)
		(property "Datasheet" "https://www.murata.com/products/productdetail?partno=GRM155R61A475MEAA%23"
			(at 0 0 270)
			(layer "F.Fab")
			(hide yes)
			(effects
				(font
					(size 1.27 1.27)
					(thickness 0.15)
				)
			)
		)
		(property "Description" "SMD Multilayer Ceramic Capacitor, 4.7 µF, 10 V, 0402 [1005 Metric], ± 20%, X5R, GRM Series"
			(at 0 0 270)
			(layer "F.Fab")
			(hide yes)
			(effects
				(font
					(size 1.27 1.27)
					(thickness 0.15)
				)
			)
		)
		(property "Author" "Antmicro"
			(at 7.639 189.199 0)
			(layer "B.Fab")
			(hide yes)
			(effects
				(font
					(size 1 1)
					(thickness 0.15)
				)
				(justify mirror)
			)
		)
		(property "Dielectric" ""
			(at 7.639 189.199 0)
			(layer "B.Fab")
			(hide yes)
			(effects
				(font
					(size 1 1)
					(thickness 0.15)
				)
				(justify mirror)
			)
		)
		(property "License" "Apache-2.0"
			(at 7.639 189.199 0)
			(layer "B.Fab")
			(hide yes)
			(effects
				(font
					(size 1 1)
					(thickness 0.15)
				)
				(justify mirror)
			)
		)
		(property "MPN" "GRM155R61A475MEAAD"
			(at 7.639 189.199 0)
			(layer "B.Fab")
			(hide yes)
			(effects
				(font
					(size 1 1)
					(thickness 0.15)
				)
				(justify mirror)
			)
		)
		(property "Manufacturer" "Murata"
			(at 7.639 189.199 0)
			(layer "B.Fab")
			(hide yes)
			(effects
				(font
					(size 1 1)
					(thickness 0.15)
				)
				(justify mirror)
			)
		)
		(property "Val" "4u7"
			(at 7.639 189.199 0)
			(layer "B.Fab")
			(hide yes)
			(effects
				(font
					(size 1 1)
					(thickness 0.15)
				)
				(justify mirror)
			)
		)
		(property "Voltage" ""
			(at 7.639 189.199 0)
			(layer "B.Fab")
			(hide yes)
			(effects
				(font
					(size 1 1)
					(thickness 0.15)
				)
				(justify mirror)
			)
		)
		(sheetname "/Ethernet/")
		(sheetfile "ethernet.kicad_sch")
		(attr smd)
		(fp_rect
			(start -0.925 0.47)
			(end 0.925 -0.47)
			(stroke
				(width 0.05)
				(type default)
			)
			(fill no)
			(layer "B.CrtYd")
		)
		(fp_line
			(start -0.494 0.25)
			(end 0.504 0.25)
			(stroke
				(width 0.15)
				(type solid)
			)
			(layer "B.Fab")
		)
		(fp_line
			(start 0.504 0.25)
			(end 0.504 -0.248)
			(stroke
				(width 0.15)
				(type solid)
			)
			(layer "B.Fab")
		)
		(fp_line
			(start -0.494 -0.248)
			(end -0.494 0.25)
			(stroke
				(width 0.15)
				(type solid)
			)
			(layer "B.Fab")
		)
		(fp_line
			(start 0.504 -0.248)
			(end -0.494 -0.248)
			(stroke
				(width 0.15)
				(type solid)
			)
			(layer "B.Fab")
		)
		(pad "1" smd roundrect
			(at -0.48 0 270)
			(size 0.59 0.64)
			(layers "B.Cu" "B.Mask" "B.Paste")
			(roundrect_rratio 0.25)
			(net 1 "GND")
			(pintype "passive")
		)
		(pad "2" smd roundrect
			(at 0.48 0 270)
			(size 0.59 0.64)
			(layers "B.Cu" "B.Mask" "B.Paste")
			(roundrect_rratio 0.25)
			(net 406 "/Ethernet/AVDDH")
			(pintype "passive")
		)
	)
	(footprint "antmicro-footprints:C_0402_1005Metric"
		(layer "B.Cu")
		(at 103.7 90.765 -90)
		(descr "Capacitor SMD 0402")
		(tags "capacitor SMD 0402")
		(property "Reference" "C209"
			(at -3.649 -0.4 90)
			(layer "B.SilkS")
			(effects
				(font
					(size 0.7 0.7)
					(thickness 0.15)
				)
				(justify left bottom mirror)
			)
		)
		(property "Value" "C_10n_0402"
			(at 0 -1.4 90)
			(layer "B.Fab")
			(effects
				(font
					(size 0.7 0.7)
					(thickness 0.15)
				)
				(justify left bottom mirror)
			)
		)
		(property "Datasheet" "https://www.murata.com/products/productdetail?partno=GRM155R71H103KA88%23"
			(at 0 0 270)
			(layer "F.Fab")
			(hide yes)
			(effects
				(font
					(size 1.27 1.27)
					(thickness 0.15)
				)
			)
		)
		(property "Description" "SMD Multilayer Ceramic Capacitor, 10000 pF, 50 V, 0402 [1005 Metric], ± 10%, X7R, GRM Series"
			(at 0 0 270)
			(layer "F.Fab")
			(hide yes)
			(effects
				(font
					(size 1.27 1.27)
					(thickness 0.15)
				)
			)
		)
		(property "Author" "Antmicro"
			(at 12.935 194.465 0)
			(layer "B.Fab")
			(hide yes)
			(effects
				(font
					(size 1 1)
					(thickness 0.15)
				)
				(justify mirror)
			)
		)
		(property "Dielectric" "X7R"
			(at 12.935 194.465 0)
			(layer "B.Fab")
			(hide yes)
			(effects
				(font
					(size 1 1)
					(thickness 0.15)
				)
				(justify mirror)
			)
		)
		(property "License" "Apache-2.0"
			(at 12.935 194.465 0)
			(layer "B.Fab")
			(hide yes)
			(effects
				(font
					(size 1 1)
					(thickness 0.15)
				)
				(justify mirror)
			)
		)
		(property "MPN" "GRM155R71H103KA88D"
			(at 12.935 194.465 0)
			(layer "B.Fab")
			(hide yes)
			(effects
				(font
					(size 1 1)
					(thickness 0.15)
				)
				(justify mirror)
			)
		)
		(property "Manufacturer" "Murata"
			(at 12.935 194.465 0)
			(layer "B.Fab")
			(hide yes)
			(effects
				(font
					(size 1 1)
					(thickness 0.15)
				)
				(justify mirror)
			)
		)
		(property "Val" "10n"
			(at 12.935 194.465 0)
			(layer "B.Fab")
			(hide yes)
			(effects
				(font
					(size 1 1)
					(thickness 0.15)
				)
				(justify mirror)
			)
		)
		(property "Voltage" "50V"
			(at 12.935 194.465 0)
			(layer "B.Fab")
			(hide yes)
			(effects
				(font
					(size 1 1)
					(thickness 0.15)
				)
				(justify mirror)
			)
		)
		(sheetname "/Ethernet/")
		(sheetfile "ethernet.kicad_sch")
		(attr smd)
		(fp_rect
			(start -0.925 0.47)
			(end 0.925 -0.47)
			(stroke
				(width 0.05)
				(type default)
			)
			(fill no)
			(layer "B.CrtYd")
		)
		(fp_line
			(start -0.494 0.25)
			(end 0.504 0.25)
			(stroke
				(width 0.15)
				(type solid)
			)
			(layer "B.Fab")
		)
		(fp_line
			(start 0.504 0.25)
			(end 0.504 -0.248)
			(stroke
				(width 0.15)
				(type solid)
			)
			(layer "B.Fab")
		)
		(fp_line
			(start -0.494 -0.248)
			(end -0.494 0.25)
			(stroke
				(width 0.15)
				(type solid)
			)
			(layer "B.Fab")
		)
		(fp_line
			(start 0.504 -0.248)
			(end -0.494 -0.248)
			(stroke
				(width 0.15)
				(type solid)
			)
			(layer "B.Fab")
		)
		(pad "1" smd roundrect
			(at -0.48 0 270)
			(size 0.59 0.64)
			(layers "B.Cu" "B.Mask" "B.Paste")
			(roundrect_rratio 0.25)
			(net 1 "GND")
			(pintype "passive")
		)
		(pad "2" smd roundrect
			(at 0.48 0 270)
			(size 0.59 0.64)
			(layers "B.Cu" "B.Mask" "B.Paste")
			(roundrect_rratio 0.25)
			(net 405 "/Ethernet/AVDDL")
			(pintype "passive")
		)
	)
	(footprint "antmicro-footprints:C_0402_1005Metric"
		(layer "B.Cu")
		(at 106.1 90.75 -90)
		(descr "Capacitor SMD 0402")
		(tags "capacitor SMD 0402")
		(property "Reference" "C211"
			(at -3.649 -0.4 90)
			(layer "B.SilkS")
			(effects
				(font
					(size 0.7 0.7)
					(thickness 0.15)
				)
				(justify left bottom mirror)
			)
		)
		(property "Value" "C_10n_0402"
			(at 0 -1.4 90)
			(layer "B.Fab")
			(effects
				(font
					(size 0.7 0.7)
					(thickness 0.15)
				)
				(justify left bottom mirror)
			)
		)
		(property "Datasheet" "https://www.murata.com/products/productdetail?partno=GRM155R71H103KA88%23"
			(at 0 0 270)
			(layer "F.Fab")
			(hide yes)
			(effects
				(font
					(size 1.27 1.27)
					(thickness 0.15)
				)
			)
		)
		(property "Description" "SMD Multilayer Ceramic Capacitor, 10000 pF, 50 V, 0402 [1005 Metric], ± 10%, X7R, GRM Series"
			(at 0 0 270)
			(layer "F.Fab")
			(hide yes)
			(effects
				(font
					(size 1.27 1.27)
					(thickness 0.15)
				)
			)
		)
		(property "Author" "Antmicro"
			(at 15.35 196.85 0)
			(layer "B.Fab")
			(hide yes)
			(effects
				(font
					(size 1 1)
					(thickness 0.15)
				)
				(justify mirror)
			)
		)
		(property "Dielectric" "X7R"
			(at 15.35 196.85 0)
			(layer "B.Fab")
			(hide yes)
			(effects
				(font
					(size 1 1)
					(thickness 0.15)
				)
				(justify mirror)
			)
		)
		(property "License" "Apache-2.0"
			(at 15.35 196.85 0)
			(layer "B.Fab")
			(hide yes)
			(effects
				(font
					(size 1 1)
					(thickness 0.15)
				)
				(justify mirror)
			)
		)
		(property "MPN" "GRM155R71H103KA88D"
			(at 15.35 196.85 0)
			(layer "B.Fab")
			(hide yes)
			(effects
				(font
					(size 1 1)
					(thickness 0.15)
				)
				(justify mirror)
			)
		)
		(property "Manufacturer" "Murata"
			(at 15.35 196.85 0)
			(layer "B.Fab")
			(hide yes)
			(effects
				(font
					(size 1 1)
					(thickness 0.15)
				)
				(justify mirror)
			)
		)
		(property "Val" "10n"
			(at 15.35 196.85 0)
			(layer "B.Fab")
			(hide yes)
			(effects
				(font
					(size 1 1)
					(thickness 0.15)
				)
				(justify mirror)
			)
		)
		(property "Voltage" "50V"
			(at 15.35 196.85 0)
			(layer "B.Fab")
			(hide yes)
			(effects
				(font
					(size 1 1)
					(thickness 0.15)
				)
				(justify mirror)
			)
		)
		(sheetname "/Ethernet/")
		(sheetfile "ethernet.kicad_sch")
		(attr smd)
		(fp_rect
			(start -0.925 0.47)
			(end 0.925 -0.47)
			(stroke
				(width 0.05)
				(type default)
			)
			(fill no)
			(layer "B.CrtYd")
		)
		(fp_line
			(start -0.494 0.25)
			(end 0.504 0.25)
			(stroke
				(width 0.15)
				(type solid)
			)
			(layer "B.Fab")
		)
		(fp_line
			(start 0.504 0.25)
			(end 0.504 -0.248)
			(stroke
				(width 0.15)
				(type solid)
			)
			(layer "B.Fab")
		)
		(fp_line
			(start -0.494 -0.248)
			(end -0.494 0.25)
			(stroke
				(width 0.15)
				(type solid)
			)
			(layer "B.Fab")
		)
		(fp_line
			(start 0.504 -0.248)
			(end -0.494 -0.248)
			(stroke
				(width 0.15)
				(type solid)
			)
			(layer "B.Fab")
		)
		(pad "1" smd roundrect
			(at -0.48 0 270)
			(size 0.59 0.64)
			(layers "B.Cu" "B.Mask" "B.Paste")
			(roundrect_rratio 0.25)
			(net 1 "GND")
			(pintype "passive")
		)
		(pad "2" smd roundrect
			(at 0.48 0 270)
			(size 0.59 0.64)
			(layers "B.Cu" "B.Mask" "B.Paste")
			(roundrect_rratio 0.25)
			(net 406 "/Ethernet/AVDDH")
			(pintype "passive")
		)
	)
	(footprint "antmicro-footprints:C_0402_1005Metric"
		(layer "B.Cu")
		(at 104.8 98.12 -90)
		(descr "Capacitor SMD 0402")
		(tags "capacitor SMD 0402")
		(property "Reference" "C212"
			(at -3.62 -0.36 90)
			(layer "B.SilkS")
			(effects
				(font
					(size 0.7 0.7)
					(thickness 0.15)
				)
				(justify left bottom mirror)
			)
		)
		(property "Value" "C_10n_0402"
			(at 0 -1.4 90)
			(layer "B.Fab")
			(effects
				(font
					(size 0.7 0.7)
					(thickness 0.15)
				)
				(justify left bottom mirror)
			)
		)
		(property "Datasheet" "https://www.murata.com/products/productdetail?partno=GRM155R71H103KA88%23"
			(at 0 0 270)
			(layer "F.Fab")
			(hide yes)
			(effects
				(font
					(size 1.27 1.27)
					(thickness 0.15)
				)
			)
		)
		(property "Description" "SMD Multilayer Ceramic Capacitor, 10000 pF, 50 V, 0402 [1005 Metric], ± 10%, X7R, GRM Series"
			(at 0 0 270)
			(layer "F.Fab")
			(hide yes)
			(effects
				(font
					(size 1.27 1.27)
					(thickness 0.15)
				)
			)
		)
		(property "Author" "Antmicro"
			(at 6.68 202.92 0)
			(layer "B.Fab")
			(hide yes)
			(effects
				(font
					(size 1 1)
					(thickness 0.15)
				)
				(justify mirror)
			)
		)
		(property "Dielectric" "X7R"
			(at 6.68 202.92 0)
			(layer "B.Fab")
			(hide yes)
			(effects
				(font
					(size 1 1)
					(thickness 0.15)
				)
				(justify mirror)
			)
		)
		(property "License" "Apache-2.0"
			(at 6.68 202.92 0)
			(layer "B.Fab")
			(hide yes)
			(effects
				(font
					(size 1 1)
					(thickness 0.15)
				)
				(justify mirror)
			)
		)
		(property "MPN" "GRM155R71H103KA88D"
			(at 6.68 202.92 0)
			(layer "B.Fab")
			(hide yes)
			(effects
				(font
					(size 1 1)
					(thickness 0.15)
				)
				(justify mirror)
			)
		)
		(property "Manufacturer" "Murata"
			(at 6.68 202.92 0)
			(layer "B.Fab")
			(hide yes)
			(effects
				(font
					(size 1 1)
					(thickness 0.15)
				)
				(justify mirror)
			)
		)
		(property "Val" "10n"
			(at 6.68 202.92 0)
			(layer "B.Fab")
			(hide yes)
			(effects
				(font
					(size 1 1)
					(thickness 0.15)
				)
				(justify mirror)
			)
		)
		(property "Voltage" "50V"
			(at 6.68 202.92 0)
			(layer "B.Fab")
			(hide yes)
			(effects
				(font
					(size 1 1)
					(thickness 0.15)
				)
				(justify mirror)
			)
		)
		(sheetname "/Ethernet/")
		(sheetfile "ethernet.kicad_sch")
		(attr smd)
		(fp_rect
			(start -0.925 0.47)
			(end 0.925 -0.47)
			(stroke
				(width 0.05)
				(type default)
			)
			(fill no)
			(layer "B.CrtYd")
		)
		(fp_line
			(start -0.494 0.25)
			(end 0.504 0.25)
			(stroke
				(width 0.15)
				(type solid)
			)
			(layer "B.Fab")
		)
		(fp_line
			(start 0.504 0.25)
			(end 0.504 -0.248)
			(stroke
				(width 0.15)
				(type solid)
			)
			(layer "B.Fab")
		)
		(fp_line
			(start -0.494 -0.248)
			(end -0.494 0.25)
			(stroke
				(width 0.15)
				(type solid)
			)
			(layer "B.Fab")
		)
		(fp_line
			(start 0.504 -0.248)
			(end -0.494 -0.248)
			(stroke
				(width 0.15)
				(type solid)
			)
			(layer "B.Fab")
		)
		(pad "1" smd roundrect
			(at -0.48 0 270)
			(size 0.59 0.64)
			(layers "B.Cu" "B.Mask" "B.Paste")
			(roundrect_rratio 0.25)
			(net 1 "GND")
			(pintype "passive")
		)
		(pad "2" smd roundrect
			(at 0.48 0 270)
			(size 0.59 0.64)
			(layers "B.Cu" "B.Mask" "B.Paste")
			(roundrect_rratio 0.25)
			(net 2 "VCC3V3")
			(pintype "passive")
		)
	)
	(footprint "antmicro-footprints:C_0402_1005Metric"
		(layer "B.Cu")
		(at 101.8 90.765 -90)
		(descr "Capacitor SMD 0402")
		(tags "capacitor SMD 0402")
		(property "Reference" "C213"
			(at -3.649 -0.4 90)
			(layer "B.SilkS")
			(effects
				(font
					(size 0.7 0.7)
					(thickness 0.15)
				)
				(justify left bottom mirror)
			)
		)
		(property "Value" "C_10n_0402"
			(at 0 -1.4 90)
			(layer "B.Fab")
			(effects
				(font
					(size 0.7 0.7)
					(thickness 0.15)
				)
				(justify left bottom mirror)
			)
		)
		(property "Datasheet" "https://www.murata.com/products/productdetail?partno=GRM155R71H103KA88%23"
			(at 0 0 270)
			(layer "F.Fab")
			(hide yes)
			(effects
				(font
					(size 1.27 1.27)
					(thickness 0.15)
				)
			)
		)
		(property "Description" "SMD Multilayer Ceramic Capacitor, 10000 pF, 50 V, 0402 [1005 Metric], ± 10%, X7R, GRM Series"
			(at 0 0 270)
			(layer "F.Fab")
			(hide yes)
			(effects
				(font
					(size 1.27 1.27)
					(thickness 0.15)
				)
			)
		)
		(property "Author" "Antmicro"
			(at 11.035 192.565 0)
			(layer "B.Fab")
			(hide yes)
			(effects
				(font
					(size 1 1)
					(thickness 0.15)
				)
				(justify mirror)
			)
		)
		(property "Dielectric" "X7R"
			(at 11.035 192.565 0)
			(layer "B.Fab")
			(hide yes)
			(effects
				(font
					(size 1 1)
					(thickness 0.15)
				)
				(justify mirror)
			)
		)
		(property "License" "Apache-2.0"
			(at 11.035 192.565 0)
			(layer "B.Fab")
			(hide yes)
			(effects
				(font
					(size 1 1)
					(thickness 0.15)
				)
				(justify mirror)
			)
		)
		(property "MPN" "GRM155R71H103KA88D"
			(at 11.035 192.565 0)
			(layer "B.Fab")
			(hide yes)
			(effects
				(font
					(size 1 1)
					(thickness 0.15)
				)
				(justify mirror)
			)
		)
		(property "Manufacturer" "Murata"
			(at 11.035 192.565 0)
			(layer "B.Fab")
			(hide yes)
			(effects
				(font
					(size 1 1)
					(thickness 0.15)
				)
				(justify mirror)
			)
		)
		(property "Val" "10n"
			(at 11.035 192.565 0)
			(layer "B.Fab")
			(hide yes)
			(effects
				(font
					(size 1 1)
					(thickness 0.15)
				)
				(justify mirror)
			)
		)
		(property "Voltage" "50V"
			(at 11.035 192.565 0)
			(layer "B.Fab")
			(hide yes)
			(effects
				(font
					(size 1 1)
					(thickness 0.15)
				)
				(justify mirror)
			)
		)
		(sheetname "/Ethernet/")
		(sheetfile "ethernet.kicad_sch")
		(attr smd)
		(fp_rect
			(start -0.925 0.47)
			(end 0.925 -0.47)
			(stroke
				(width 0.05)
				(type default)
			)
			(fill no)
			(layer "B.CrtYd")
		)
		(fp_line
			(start -0.494 0.25)
			(end 0.504 0.25)
			(stroke
				(width 0.15)
				(type solid)
			)
			(layer "B.Fab")
		)
		(fp_line
			(start 0.504 0.25)
			(end 0.504 -0.248)
			(stroke
				(width 0.15)
				(type solid)
			)
			(layer "B.Fab")
		)
		(fp_line
			(start -0.494 -0.248)
			(end -0.494 0.25)
			(stroke
				(width 0.15)
				(type solid)
			)
			(layer "B.Fab")
		)
		(fp_line
			(start 0.504 -0.248)
			(end -0.494 -0.248)
			(stroke
				(width 0.15)
				(type solid)
			)
			(layer "B.Fab")
		)
		(pad "1" smd roundrect
			(at -0.48 0 270)
			(size 0.59 0.64)
			(layers "B.Cu" "B.Mask" "B.Paste")
			(roundrect_rratio 0.25)
			(net 1 "GND")
			(pintype "passive")
		)
		(pad "2" smd roundrect
			(at 0.48 0 270)
			(size 0.59 0.64)
			(layers "B.Cu" "B.Mask" "B.Paste")
			(roundrect_rratio 0.25)
			(net 405 "/Ethernet/AVDDL")
			(pintype "passive")
		)
	)
	(footprint "antmicro-footprints:C_0402_1005Metric"
		(layer "B.Cu")
		(at 102.6 98.1 -90)
		(descr "Capacitor SMD 0402")
		(tags "capacitor SMD 0402")
		(property "Reference" "C217"
			(at -3.62 -0.36 90)
			(layer "B.SilkS")
			(effects
				(font
					(size 0.7 0.7)
					(thickness 0.15)
				)
				(justify left bottom mirror)
			)
		)
		(property "Value" "C_10n_0402"
			(at 0 -1.4 90)
			(layer "B.Fab")
			(effects
				(font
					(size 0.7 0.7)
					(thickness 0.15)
				)
				(justify left bottom mirror)
			)
		)
		(property "Datasheet" "https://www.murata.com/products/productdetail?partno=GRM155R71H103KA88%23"
			(at 0 0 270)
			(layer "F.Fab")
			(hide yes)
			(effects
				(font
					(size 1.27 1.27)
					(thickness 0.15)
				)
			)
		)
		(property "Description" "SMD Multilayer Ceramic Capacitor, 10000 pF, 50 V, 0402 [1005 Metric], ± 10%, X7R, GRM Series"
			(at 0 0 270)
			(layer "F.Fab")
			(hide yes)
			(effects
				(font
					(size 1.27 1.27)
					(thickness 0.15)
				)
			)
		)
		(property "Author" "Antmicro"
			(at 4.5 200.7 0)
			(layer "B.Fab")
			(hide yes)
			(effects
				(font
					(size 1 1)
					(thickness 0.15)
				)
				(justify mirror)
			)
		)
		(property "Dielectric" "X7R"
			(at 4.5 200.7 0)
			(layer "B.Fab")
			(hide yes)
			(effects
				(font
					(size 1 1)
					(thickness 0.15)
				)
				(justify mirror)
			)
		)
		(property "License" "Apache-2.0"
			(at 4.5 200.7 0)
			(layer "B.Fab")
			(hide yes)
			(effects
				(font
					(size 1 1)
					(thickness 0.15)
				)
				(justify mirror)
			)
		)
		(property "MPN" "GRM155R71H103KA88D"
			(at 4.5 200.7 0)
			(layer "B.Fab")
			(hide yes)
			(effects
				(font
					(size 1 1)
					(thickness 0.15)
				)
				(justify mirror)
			)
		)
		(property "Manufacturer" "Murata"
			(at 4.5 200.7 0)
			(layer "B.Fab")
			(hide yes)
			(effects
				(font
					(size 1 1)
					(thickness 0.15)
				)
				(justify mirror)
			)
		)
		(property "Val" "10n"
			(at 4.5 200.7 0)
			(layer "B.Fab")
			(hide yes)
			(effects
				(font
					(size 1 1)
					(thickness 0.15)
				)
				(justify mirror)
			)
		)
		(property "Voltage" "50V"
			(at 4.5 200.7 0)
			(layer "B.Fab")
			(hide yes)
			(effects
				(font
					(size 1 1)
					(thickness 0.15)
				)
				(justify mirror)
			)
		)
		(sheetname "/Ethernet/")
		(sheetfile "ethernet.kicad_sch")
		(attr smd)
		(fp_rect
			(start -0.925 0.47)
			(end 0.925 -0.47)
			(stroke
				(width 0.05)
				(type default)
			)
			(fill no)
			(layer "B.CrtYd")
		)
		(fp_line
			(start -0.494 0.25)
			(end 0.504 0.25)
			(stroke
				(width 0.15)
				(type solid)
			)
			(layer "B.Fab")
		)
		(fp_line
			(start 0.504 0.25)
			(end 0.504 -0.248)
			(stroke
				(width 0.15)
				(type solid)
			)
			(layer "B.Fab")
		)
		(fp_line
			(start -0.494 -0.248)
			(end -0.494 0.25)
			(stroke
				(width 0.15)
				(type solid)
			)
			(layer "B.Fab")
		)
		(fp_line
			(start 0.504 -0.248)
			(end -0.494 -0.248)
			(stroke
				(width 0.15)
				(type solid)
			)
			(layer "B.Fab")
		)
		(pad "1" smd roundrect
			(at -0.48 0 270)
			(size 0.59 0.64)
			(layers "B.Cu" "B.Mask" "B.Paste")
			(roundrect_rratio 0.25)
			(net 1 "GND")
			(pintype "passive")
		)
		(pad "2" smd roundrect
			(at 0.48 0 270)
			(size 0.59 0.64)
			(layers "B.Cu" "B.Mask" "B.Paste")
			(roundrect_rratio 0.25)
			(net 339 "VCC1V2")
			(pintype "passive")
		)
	)
	(footprint "antmicro-footprints:FB_0603_1608Metric"
		(layer "B.Cu")
		(at 104.9 90.45 -90)
		(property "Reference" "FB4"
			(at -3.35 -0.3 90)
			(layer "B.SilkS")
			(effects
				(font
					(size 0.7 0.7)
					(thickness 0.15)
				)
				(justify left bottom mirror)
			)
		)
		(property "Value" "FB_120Z_2A_Murata-BLM18PG_0603"
			(at 0 -1.7 90)
			(layer "B.Fab")
			(effects
				(font
					(size 0.7 0.7)
					(thickness 0.15)
				)
				(justify left bottom mirror)
			)
		)
		(property "Datasheet" "https://www.murata.com/en-us/products/productdata/8796738650142/ENFA0003.pdf"
			(at 0 0 270)
			(layer "F.Fab")
			(hide yes)
			(effects
				(font
					(size 1.27 1.27)
					(thickness 0.15)
				)
			)
		)
		(property "Description" "Ferrite Bead, 0603 [1608 Metric], 120 ohm, 2 A, BLM18P, 0.05 ohm, ± 25%, DC power line"
			(at 0 0 270)
			(layer "F.Fab")
			(hide yes)
			(effects
				(font
					(size 1.27 1.27)
					(thickness 0.15)
				)
			)
		)
		(property "Author" "Antmicro"
			(at 14.45 195.35 0)
			(layer "B.Fab")
			(hide yes)
			(effects
				(font
					(size 1 1)
					(thickness 0.15)
				)
				(justify mirror)
			)
		)
		(property "Current" ""
			(at 14.45 195.35 0)
			(layer "B.Fab")
			(hide yes)
			(effects
				(font
					(size 1 1)
					(thickness 0.15)
				)
				(justify mirror)
			)
		)
		(property "License" "Apache-2.0"
			(at 14.45 195.35 0)
			(layer "B.Fab")
			(hide yes)
			(effects
				(font
					(size 1 1)
					(thickness 0.15)
				)
				(justify mirror)
			)
		)
		(property "MPN" "BLM18PG121SN1D"
			(at 14.45 195.35 0)
			(layer "B.Fab")
			(hide yes)
			(effects
				(font
					(size 1 1)
					(thickness 0.15)
				)
				(justify mirror)
			)
		)
		(property "Manufacturer" "Murata"
			(at 14.45 195.35 0)
			(layer "B.Fab")
			(hide yes)
			(effects
				(font
					(size 1 1)
					(thickness 0.15)
				)
				(justify mirror)
			)
		)
		(property "Val" "120Z/2A"
			(at 14.45 195.35 0)
			(layer "B.Fab")
			(hide yes)
			(effects
				(font
					(size 1 1)
					(thickness 0.15)
				)
				(justify mirror)
			)
		)
		(sheetname "/Ethernet/")
		(sheetfile "ethernet.kicad_sch")
		(attr smd)
		(fp_line
			(start -0.15 0.4)
			(end 0.15 0.4)
			(stroke
				(width 0.15)
				(type solid)
			)
			(layer "B.SilkS")
		)
		(fp_line
			(start -0.15 -0.4)
			(end 0.15 -0.4)
			(stroke
				(width 0.15)
				(type solid)
			)
			(layer "B.SilkS")
		)
		(fp_rect
			(start -1.25 0.65)
			(end 1.25 -0.65)
			(stroke
				(width 0.05)
				(type solid)
			)
			(fill no)
			(layer "B.CrtYd")
		)
		(fp_line
			(start 0.8 0.408)
			(end -0.803 0.408)
			(stroke
				(width 0.15)
				(type solid)
			)
			(layer "B.Fab")
		)
		(fp_line
			(start 0.8 0.408)
			(end 0.8 -0.406)
			(stroke
				(width 0.15)
				(type solid)
			)
			(layer "B.Fab")
		)
		(fp_line
			(start -0.803 -0.406)
			(end -0.803 0.408)
			(stroke
				(width 0.15)
				(type solid)
			)
			(layer "B.Fab")
		)
		(fp_line
			(start 0.8 -0.406)
			(end -0.803 -0.406)
			(stroke
				(width 0.15)
				(type solid)
			)
			(layer "B.Fab")
		)
		(pad "1" smd roundrect
			(at -0.7 0 270)
			(size 0.8 1)
			(layers "B.Cu" "B.Mask" "B.Paste")
			(roundrect_rratio 0.2)
			(net 2 "VCC3V3")
			(pintype "passive")
		)
		(pad "2" smd roundrect
			(at 0.7 0 270)
			(size 0.8 1)
			(layers "B.Cu" "B.Mask" "B.Paste")
			(roundrect_rratio 0.2)
			(net 406 "/Ethernet/AVDDH")
			(pintype "passive")
		)
	)
	(footprint "antmicro-footprints:FB_0603_1608Metric"
		(layer "B.Cu")
		(at 99.66 90.47 90)
		(property "Reference" "FB6"
			(at 1.27 0.44 90)
			(layer "B.SilkS")
			(effects
				(font
					(size 0.7 0.7)
					(thickness 0.15)
				)
				(justify right bottom mirror)
			)
		)
		(property "Value" "FB_120Z_2A_Murata-BLM18PG_0603"
			(at 0 -1.7 90)
			(layer "B.Fab")
			(effects
				(font
					(size 0.7 0.7)
					(thickness 0.15)
				)
				(justify right bottom mirror)
			)
		)
		(property "Datasheet" "https://www.murata.com/en-us/products/productdata/8796738650142/ENFA0003.pdf"
			(at 0 0 90)
			(layer "F.Fab")
			(hide yes)
			(effects
				(font
					(size 1.27 1.27)
					(thickness 0.15)
				)
			)
		)
		(property "Description" "Ferrite Bead, 0603 [1608 Metric], 120 ohm, 2 A, BLM18P, 0.05 ohm, ± 25%, DC power line"
			(at 0 0 90)
			(layer "F.Fab")
			(hide yes)
			(effects
				(font
					(size 1.27 1.27)
					(thickness 0.15)
				)
			)
		)
		(property "Author" "Antmicro"
			(at 190.13 -9.19 0)
			(layer "B.Fab")
			(hide yes)
			(effects
				(font
					(size 1 1)
					(thickness 0.15)
				)
				(justify mirror)
			)
		)
		(property "Current" ""
			(at 190.13 -9.19 0)
			(layer "B.Fab")
			(hide yes)
			(effects
				(font
					(size 1 1)
					(thickness 0.15)
				)
				(justify mirror)
			)
		)
		(property "License" "Apache-2.0"
			(at 190.13 -9.19 0)
			(layer "B.Fab")
			(hide yes)
			(effects
				(font
					(size 1 1)
					(thickness 0.15)
				)
				(justify mirror)
			)
		)
		(property "MPN" "BLM18PG121SN1D"
			(at 190.13 -9.19 0)
			(layer "B.Fab")
			(hide yes)
			(effects
				(font
					(size 1 1)
					(thickness 0.15)
				)
				(justify mirror)
			)
		)
		(property "Manufacturer" "Murata"
			(at 190.13 -9.19 0)
			(layer "B.Fab")
			(hide yes)
			(effects
				(font
					(size 1 1)
					(thickness 0.15)
				)
				(justify mirror)
			)
		)
		(property "Val" "120Z/2A"
			(at 190.13 -9.19 0)
			(layer "B.Fab")
			(hide yes)
			(effects
				(font
					(size 1 1)
					(thickness 0.15)
				)
				(justify mirror)
			)
		)
		(sheetname "/Ethernet/")
		(sheetfile "ethernet.kicad_sch")
		(attr smd)
		(fp_line
			(start -0.15 -0.4)
			(end 0.15 -0.4)
			(stroke
				(width 0.15)
				(type solid)
			)
			(layer "B.SilkS")
		)
		(fp_line
			(start -0.15 0.4)
			(end 0.15 0.4)
			(stroke
				(width 0.15)
				(type solid)
			)
			(layer "B.SilkS")
		)
		(fp_rect
			(start -1.25 0.65)
			(end 1.25 -0.65)
			(stroke
				(width 0.05)
				(type solid)
			)
			(fill no)
			(layer "B.CrtYd")
		)
		(fp_line
			(start 0.8 -0.406)
			(end -0.803 -0.406)
			(stroke
				(width 0.15)
				(type solid)
			)
			(layer "B.Fab")
		)
		(fp_line
			(start -0.803 -0.406)
			(end -0.803 0.408)
			(stroke
				(width 0.15)
				(type solid)
			)
			(layer "B.Fab")
		)
		(fp_line
			(start 0.8 0.408)
			(end 0.8 -0.406)
			(stroke
				(width 0.15)
				(type solid)
			)
			(layer "B.Fab")
		)
		(fp_line
			(start 0.8 0.408)
			(end -0.803 0.408)
			(stroke
				(width 0.15)
				(type solid)
			)
			(layer "B.Fab")
		)
		(pad "1" smd roundrect
			(at -0.7 0 90)
			(size 0.8 1)
			(layers "B.Cu" "B.Mask" "B.Paste")
			(roundrect_rratio 0.2)
			(net 405 "/Ethernet/AVDDL")
			(pintype "passive")
		)
		(pad "2" smd roundrect
			(at 0.7 0 90)
			(size 0.8 1)
			(layers "B.Cu" "B.Mask" "B.Paste")
			(roundrect_rratio 0.2)
			(net 339 "VCC1V2")
			(pintype "passive")
		)
	)
	(footprint "antmicro-footprints:R_0402_1005Metric"
		(layer "B.Cu")
		(at 102.6 102.9 -90)
		(descr "Resistor SMD 0402")
		(tags "resistor SMD 0402")
		(property "Reference" "R127"
			(at 0.7 -0.35 90)
			(layer "B.SilkS")
			(effects
				(font
					(size 0.7 0.7)
					(thickness 0.15)
				)
				(justify left bottom mirror)
			)
		)
		(property "Value" "R_10k2_0402"
			(at 0 -1.4 90)
			(layer "B.Fab")
			(effects
				(font
					(size 0.7 0.7)
					(thickness 0.15)
				)
				(justify left bottom mirror)
			)
		)
		(property "Datasheet" "https://www.bourns.com/docs/product-datasheets/cr.pdf"
			(at 0 0 270)
			(layer "F.Fab")
			(hide yes)
			(effects
				(font
					(size 1.27 1.27)
					(thickness 0.15)
				)
			)
		)
		(property "Description" "SMD Chip Resistor"
			(at 0 0 270)
			(layer "F.Fab")
			(hide yes)
			(effects
				(font
					(size 1.27 1.27)
					(thickness 0.15)
				)
			)
		)
		(property "Author" "Antmicro"
			(at -0.3 205.5 0)
			(layer "B.Fab")
			(hide yes)
			(effects
				(font
					(size 1 1)
					(thickness 0.15)
				)
				(justify mirror)
			)
		)
		(property "License" "Apache-2.0"
			(at -0.3 205.5 0)
			(layer "B.Fab")
			(hide yes)
			(effects
				(font
					(size 1 1)
					(thickness 0.15)
				)
				(justify mirror)
			)
		)
		(property "MPN" "CR0402-FX-1022GLF"
			(at -0.3 205.5 0)
			(layer "B.Fab")
			(hide yes)
			(effects
				(font
					(size 1 1)
					(thickness 0.15)
				)
				(justify mirror)
			)
		)
		(property "Manufacturer" "Bourns"
			(at -0.3 205.5 0)
			(layer "B.Fab")
			(hide yes)
			(effects
				(font
					(size 1 1)
					(thickness 0.15)
				)
				(justify mirror)
			)
		)
		(property "Tolerance" "1%"
			(at -0.3 205.5 0)
			(layer "B.Fab")
			(hide yes)
			(effects
				(font
					(size 1 1)
					(thickness 0.15)
				)
				(justify mirror)
			)
		)
		(property "Val" "10k2"
			(at -0.3 205.5 0)
			(layer "B.Fab")
			(hide yes)
			(effects
				(font
					(size 1 1)
					(thickness 0.15)
				)
				(justify mirror)
			)
		)
		(sheetname "/Ethernet/")
		(sheetfile "ethernet.kicad_sch")
		(attr smd)
		(fp_rect
			(start -0.925 0.47)
			(end 0.925 -0.47)
			(stroke
				(width 0.05)
				(type default)
			)
			(fill no)
			(layer "B.CrtYd")
		)
		(fp_rect
			(start -0.5 0.25)
			(end 0.5 -0.25)
			(stroke
				(width 0.15)
				(type solid)
			)
			(fill no)
			(layer "B.Fab")
		)
		(pad "1" smd roundrect
			(at -0.48 0 270)
			(size 0.59 0.64)
			(layers "B.Cu" "B.Mask" "B.Paste")
			(roundrect_rratio 0.25)
			(net 407 "RGMII_RXD0")
			(pintype "passive")
		)
		(pad "2" smd roundrect
			(at 0.48 0 270)
			(size 0.59 0.64)
			(layers "B.Cu" "B.Mask" "B.Paste")
			(roundrect_rratio 0.25)
			(net 2 "VCC3V3")
			(pintype "passive")
		)
	)
	(footprint "antmicro-footprints:R_0402_1005Metric"
		(layer "B.Cu")
		(at 101.65 102.9 -90)
		(descr "Resistor SMD 0402")
		(tags "resistor SMD 0402")
		(property "Reference" "R148"
			(at 0.7 -0.35 90)
			(layer "B.SilkS")
			(effects
				(font
					(size 0.7 0.7)
					(thickness 0.15)
				)
				(justify left bottom mirror)
			)
		)
		(property "Value" "R_10k2_0402"
			(at 0 -1.4 90)
			(layer "B.Fab")
			(effects
				(font
					(size 0.7 0.7)
					(thickness 0.15)
				)
				(justify left bottom mirror)
			)
		)
		(property "Datasheet" "https://www.bourns.com/docs/product-datasheets/cr.pdf"
			(at 0 0 270)
			(layer "F.Fab")
			(hide yes)
			(effects
				(font
					(size 1.27 1.27)
					(thickness 0.15)
				)
			)
		)
		(property "Description" "SMD Chip Resistor"
			(at 0 0 270)
			(layer "F.Fab")
			(hide yes)
			(effects
				(font
					(size 1.27 1.27)
					(thickness 0.15)
				)
			)
		)
		(property "Author" "Antmicro"
			(at -1.25 204.55 0)
			(layer "B.Fab")
			(hide yes)
			(effects
				(font
					(size 1 1)
					(thickness 0.15)
				)
				(justify mirror)
			)
		)
		(property "License" "Apache-2.0"
			(at -1.25 204.55 0)
			(layer "B.Fab")
			(hide yes)
			(effects
				(font
					(size 1 1)
					(thickness 0.15)
				)
				(justify mirror)
			)
		)
		(property "MPN" "CR0402-FX-1022GLF"
			(at -1.25 204.55 0)
			(layer "B.Fab")
			(hide yes)
			(effects
				(font
					(size 1 1)
					(thickness 0.15)
				)
				(justify mirror)
			)
		)
		(property "Manufacturer" "Bourns"
			(at -1.25 204.55 0)
			(layer "B.Fab")
			(hide yes)
			(effects
				(font
					(size 1 1)
					(thickness 0.15)
				)
				(justify mirror)
			)
		)
		(property "Tolerance" "1%"
			(at -1.25 204.55 0)
			(layer "B.Fab")
			(hide yes)
			(effects
				(font
					(size 1 1)
					(thickness 0.15)
				)
				(justify mirror)
			)
		)
		(property "Val" "10k2"
			(at -1.25 204.55 0)
			(layer "B.Fab")
			(hide yes)
			(effects
				(font
					(size 1 1)
					(thickness 0.15)
				)
				(justify mirror)
			)
		)
		(sheetname "/Ethernet/")
		(sheetfile "ethernet.kicad_sch")
		(attr smd)
		(fp_rect
			(start -0.925 0.47)
			(end 0.925 -0.47)
			(stroke
				(width 0.05)
				(type default)
			)
			(fill no)
			(layer "B.CrtYd")
		)
		(fp_rect
			(start -0.5 0.25)
			(end 0.5 -0.25)
			(stroke
				(width 0.15)
				(type solid)
			)
			(fill no)
			(layer "B.Fab")
		)
		(pad "1" smd roundrect
			(at -0.48 0 270)
			(size 0.59 0.64)
			(layers "B.Cu" "B.Mask" "B.Paste")
			(roundrect_rratio 0.25)
			(net 408 "RGMII_RXD1")
			(pintype "passive")
		)
		(pad "2" smd roundrect
			(at 0.48 0 270)
			(size 0.59 0.64)
			(layers "B.Cu" "B.Mask" "B.Paste")
			(roundrect_rratio 0.25)
			(net 2 "VCC3V3")
			(pintype "passive")
		)
	)
	(footprint "antmicro-footprints:R_0402_1005Metric"
		(layer "B.Cu")
		(at 100.7 102.9 -90)
		(descr "Resistor SMD 0402")
		(tags "resistor SMD 0402")
		(property "Reference" "R149"
			(at 0.7 -0.35 90)
			(layer "B.SilkS")
			(effects
				(font
					(size 0.7 0.7)
					(thickness 0.15)
				)
				(justify left bottom mirror)
			)
		)
		(property "Value" "R_10k2_0402"
			(at 0 -1.4 90)
			(layer "B.Fab")
			(effects
				(font
					(size 0.7 0.7)
					(thickness 0.15)
				)
				(justify left bottom mirror)
			)
		)
		(property "Datasheet" "https://www.bourns.com/docs/product-datasheets/cr.pdf"
			(at 0 0 270)
			(layer "F.Fab")
			(hide yes)
			(effects
				(font
					(size 1.27 1.27)
					(thickness 0.15)
				)
			)
		)
		(property "Description" "SMD Chip Resistor"
			(at 0 0 270)
			(layer "F.Fab")
			(hide yes)
			(effects
				(font
					(size 1.27 1.27)
					(thickness 0.15)
				)
			)
		)
		(property "Author" "Antmicro"
			(at -2.2 203.6 0)
			(layer "B.Fab")
			(hide yes)
			(effects
				(font
					(size 1 1)
					(thickness 0.15)
				)
				(justify mirror)
			)
		)
		(property "License" "Apache-2.0"
			(at -2.2 203.6 0)
			(layer "B.Fab")
			(hide yes)
			(effects
				(font
					(size 1 1)
					(thickness 0.15)
				)
				(justify mirror)
			)
		)
		(property "MPN" "CR0402-FX-1022GLF"
			(at -2.2 203.6 0)
			(layer "B.Fab")
			(hide yes)
			(effects
				(font
					(size 1 1)
					(thickness 0.15)
				)
				(justify mirror)
			)
		)
		(property "Manufacturer" "Bourns"
			(at -2.2 203.6 0)
			(layer "B.Fab")
			(hide yes)
			(effects
				(font
					(size 1 1)
					(thickness 0.15)
				)
				(justify mirror)
			)
		)
		(property "Tolerance" "1%"
			(at -2.2 203.6 0)
			(layer "B.Fab")
			(hide yes)
			(effects
				(font
					(size 1 1)
					(thickness 0.15)
				)
				(justify mirror)
			)
		)
		(property "Val" "10k2"
			(at -2.2 203.6 0)
			(layer "B.Fab")
			(hide yes)
			(effects
				(font
					(size 1 1)
					(thickness 0.15)
				)
				(justify mirror)
			)
		)
		(sheetname "/Ethernet/")
		(sheetfile "ethernet.kicad_sch")
		(attr smd)
		(fp_rect
			(start -0.925 0.47)
			(end 0.925 -0.47)
			(stroke
				(width 0.05)
				(type default)
			)
			(fill no)
			(layer "B.CrtYd")
		)
		(fp_rect
			(start -0.5 0.25)
			(end 0.5 -0.25)
			(stroke
				(width 0.15)
				(type solid)
			)
			(fill no)
			(layer "B.Fab")
		)
		(pad "1" smd roundrect
			(at -0.48 0 270)
			(size 0.59 0.64)
			(layers "B.Cu" "B.Mask" "B.Paste")
			(roundrect_rratio 0.25)
			(net 409 "RGMII_RXD2")
			(pintype "passive")
		)
		(pad "2" smd roundrect
			(at 0.48 0 270)
			(size 0.59 0.64)
			(layers "B.Cu" "B.Mask" "B.Paste")
			(roundrect_rratio 0.25)
			(net 2 "VCC3V3")
			(pintype "passive")
		)
	)
	(footprint "antmicro-footprints:R_0402_1005Metric"
		(layer "B.Cu")
		(at 99.75 102.9 -90)
		(descr "Resistor SMD 0402")
		(tags "resistor SMD 0402")
		(property "Reference" "R150"
			(at 0.7 -0.35 90)
			(layer "B.SilkS")
			(effects
				(font
					(size 0.7 0.7)
					(thickness 0.15)
				)
				(justify left bottom mirror)
			)
		)
		(property "Value" "R_10k2_0402"
			(at 0 -1.4 90)
			(layer "B.Fab")
			(effects
				(font
					(size 0.7 0.7)
					(thickness 0.15)
				)
				(justify left bottom mirror)
			)
		)
		(property "Datasheet" "https://www.bourns.com/docs/product-datasheets/cr.pdf"
			(at 0 0 270)
			(layer "F.Fab")
			(hide yes)
			(effects
				(font
					(size 1.27 1.27)
					(thickness 0.15)
				)
			)
		)
		(property "Description" "SMD Chip Resistor"
			(at 0 0 270)
			(layer "F.Fab")
			(hide yes)
			(effects
				(font
					(size 1.27 1.27)
					(thickness 0.15)
				)
			)
		)
		(property "Author" "Antmicro"
			(at -3.15 202.65 0)
			(layer "B.Fab")
			(hide yes)
			(effects
				(font
					(size 1 1)
					(thickness 0.15)
				)
				(justify mirror)
			)
		)
		(property "License" "Apache-2.0"
			(at -3.15 202.65 0)
			(layer "B.Fab")
			(hide yes)
			(effects
				(font
					(size 1 1)
					(thickness 0.15)
				)
				(justify mirror)
			)
		)
		(property "MPN" "CR0402-FX-1022GLF"
			(at -3.15 202.65 0)
			(layer "B.Fab")
			(hide yes)
			(effects
				(font
					(size 1 1)
					(thickness 0.15)
				)
				(justify mirror)
			)
		)
		(property "Manufacturer" "Bourns"
			(at -3.15 202.65 0)
			(layer "B.Fab")
			(hide yes)
			(effects
				(font
					(size 1 1)
					(thickness 0.15)
				)
				(justify mirror)
			)
		)
		(property "Tolerance" "1%"
			(at -3.15 202.65 0)
			(layer "B.Fab")
			(hide yes)
			(effects
				(font
					(size 1 1)
					(thickness 0.15)
				)
				(justify mirror)
			)
		)
		(property "Val" "10k2"
			(at -3.15 202.65 0)
			(layer "B.Fab")
			(hide yes)
			(effects
				(font
					(size 1 1)
					(thickness 0.15)
				)
				(justify mirror)
			)
		)
		(sheetname "/Ethernet/")
		(sheetfile "ethernet.kicad_sch")
		(attr smd)
		(fp_rect
			(start -0.925 0.47)
			(end 0.925 -0.47)
			(stroke
				(width 0.05)
				(type default)
			)
			(fill no)
			(layer "B.CrtYd")
		)
		(fp_rect
			(start -0.5 0.25)
			(end 0.5 -0.25)
			(stroke
				(width 0.15)
				(type solid)
			)
			(fill no)
			(layer "B.Fab")
		)
		(pad "1" smd roundrect
			(at -0.48 0 270)
			(size 0.59 0.64)
			(layers "B.Cu" "B.Mask" "B.Paste")
			(roundrect_rratio 0.25)
			(net 410 "RGMII_RXD3")
			(pintype "passive")
		)
		(pad "2" smd roundrect
			(at 0.48 0 270)
			(size 0.59 0.64)
			(layers "B.Cu" "B.Mask" "B.Paste")
			(roundrect_rratio 0.25)
			(net 2 "VCC3V3")
			(pintype "passive")
		)
	)
	(footprint "antmicro-footprints:R_0402_1005Metric"
		(layer "B.Cu")
		(at 103.55 102.9 -90)
		(descr "Resistor SMD 0402")
		(tags "resistor SMD 0402")
		(property "Reference" "R151"
			(at 0.7 -0.35 90)
			(layer "B.SilkS")
			(effects
				(font
					(size 0.7 0.7)
					(thickness 0.15)
				)
				(justify left bottom mirror)
			)
		)
		(property "Value" "R_10k2_0402"
			(at 0 -1.4 90)
			(layer "B.Fab")
			(effects
				(font
					(size 0.7 0.7)
					(thickness 0.15)
				)
				(justify left bottom mirror)
			)
		)
		(property "Datasheet" "https://www.bourns.com/docs/product-datasheets/cr.pdf"
			(at 0 0 270)
			(layer "F.Fab")
			(hide yes)
			(effects
				(font
					(size 1.27 1.27)
					(thickness 0.15)
				)
			)
		)
		(property "Description" "SMD Chip Resistor"
			(at 0 0 270)
			(layer "F.Fab")
			(hide yes)
			(effects
				(font
					(size 1.27 1.27)
					(thickness 0.15)
				)
			)
		)
		(property "Author" "Antmicro"
			(at 0.65 206.45 0)
			(layer "B.Fab")
			(hide yes)
			(effects
				(font
					(size 1 1)
					(thickness 0.15)
				)
				(justify mirror)
			)
		)
		(property "License" "Apache-2.0"
			(at 0.65 206.45 0)
			(layer "B.Fab")
			(hide yes)
			(effects
				(font
					(size 1 1)
					(thickness 0.15)
				)
				(justify mirror)
			)
		)
		(property "MPN" "CR0402-FX-1022GLF"
			(at 0.65 206.45 0)
			(layer "B.Fab")
			(hide yes)
			(effects
				(font
					(size 1 1)
					(thickness 0.15)
				)
				(justify mirror)
			)
		)
		(property "Manufacturer" "Bourns"
			(at 0.65 206.45 0)
			(layer "B.Fab")
			(hide yes)
			(effects
				(font
					(size 1 1)
					(thickness 0.15)
				)
				(justify mirror)
			)
		)
		(property "Tolerance" "1%"
			(at 0.65 206.45 0)
			(layer "B.Fab")
			(hide yes)
			(effects
				(font
					(size 1 1)
					(thickness 0.15)
				)
				(justify mirror)
			)
		)
		(property "Val" "10k2"
			(at 0.65 206.45 0)
			(layer "B.Fab")
			(hide yes)
			(effects
				(font
					(size 1 1)
					(thickness 0.15)
				)
				(justify mirror)
			)
		)
		(sheetname "/Ethernet/")
		(sheetfile "ethernet.kicad_sch")
		(attr smd)
		(fp_rect
			(start -0.925 0.47)
			(end 0.925 -0.47)
			(stroke
				(width 0.05)
				(type default)
			)
			(fill no)
			(layer "B.CrtYd")
		)
		(fp_rect
			(start -0.5 0.25)
			(end 0.5 -0.25)
			(stroke
				(width 0.15)
				(type solid)
			)
			(fill no)
			(layer "B.Fab")
		)
		(pad "1" smd roundrect
			(at -0.48 0 270)
			(size 0.59 0.64)
			(layers "B.Cu" "B.Mask" "B.Paste")
			(roundrect_rratio 0.25)
			(net 411 "RGMII_RX_DV")
			(pintype "passive")
		)
		(pad "2" smd roundrect
			(at 0.48 0 270)
			(size 0.59 0.64)
			(layers "B.Cu" "B.Mask" "B.Paste")
			(roundrect_rratio 0.25)
			(net 2 "VCC3V3")
			(pintype "passive")
		)
	)
	(footprint "antmicro-footprints:R_0402_1005Metric"
		(layer "B.Cu")
		(at 104.5 102.9 -90)
		(descr "Resistor SMD 0402")
		(tags "resistor SMD 0402")
		(property "Reference" "R152"
			(at 0.7 -0.35 90)
			(layer "B.SilkS")
			(effects
				(font
					(size 0.7 0.7)
					(thickness 0.15)
				)
				(justify left bottom mirror)
			)
		)
		(property "Value" "R_10k2_0402"
			(at 0 -1.4 90)
			(layer "B.Fab")
			(effects
				(font
					(size 0.7 0.7)
					(thickness 0.15)
				)
				(justify left bottom mirror)
			)
		)
		(property "Datasheet" "https://www.bourns.com/docs/product-datasheets/cr.pdf"
			(at 0 0 270)
			(layer "F.Fab")
			(hide yes)
			(effects
				(font
					(size 1.27 1.27)
					(thickness 0.15)
				)
			)
		)
		(property "Description" "SMD Chip Resistor"
			(at 0 0 270)
			(layer "F.Fab")
			(hide yes)
			(effects
				(font
					(size 1.27 1.27)
					(thickness 0.15)
				)
			)
		)
		(property "Author" "Antmicro"
			(at 1.6 207.4 0)
			(layer "B.Fab")
			(hide yes)
			(effects
				(font
					(size 1 1)
					(thickness 0.15)
				)
				(justify mirror)
			)
		)
		(property "License" "Apache-2.0"
			(at 1.6 207.4 0)
			(layer "B.Fab")
			(hide yes)
			(effects
				(font
					(size 1 1)
					(thickness 0.15)
				)
				(justify mirror)
			)
		)
		(property "MPN" "CR0402-FX-1022GLF"
			(at 1.6 207.4 0)
			(layer "B.Fab")
			(hide yes)
			(effects
				(font
					(size 1 1)
					(thickness 0.15)
				)
				(justify mirror)
			)
		)
		(property "Manufacturer" "Bourns"
			(at 1.6 207.4 0)
			(layer "B.Fab")
			(hide yes)
			(effects
				(font
					(size 1 1)
					(thickness 0.15)
				)
				(justify mirror)
			)
		)
		(property "Tolerance" "1%"
			(at 1.6 207.4 0)
			(layer "B.Fab")
			(hide yes)
			(effects
				(font
					(size 1 1)
					(thickness 0.15)
				)
				(justify mirror)
			)
		)
		(property "Val" "10k2"
			(at 1.6 207.4 0)
			(layer "B.Fab")
			(hide yes)
			(effects
				(font
					(size 1 1)
					(thickness 0.15)
				)
				(justify mirror)
			)
		)
		(sheetname "/Ethernet/")
		(sheetfile "ethernet.kicad_sch")
		(attr smd)
		(fp_rect
			(start -0.925 0.47)
			(end 0.925 -0.47)
			(stroke
				(width 0.05)
				(type default)
			)
			(fill no)
			(layer "B.CrtYd")
		)
		(fp_rect
			(start -0.5 0.25)
			(end 0.5 -0.25)
			(stroke
				(width 0.15)
				(type solid)
			)
			(fill no)
			(layer "B.Fab")
		)
		(pad "1" smd roundrect
			(at -0.48 0 270)
			(size 0.59 0.64)
			(layers "B.Cu" "B.Mask" "B.Paste")
			(roundrect_rratio 0.25)
			(net 412 "RGMII_RX_CLK")
			(pintype "passive")
		)
		(pad "2" smd roundrect
			(at 0.48 0 270)
			(size 0.59 0.64)
			(layers "B.Cu" "B.Mask" "B.Paste")
			(roundrect_rratio 0.25)
			(net 2 "VCC3V3")
			(pintype "passive")
		)
	)
	(footprint "antmicro-footprints:R_0402_1005Metric"
		(layer "B.Cu")
		(at 107.35 102.9 -90)
		(descr "Resistor SMD 0402")
		(tags "resistor SMD 0402")
		(property "Reference" "R153"
			(at 0.7 -0.35 90)
			(layer "B.SilkS")
			(effects
				(font
					(size 0.7 0.7)
					(thickness 0.15)
				)
				(justify left bottom mirror)
			)
		)
		(property "Value" "R_10k2_0402"
			(at 0 -1.4 90)
			(layer "B.Fab")
			(effects
				(font
					(size 0.7 0.7)
					(thickness 0.15)
				)
				(justify left bottom mirror)
			)
		)
		(property "Datasheet" "https://www.bourns.com/docs/product-datasheets/cr.pdf"
			(at 0 0 270)
			(layer "F.Fab")
			(hide yes)
			(effects
				(font
					(size 1.27 1.27)
					(thickness 0.15)
				)
			)
		)
		(property "Description" "SMD Chip Resistor"
			(at 0 0 270)
			(layer "F.Fab")
			(hide yes)
			(effects
				(font
					(size 1.27 1.27)
					(thickness 0.15)
				)
			)
		)
		(property "Author" "Antmicro"
			(at 4.45 210.25 0)
			(layer "B.Fab")
			(hide yes)
			(effects
				(font
					(size 1 1)
					(thickness 0.15)
				)
				(justify mirror)
			)
		)
		(property "License" "Apache-2.0"
			(at 4.45 210.25 0)
			(layer "B.Fab")
			(hide yes)
			(effects
				(font
					(size 1 1)
					(thickness 0.15)
				)
				(justify mirror)
			)
		)
		(property "MPN" "CR0402-FX-1022GLF"
			(at 4.45 210.25 0)
			(layer "B.Fab")
			(hide yes)
			(effects
				(font
					(size 1 1)
					(thickness 0.15)
				)
				(justify mirror)
			)
		)
		(property "Manufacturer" "Bourns"
			(at 4.45 210.25 0)
			(layer "B.Fab")
			(hide yes)
			(effects
				(font
					(size 1 1)
					(thickness 0.15)
				)
				(justify mirror)
			)
		)
		(property "Tolerance" "1%"
			(at 4.45 210.25 0)
			(layer "B.Fab")
			(hide yes)
			(effects
				(font
					(size 1 1)
					(thickness 0.15)
				)
				(justify mirror)
			)
		)
		(property "Val" "10k2"
			(at 4.45 210.25 0)
			(layer "B.Fab")
			(hide yes)
			(effects
				(font
					(size 1 1)
					(thickness 0.15)
				)
				(justify mirror)
			)
		)
		(sheetname "/Ethernet/")
		(sheetfile "ethernet.kicad_sch")
		(attr smd)
		(fp_rect
			(start -0.925 0.47)
			(end 0.925 -0.47)
			(stroke
				(width 0.05)
				(type default)
			)
			(fill no)
			(layer "B.CrtYd")
		)
		(fp_rect
			(start -0.5 0.25)
			(end 0.5 -0.25)
			(stroke
				(width 0.15)
				(type solid)
			)
			(fill no)
			(layer "B.Fab")
		)
		(pad "1" smd roundrect
			(at -0.48 0 270)
			(size 0.59 0.64)
			(layers "B.Cu" "B.Mask" "B.Paste")
			(roundrect_rratio 0.25)
			(net 413 "RGMII_REF_CLK")
			(pintype "passive")
		)
		(pad "2" smd roundrect
			(at 0.48 0 270)
			(size 0.59 0.64)
			(layers "B.Cu" "B.Mask" "B.Paste")
			(roundrect_rratio 0.25)
			(net 2 "VCC3V3")
			(pintype "passive")
		)
	)
	(footprint "antmicro-footprints:R_0402_1005Metric"
		(layer "B.Cu")
		(at 106.4 102.9 -90)
		(descr "Resistor SMD 0402")
		(tags "resistor SMD 0402")
		(property "Reference" "R155"
			(at 0.7 -0.35 90)
			(layer "B.SilkS")
			(effects
				(font
					(size 0.7 0.7)
					(thickness 0.15)
				)
				(justify left bottom mirror)
			)
		)
		(property "Value" "R_4k7_0402"
			(at 0 -1.4 90)
			(layer "B.Fab")
			(effects
				(font
					(size 0.7 0.7)
					(thickness 0.15)
				)
				(justify left bottom mirror)
			)
		)
		(property "Datasheet" "https://www.bourns.com/docs/product-datasheets/cr.pdf"
			(at 0 0 270)
			(layer "F.Fab")
			(hide yes)
			(effects
				(font
					(size 1.27 1.27)
					(thickness 0.15)
				)
			)
		)
		(property "Description" "SMD Chip Resistor, 4.7 kohm, ± 1%, 62.5 mW, 0402 [1005 Metric], Thick Film, General Purpose"
			(at 0 0 270)
			(layer "F.Fab")
			(hide yes)
			(effects
				(font
					(size 1.27 1.27)
					(thickness 0.15)
				)
			)
		)
		(property "Author" "Antmicro"
			(at 3.5 209.3 0)
			(layer "B.Fab")
			(hide yes)
			(effects
				(font
					(size 1 1)
					(thickness 0.15)
				)
				(justify mirror)
			)
		)
		(property "License" "Apache-2.0"
			(at 3.5 209.3 0)
			(layer "B.Fab")
			(hide yes)
			(effects
				(font
					(size 1 1)
					(thickness 0.15)
				)
				(justify mirror)
			)
		)
		(property "MPN" "CR0402-FX-4701GLF"
			(at 3.5 209.3 0)
			(layer "B.Fab")
			(hide yes)
			(effects
				(font
					(size 1 1)
					(thickness 0.15)
				)
				(justify mirror)
			)
		)
		(property "Manufacturer" "Bourns"
			(at 3.5 209.3 0)
			(layer "B.Fab")
			(hide yes)
			(effects
				(font
					(size 1 1)
					(thickness 0.15)
				)
				(justify mirror)
			)
		)
		(property "Tolerance" "1%"
			(at 3.5 209.3 0)
			(layer "B.Fab")
			(hide yes)
			(effects
				(font
					(size 1 1)
					(thickness 0.15)
				)
				(justify mirror)
			)
		)
		(property "Val" "4k7"
			(at 3.5 209.3 0)
			(layer "B.Fab")
			(hide yes)
			(effects
				(font
					(size 1 1)
					(thickness 0.15)
				)
				(justify mirror)
			)
		)
		(sheetname "/Ethernet/")
		(sheetfile "ethernet.kicad_sch")
		(attr smd)
		(fp_rect
			(start -0.925 0.47)
			(end 0.925 -0.47)
			(stroke
				(width 0.05)
				(type default)
			)
			(fill no)
			(layer "B.CrtYd")
		)
		(fp_rect
			(start -0.5 0.25)
			(end 0.5 -0.25)
			(stroke
				(width 0.15)
				(type solid)
			)
			(fill no)
			(layer "B.Fab")
		)
		(pad "1" smd roundrect
			(at -0.48 0 270)
			(size 0.59 0.64)
			(layers "B.Cu" "B.Mask" "B.Paste")
			(roundrect_rratio 0.25)
			(net 142 "ETH_MDIO")
			(pintype "passive")
		)
		(pad "2" smd roundrect
			(at 0.48 0 270)
			(size 0.59 0.64)
			(layers "B.Cu" "B.Mask" "B.Paste")
			(roundrect_rratio 0.25)
			(net 2 "VCC3V3")
			(pintype "passive")
		)
	)
	(footprint "antmicro-footprints:C_0402_1005Metric"
		(layer "B.Cu")
		(at 110.78 86.955 90)
		(descr "Capacitor SMD 0402")
		(tags "capacitor SMD 0402")
		(property "Reference" "C225"
			(at -1.045 2.32 90)
			(layer "B.SilkS")
			(effects
				(font
					(size 0.7 0.7)
					(thickness 0.15)
				)
				(justify right bottom mirror)
			)
		)
		(property "Value" "C_100n_0402"
			(at 0 -1.4 90)
			(layer "B.Fab")
			(effects
				(font
					(size 0.7 0.7)
					(thickness 0.15)
				)
				(justify right bottom mirror)
			)
		)
		(property "Datasheet" "https://www.murata.com/products/productdetail?partno=GRM155R61H104KE14%23"
			(at 0 0 90)
			(layer "F.Fab")
			(hide yes)
			(effects
				(font
					(size 1.27 1.27)
					(thickness 0.15)
				)
			)
		)
		(property "Description" "SMD Multilayer Ceramic Capacitor, 0.1 µF, 50 V, 0402 [1005 Metric], ± 10%, X5R, GRM Series"
			(at 0 0 90)
			(layer "F.Fab")
			(hide yes)
			(effects
				(font
					(size 1.27 1.27)
					(thickness 0.15)
				)
			)
		)
		(property "Author" "Antmicro"
			(at 197.735 -23.825 0)
			(layer "B.Fab")
			(hide yes)
			(effects
				(font
					(size 1 1)
					(thickness 0.15)
				)
				(justify mirror)
			)
		)
		(property "Dielectric" "X5R"
			(at 197.735 -23.825 0)
			(layer "B.Fab")
			(hide yes)
			(effects
				(font
					(size 1 1)
					(thickness 0.15)
				)
				(justify mirror)
			)
		)
		(property "License" "Apache-2.0"
			(at 197.735 -23.825 0)
			(layer "B.Fab")
			(hide yes)
			(effects
				(font
					(size 1 1)
					(thickness 0.15)
				)
				(justify mirror)
			)
		)
		(property "MPN" "GRM155R61H104KE14D"
			(at 197.735 -23.825 0)
			(layer "B.Fab")
			(hide yes)
			(effects
				(font
					(size 1 1)
					(thickness 0.15)
				)
				(justify mirror)
			)
		)
		(property "Manufacturer" "Murata"
			(at 197.735 -23.825 0)
			(layer "B.Fab")
			(hide yes)
			(effects
				(font
					(size 1 1)
					(thickness 0.15)
				)
				(justify mirror)
			)
		)
		(property "Val" "100n"
			(at 197.735 -23.825 0)
			(layer "B.Fab")
			(hide yes)
			(effects
				(font
					(size 1 1)
					(thickness 0.15)
				)
				(justify mirror)
			)
		)
		(property "Voltage" "50V"
			(at 197.735 -23.825 0)
			(layer "B.Fab")
			(hide yes)
			(effects
				(font
					(size 1 1)
					(thickness 0.15)
				)
				(justify mirror)
			)
		)
		(sheetname "/Ethernet/")
		(sheetfile "ethernet.kicad_sch")
		(attr smd)
		(fp_rect
			(start -0.925 0.47)
			(end 0.925 -0.47)
			(stroke
				(width 0.05)
				(type default)
			)
			(fill no)
			(layer "B.CrtYd")
		)
		(fp_line
			(start 0.504 -0.248)
			(end -0.494 -0.248)
			(stroke
				(width 0.15)
				(type solid)
			)
			(layer "B.Fab")
		)
		(fp_line
			(start -0.494 -0.248)
			(end -0.494 0.25)
			(stroke
				(width 0.15)
				(type solid)
			)
			(layer "B.Fab")
		)
		(fp_line
			(start 0.504 0.25)
			(end 0.504 -0.248)
			(stroke
				(width 0.15)
				(type solid)
			)
			(layer "B.Fab")
		)
		(fp_line
			(start -0.494 0.25)
			(end 0.504 0.25)
			(stroke
				(width 0.15)
				(type solid)
			)
			(layer "B.Fab")
		)
		(pad "1" smd roundrect
			(at -0.48 0 90)
			(size 0.59 0.64)
			(layers "B.Cu" "B.Mask" "B.Paste")
			(roundrect_rratio 0.25)
			(net 1 "GND")
			(pintype "passive")
		)
		(pad "2" smd roundrect
			(at 0.48 0 90)
			(size 0.59 0.64)
			(layers "B.Cu" "B.Mask" "B.Paste")
			(roundrect_rratio 0.25)
			(net 202 "Net-(J1-TRCT1)")
			(pintype "passive")
		)
	)
	(footprint "antmicro-footprints:C_0402_1005Metric"
		(layer "B.Cu")
		(at 111.78 86.94 90)
		(descr "Capacitor SMD 0402")
		(tags "capacitor SMD 0402")
		(property "Reference" "C226"
			(at -1.045 2.32 90)
			(layer "B.SilkS")
			(effects
				(font
					(size 0.7 0.7)
					(thickness 0.15)
				)
				(justify right bottom mirror)
			)
		)
		(property "Value" "C_100n_0402"
			(at 0 -1.4 90)
			(layer "B.Fab")
			(effects
				(font
					(size 0.7 0.7)
					(thickness 0.15)
				)
				(justify right bottom mirror)
			)
		)
		(property "Datasheet" "https://www.murata.com/products/productdetail?partno=GRM155R61H104KE14%23"
			(at 0 0 90)
			(layer "F.Fab")
			(hide yes)
			(effects
				(font
					(size 1.27 1.27)
					(thickness 0.15)
				)
			)
		)
		(property "Description" "SMD Multilayer Ceramic Capacitor, 0.1 µF, 50 V, 0402 [1005 Metric], ± 10%, X5R, GRM Series"
			(at 0 0 90)
			(layer "F.Fab")
			(hide yes)
			(effects
				(font
					(size 1.27 1.27)
					(thickness 0.15)
				)
			)
		)
		(property "Author" "Antmicro"
			(at 198.72 -24.84 0)
			(layer "B.Fab")
			(hide yes)
			(effects
				(font
					(size 1 1)
					(thickness 0.15)
				)
				(justify mirror)
			)
		)
		(property "Dielectric" "X5R"
			(at 198.72 -24.84 0)
			(layer "B.Fab")
			(hide yes)
			(effects
				(font
					(size 1 1)
					(thickness 0.15)
				)
				(justify mirror)
			)
		)
		(property "License" "Apache-2.0"
			(at 198.72 -24.84 0)
			(layer "B.Fab")
			(hide yes)
			(effects
				(font
					(size 1 1)
					(thickness 0.15)
				)
				(justify mirror)
			)
		)
		(property "MPN" "GRM155R61H104KE14D"
			(at 198.72 -24.84 0)
			(layer "B.Fab")
			(hide yes)
			(effects
				(font
					(size 1 1)
					(thickness 0.15)
				)
				(justify mirror)
			)
		)
		(property "Manufacturer" "Murata"
			(at 198.72 -24.84 0)
			(layer "B.Fab")
			(hide yes)
			(effects
				(font
					(size 1 1)
					(thickness 0.15)
				)
				(justify mirror)
			)
		)
		(property "Val" "100n"
			(at 198.72 -24.84 0)
			(layer "B.Fab")
			(hide yes)
			(effects
				(font
					(size 1 1)
					(thickness 0.15)
				)
				(justify mirror)
			)
		)
		(property "Voltage" "50V"
			(at 198.72 -24.84 0)
			(layer "B.Fab")
			(hide yes)
			(effects
				(font
					(size 1 1)
					(thickness 0.15)
				)
				(justify mirror)
			)
		)
		(sheetname "/Ethernet/")
		(sheetfile "ethernet.kicad_sch")
		(attr smd)
		(fp_rect
			(start -0.925 0.47)
			(end 0.925 -0.47)
			(stroke
				(width 0.05)
				(type default)
			)
			(fill no)
			(layer "B.CrtYd")
		)
		(fp_line
			(start 0.504 -0.248)
			(end -0.494 -0.248)
			(stroke
				(width 0.15)
				(type solid)
			)
			(layer "B.Fab")
		)
		(fp_line
			(start -0.494 -0.248)
			(end -0.494 0.25)
			(stroke
				(width 0.15)
				(type solid)
			)
			(layer "B.Fab")
		)
		(fp_line
			(start 0.504 0.25)
			(end 0.504 -0.248)
			(stroke
				(width 0.15)
				(type solid)
			)
			(layer "B.Fab")
		)
		(fp_line
			(start -0.494 0.25)
			(end 0.504 0.25)
			(stroke
				(width 0.15)
				(type solid)
			)
			(layer "B.Fab")
		)
		(pad "1" smd roundrect
			(at -0.48 0 90)
			(size 0.59 0.64)
			(layers "B.Cu" "B.Mask" "B.Paste")
			(roundrect_rratio 0.25)
			(net 1 "GND")
			(pintype "passive")
		)
		(pad "2" smd roundrect
			(at 0.48 0 90)
			(size 0.59 0.64)
			(layers "B.Cu" "B.Mask" "B.Paste")
			(roundrect_rratio 0.25)
			(net 203 "Net-(J1-TRCT2)")
			(pintype "passive")
		)
	)
	(footprint "antmicro-footprints:C_0402_1005Metric"
		(layer "B.Cu")
		(at 97.57 87.005 90)
		(descr "Capacitor SMD 0402")
		(tags "capacitor SMD 0402")
		(property "Reference" "C227"
			(at 1.005 -1.07 90)
			(layer "B.SilkS")
			(effects
				(font
					(size 0.7 0.7)
					(thickness 0.15)
				)
				(justify right bottom mirror)
			)
		)
		(property "Value" "C_100n_0402"
			(at 0 -1.4 90)
			(layer "B.Fab")
			(effects
				(font
					(size 0.7 0.7)
					(thickness 0.15)
				)
				(justify right bottom mirror)
			)
		)
		(property "Datasheet" "https://www.murata.com/products/productdetail?partno=GRM155R61H104KE14%23"
			(at 0 0 90)
			(layer "F.Fab")
			(hide yes)
			(effects
				(font
					(size 1.27 1.27)
					(thickness 0.15)
				)
			)
		)
		(property "Description" "SMD Multilayer Ceramic Capacitor, 0.1 µF, 50 V, 0402 [1005 Metric], ± 10%, X5R, GRM Series"
			(at 0 0 90)
			(layer "F.Fab")
			(hide yes)
			(effects
				(font
					(size 1.27 1.27)
					(thickness 0.15)
				)
			)
		)
		(property "Author" "Antmicro"
			(at 184.575 -10.565 0)
			(layer "B.Fab")
			(hide yes)
			(effects
				(font
					(size 1 1)
					(thickness 0.15)
				)
				(justify mirror)
			)
		)
		(property "Dielectric" "X5R"
			(at 184.575 -10.565 0)
			(layer "B.Fab")
			(hide yes)
			(effects
				(font
					(size 1 1)
					(thickness 0.15)
				)
				(justify mirror)
			)
		)
		(property "License" "Apache-2.0"
			(at 184.575 -10.565 0)
			(layer "B.Fab")
			(hide yes)
			(effects
				(font
					(size 1 1)
					(thickness 0.15)
				)
				(justify mirror)
			)
		)
		(property "MPN" "GRM155R61H104KE14D"
			(at 184.575 -10.565 0)
			(layer "B.Fab")
			(hide yes)
			(effects
				(font
					(size 1 1)
					(thickness 0.15)
				)
				(justify mirror)
			)
		)
		(property "Manufacturer" "Murata"
			(at 184.575 -10.565 0)
			(layer "B.Fab")
			(hide yes)
			(effects
				(font
					(size 1 1)
					(thickness 0.15)
				)
				(justify mirror)
			)
		)
		(property "Val" "100n"
			(at 184.575 -10.565 0)
			(layer "B.Fab")
			(hide yes)
			(effects
				(font
					(size 1 1)
					(thickness 0.15)
				)
				(justify mirror)
			)
		)
		(property "Voltage" "50V"
			(at 184.575 -10.565 0)
			(layer "B.Fab")
			(hide yes)
			(effects
				(font
					(size 1 1)
					(thickness 0.15)
				)
				(justify mirror)
			)
		)
		(sheetname "/Ethernet/")
		(sheetfile "ethernet.kicad_sch")
		(attr smd)
		(fp_rect
			(start -0.925 0.47)
			(end 0.925 -0.47)
			(stroke
				(width 0.05)
				(type default)
			)
			(fill no)
			(layer "B.CrtYd")
		)
		(fp_line
			(start 0.504 -0.248)
			(end -0.494 -0.248)
			(stroke
				(width 0.15)
				(type solid)
			)
			(layer "B.Fab")
		)
		(fp_line
			(start -0.494 -0.248)
			(end -0.494 0.25)
			(stroke
				(width 0.15)
				(type solid)
			)
			(layer "B.Fab")
		)
		(fp_line
			(start 0.504 0.25)
			(end 0.504 -0.248)
			(stroke
				(width 0.15)
				(type solid)
			)
			(layer "B.Fab")
		)
		(fp_line
			(start -0.494 0.25)
			(end 0.504 0.25)
			(stroke
				(width 0.15)
				(type solid)
			)
			(layer "B.Fab")
		)
		(pad "1" smd roundrect
			(at -0.48 0 90)
			(size 0.59 0.64)
			(layers "B.Cu" "B.Mask" "B.Paste")
			(roundrect_rratio 0.25)
			(net 1 "GND")
			(pintype "passive")
		)
		(pad "2" smd roundrect
			(at 0.48 0 90)
			(size 0.59 0.64)
			(layers "B.Cu" "B.Mask" "B.Paste")
			(roundrect_rratio 0.25)
			(net 204 "Net-(J1-TRCT3)")
			(pintype "passive")
		)
	)
	(footprint "antmicro-footprints:R_0402_1005Metric"
		(layer "B.Cu")
		(at 108.3 102.9 -90)
		(descr "Resistor SMD 0402")
		(tags "resistor SMD 0402")
		(property "Reference" "R156"
			(at 0.7 -0.35 90)
			(layer "B.SilkS")
			(effects
				(font
					(size 0.7 0.7)
					(thickness 0.15)
				)
				(justify left bottom mirror)
			)
		)
		(property "Value" "R_10k2_0402"
			(at 0 -1.4 90)
			(layer "B.Fab")
			(effects
				(font
					(size 0.7 0.7)
					(thickness 0.15)
				)
				(justify left bottom mirror)
			)
		)
		(property "Datasheet" "https://www.bourns.com/docs/product-datasheets/cr.pdf"
			(at 0 0 270)
			(layer "F.Fab")
			(hide yes)
			(effects
				(font
					(size 1.27 1.27)
					(thickness 0.15)
				)
			)
		)
		(property "Description" "SMD Chip Resistor"
			(at 0 0 270)
			(layer "F.Fab")
			(hide yes)
			(effects
				(font
					(size 1.27 1.27)
					(thickness 0.15)
				)
			)
		)
		(property "Author" "Antmicro"
			(at 5.4 211.2 0)
			(layer "B.Fab")
			(hide yes)
			(effects
				(font
					(size 1 1)
					(thickness 0.15)
				)
				(justify mirror)
			)
		)
		(property "License" "Apache-2.0"
			(at 5.4 211.2 0)
			(layer "B.Fab")
			(hide yes)
			(effects
				(font
					(size 1 1)
					(thickness 0.15)
				)
				(justify mirror)
			)
		)
		(property "MPN" "CR0402-FX-1022GLF"
			(at 5.4 211.2 0)
			(layer "B.Fab")
			(hide yes)
			(effects
				(font
					(size 1 1)
					(thickness 0.15)
				)
				(justify mirror)
			)
		)
		(property "Manufacturer" "Bourns"
			(at 5.4 211.2 0)
			(layer "B.Fab")
			(hide yes)
			(effects
				(font
					(size 1 1)
					(thickness 0.15)
				)
				(justify mirror)
			)
		)
		(property "Tolerance" "1%"
			(at 5.4 211.2 0)
			(layer "B.Fab")
			(hide yes)
			(effects
				(font
					(size 1 1)
					(thickness 0.15)
				)
				(justify mirror)
			)
		)
		(property "Val" "10k2"
			(at 5.4 211.2 0)
			(layer "B.Fab")
			(hide yes)
			(effects
				(font
					(size 1 1)
					(thickness 0.15)
				)
				(justify mirror)
			)
		)
		(sheetname "/Ethernet/")
		(sheetfile "ethernet.kicad_sch")
		(attr smd)
		(fp_rect
			(start -0.925 0.47)
			(end 0.925 -0.47)
			(stroke
				(width 0.05)
				(type default)
			)
			(fill no)
			(layer "B.CrtYd")
		)
		(fp_rect
			(start -0.5 0.25)
			(end 0.5 -0.25)
			(stroke
				(width 0.15)
				(type solid)
			)
			(fill no)
			(layer "B.Fab")
		)
		(pad "1" smd roundrect
			(at -0.48 0 270)
			(size 0.59 0.64)
			(layers "B.Cu" "B.Mask" "B.Paste")
			(roundrect_rratio 0.25)
			(net 414 "ETH_~{RESET}")
			(pintype "passive")
		)
		(pad "2" smd roundrect
			(at 0.48 0 270)
			(size 0.59 0.64)
			(layers "B.Cu" "B.Mask" "B.Paste")
			(roundrect_rratio 0.25)
			(net 2 "VCC3V3")
			(pintype "passive")
		)
	)
	(footprint "antmicro-footprints:C_0402_1005Metric"
		(layer "B.Cu")
		(at 123.88625 113.475 -90)
		(descr "Capacitor SMD 0402")
		(tags "capacitor SMD 0402")
		(property "Reference" "C20"
			(at 0.825 -0.31375 90)
			(layer "B.SilkS")
			(effects
				(font
					(size 0.7 0.7)
					(thickness 0.15)
				)
				(justify left bottom mirror)
			)
		)
		(property "Value" "C_100n_0402"
			(at 0 -1.4 90)
			(layer "B.Fab")
			(effects
				(font
					(size 0.7 0.7)
					(thickness 0.15)
				)
				(justify left bottom mirror)
			)
		)
		(property "Datasheet" "https://www.murata.com/products/productdetail?partno=GRM155R61H104KE14%23"
			(at 0 0 270)
			(layer "F.Fab")
			(hide yes)
			(effects
				(font
					(size 1.27 1.27)
					(thickness 0.15)
				)
			)
		)
		(property "Description" "SMD Multilayer Ceramic Capacitor, 0.1 µF, 50 V, 0402 [1005 Metric], ± 10%, X5R, GRM Series"
			(at 0 0 270)
			(layer "F.Fab")
			(hide yes)
			(effects
				(font
					(size 1.27 1.27)
					(thickness 0.15)
				)
			)
		)
		(property "Author" "Antmicro"
			(at 10.41125 237.36125 0)
			(layer "B.Fab")
			(hide yes)
			(effects
				(font
					(size 1 1)
					(thickness 0.15)
				)
				(justify mirror)
			)
		)
		(property "Dielectric" "X5R"
			(at 10.41125 237.36125 0)
			(layer "B.Fab")
			(hide yes)
			(effects
				(font
					(size 1 1)
					(thickness 0.15)
				)
				(justify mirror)
			)
		)
		(property "License" "Apache-2.0"
			(at 10.41125 237.36125 0)
			(layer "B.Fab")
			(hide yes)
			(effects
				(font
					(size 1 1)
					(thickness 0.15)
				)
				(justify mirror)
			)
		)
		(property "MPN" "GRM155R61H104KE14D"
			(at 10.41125 237.36125 0)
			(layer "B.Fab")
			(hide yes)
			(effects
				(font
					(size 1 1)
					(thickness 0.15)
				)
				(justify mirror)
			)
		)
		(property "Manufacturer" "Murata"
			(at 10.41125 237.36125 0)
			(layer "B.Fab")
			(hide yes)
			(effects
				(font
					(size 1 1)
					(thickness 0.15)
				)
				(justify mirror)
			)
		)
		(property "Val" "100n"
			(at 10.41125 237.36125 0)
			(layer "B.Fab")
			(hide yes)
			(effects
				(font
					(size 1 1)
					(thickness 0.15)
				)
				(justify mirror)
			)
		)
		(property "Voltage" "50V"
			(at 10.41125 237.36125 0)
			(layer "B.Fab")
			(hide yes)
			(effects
				(font
					(size 1 1)
					(thickness 0.15)
				)
				(justify mirror)
			)
		)
		(sheetname "/Interfaces/")
		(sheetfile "interfaces.kicad_sch")
		(attr smd)
		(fp_rect
			(start -0.925 0.47)
			(end 0.925 -0.47)
			(stroke
				(width 0.05)
				(type default)
			)
			(fill no)
			(layer "B.CrtYd")
		)
		(fp_line
			(start -0.494 0.25)
			(end 0.504 0.25)
			(stroke
				(width 0.15)
				(type solid)
			)
			(layer "B.Fab")
		)
		(fp_line
			(start 0.504 0.25)
			(end 0.504 -0.248)
			(stroke
				(width 0.15)
				(type solid)
			)
			(layer "B.Fab")
		)
		(fp_line
			(start -0.494 -0.248)
			(end -0.494 0.25)
			(stroke
				(width 0.15)
				(type solid)
			)
			(layer "B.Fab")
		)
		(fp_line
			(start 0.504 -0.248)
			(end -0.494 -0.248)
			(stroke
				(width 0.15)
				(type solid)
			)
			(layer "B.Fab")
		)
		(pad "1" smd roundrect
			(at -0.48 0 270)
			(size 0.59 0.64)
			(layers "B.Cu" "B.Mask" "B.Paste")
			(roundrect_rratio 0.25)
			(net 1 "GND")
			(pintype "passive")
		)
		(pad "2" smd roundrect
			(at 0.48 0 270)
			(size 0.59 0.64)
			(layers "B.Cu" "B.Mask" "B.Paste")
			(roundrect_rratio 0.25)
			(net 105 "Net-(C20-Pad2)")
			(pintype "passive")
		)
	)
	(footprint "antmicro-footprints:R_0402_1005Metric"
		(layer "B.Cu")
		(at 106.225 148.275 90)
		(descr "Resistor SMD 0402")
		(tags "resistor SMD 0402")
		(property "Reference" "R99"
			(at -2.926 0.375 90)
			(layer "B.SilkS")
			(effects
				(font
					(size 0.7 0.7)
					(thickness 0.15)
				)
				(justify right bottom mirror)
			)
		)
		(property "Value" "R_51R_0402"
			(at 0 -1.4 90)
			(layer "B.Fab")
			(effects
				(font
					(size 0.7 0.7)
					(thickness 0.15)
				)
				(justify right bottom mirror)
			)
		)
		(property "Datasheet" "https://www.bourns.com/docs/product-datasheets/cr.pdf"
			(at 0 0 90)
			(layer "F.Fab")
			(hide yes)
			(effects
				(font
					(size 1.27 1.27)
					(thickness 0.15)
				)
			)
		)
		(property "Description" "SMD Chip Resistor, 51 ohm, ± 1%, 63 mW, 0402 [1005 Metric], Thick Film, General Purpose"
			(at 0 0 90)
			(layer "F.Fab")
			(hide yes)
			(effects
				(font
					(size 1.27 1.27)
					(thickness 0.15)
				)
			)
		)
		(property "Author" "Antmicro"
			(at 254.5 42.05 0)
			(layer "B.Fab")
			(hide yes)
			(effects
				(font
					(size 1 1)
					(thickness 0.15)
				)
				(justify mirror)
			)
		)
		(property "License" "Apache-2.0"
			(at 254.5 42.05 0)
			(layer "B.Fab")
			(hide yes)
			(effects
				(font
					(size 1 1)
					(thickness 0.15)
				)
				(justify mirror)
			)
		)
		(property "MPN" "CR0402-FX-51R0GLF"
			(at 254.5 42.05 0)
			(layer "B.Fab")
			(hide yes)
			(effects
				(font
					(size 1 1)
					(thickness 0.15)
				)
				(justify mirror)
			)
		)
		(property "Manufacturer" "Bourns"
			(at 254.5 42.05 0)
			(layer "B.Fab")
			(hide yes)
			(effects
				(font
					(size 1 1)
					(thickness 0.15)
				)
				(justify mirror)
			)
		)
		(property "Tolerance" "1%"
			(at 254.5 42.05 0)
			(layer "B.Fab")
			(hide yes)
			(effects
				(font
					(size 1 1)
					(thickness 0.15)
				)
				(justify mirror)
			)
		)
		(property "Val" "51R"
			(at 254.5 42.05 0)
			(layer "B.Fab")
			(hide yes)
			(effects
				(font
					(size 1 1)
					(thickness 0.15)
				)
				(justify mirror)
			)
		)
		(sheetname "/DDR3/")
		(sheetfile "ddr3.kicad_sch")
		(attr smd exclude_from_pos_files exclude_from_bom dnp)
		(fp_rect
			(start -0.925 0.47)
			(end 0.925 -0.47)
			(stroke
				(width 0.05)
				(type default)
			)
			(fill no)
			(layer "B.CrtYd")
		)
		(fp_rect
			(start -0.5 0.25)
			(end 0.5 -0.25)
			(stroke
				(width 0.15)
				(type solid)
			)
			(fill no)
			(layer "B.Fab")
		)
		(pad "1" smd roundrect
			(at -0.48 0 90)
			(size 0.59 0.64)
			(layers "B.Cu" "B.Mask" "B.Paste")
			(roundrect_rratio 0.25)
			(net 109 "Net-(C63-Pad1)")
			(pintype "passive")
		)
		(pad "2" smd roundrect
			(at 0.48 0 90)
			(size 0.59 0.64)
			(layers "B.Cu" "B.Mask" "B.Paste")
			(roundrect_rratio 0.25)
			(net 479 "DDR3_CLK_P")
			(pintype "passive")
		)
	)
	(footprint "antmicro-footprints:C_1210_3225Metric"
		(layer "B.Cu")
		(at 112.8 102.2 180)
		(descr "Capacitor SMD 1210")
		(tags "capacitor SMD 1210")
		(property "Reference" "C93"
			(at -2.9 1 90)
			(layer "B.SilkS")
			(effects
				(font
					(size 0.7 0.7)
					(thickness 0.15)
				)
				(justify left bottom mirror)
			)
		)
		(property "Value" "C_47u_1210"
			(at 0 -2.749 0)
			(layer "B.Fab")
			(effects
				(font
					(size 0.7 0.7)
					(thickness 0.15)
				)
				(justify left bottom mirror)
			)
		)
		(property "Datasheet" "https://www.kemet.com/en/us/capacitors/product/C1210C476K8RACTU.html"
			(at 0 0 180)
			(layer "F.Fab")
			(hide yes)
			(effects
				(font
					(size 1.27 1.27)
					(thickness 0.15)
				)
			)
		)
		(property "Description" "SMD Multilayer Ceramic Capacitor, 47 µF, 10 V, 1210 [3225 Metric], ± 10%, X7R, C Series KEMET"
			(at 0 0 180)
			(layer "F.Fab")
			(hide yes)
			(effects
				(font
					(size 1.27 1.27)
					(thickness 0.15)
				)
			)
		)
		(property "Author" "Antmicro"
			(at 225.6 204.4 0)
			(layer "B.Fab")
			(hide yes)
			(effects
				(font
					(size 1 1)
					(thickness 0.15)
				)
				(justify mirror)
			)
		)
		(property "Dielectric" ""
			(at 225.6 204.4 0)
			(layer "B.Fab")
			(hide yes)
			(effects
				(font
					(size 1 1)
					(thickness 0.15)
				)
				(justify mirror)
			)
		)
		(property "License" "Apache-2.0"
			(at 225.6 204.4 0)
			(layer "B.Fab")
			(hide yes)
			(effects
				(font
					(size 1 1)
					(thickness 0.15)
				)
				(justify mirror)
			)
		)
		(property "MPN" "C1210C476K8RACTU"
			(at 225.6 204.4 0)
			(layer "B.Fab")
			(hide yes)
			(effects
				(font
					(size 1 1)
					(thickness 0.15)
				)
				(justify mirror)
			)
		)
		(property "Manufacturer" "KEMET"
			(at 225.6 204.4 0)
			(layer "B.Fab")
			(hide yes)
			(effects
				(font
					(size 1 1)
					(thickness 0.15)
				)
				(justify mirror)
			)
		)
		(property "Public" "False"
			(at 225.6 204.4 0)
			(layer "B.Fab")
			(hide yes)
			(effects
				(font
					(size 1 1)
					(thickness 0.15)
				)
				(justify mirror)
			)
		)
		(property "Val" "47u"
			(at 225.6 204.4 0)
			(layer "B.Fab")
			(hide yes)
			(effects
				(font
					(size 1 1)
					(thickness 0.15)
				)
				(justify mirror)
			)
		)
		(property "Voltage" ""
			(at 225.6 204.4 0)
			(layer "B.Fab")
			(hide yes)
			(effects
				(font
					(size 1 1)
					(thickness 0.15)
				)
				(justify mirror)
			)
		)
		(sheetname "/FPGA banks 13-16/")
		(sheetfile "fpga-banks-13-16.kicad_sch")
		(attr smd)
		(fp_line
			(start -0.3 1.39)
			(end 0.3 1.39)
			(stroke
				(width 0.15)
				(type solid)
			)
			(layer "B.SilkS")
		)
		(fp_line
			(start -0.3 -1.39)
			(end 0.3 -1.39)
			(stroke
				(width 0.15)
				(type solid)
			)
			(layer "B.SilkS")
		)
		(fp_rect
			(start -2.1 1.75)
			(end 2.1 -1.75)
			(stroke
				(width 0.05)
				(type solid)
			)
			(fill no)
			(layer "B.CrtYd")
		)
		(fp_rect
			(start -1.6 1.25)
			(end 1.6 -1.25)
			(stroke
				(width 0.15)
				(type solid)
			)
			(fill no)
			(layer "B.Fab")
		)
		(pad "1" smd rect
			(at -1.145 0 180)
			(size 1.52 3.05)
			(layers "B.Cu" "B.Mask" "B.Paste")
			(net 1 "GND")
			(pintype "passive")
		)
		(pad "2" smd rect
			(at 1.145 0 180)
			(size 1.52 3.05)
			(layers "B.Cu" "B.Mask" "B.Paste")
			(net 2 "VCC3V3")
			(pintype "passive")
		)
	)
	(footprint "antmicro-footprints:C_0402_1005Metric"
		(layer "B.Cu")
		(at 122.975 109.375 90)
		(descr "Capacitor SMD 0402")
		(tags "capacitor SMD 0402")
		(property "Reference" "C10"
			(at 0.86 0.425 90)
			(layer "B.SilkS")
			(effects
				(font
					(size 0.7 0.7)
					(thickness 0.15)
				)
				(justify right bottom mirror)
			)
		)
		(property "Value" "C_100n_0402"
			(at 0 -1.4 90)
			(layer "B.Fab")
			(effects
				(font
					(size 0.7 0.7)
					(thickness 0.15)
				)
				(justify right bottom mirror)
			)
		)
		(property "Datasheet" "https://www.murata.com/products/productdetail?partno=GRM155R61H104KE14%23"
			(at 0 0 90)
			(layer "F.Fab")
			(hide yes)
			(effects
				(font
					(size 1.27 1.27)
					(thickness 0.15)
				)
			)
		)
		(property "Description" "SMD Multilayer Ceramic Capacitor, 0.1 µF, 50 V, 0402 [1005 Metric], ± 10%, X5R, GRM Series"
			(at 0 0 90)
			(layer "F.Fab")
			(hide yes)
			(effects
				(font
					(size 1.27 1.27)
					(thickness 0.15)
				)
			)
		)
		(property "Author" "Antmicro"
			(at 232.35 -13.6 0)
			(layer "B.Fab")
			(hide yes)
			(effects
				(font
					(size 1 1)
					(thickness 0.15)
				)
				(justify mirror)
			)
		)
		(property "Dielectric" "X5R"
			(at 232.35 -13.6 0)
			(layer "B.Fab")
			(hide yes)
			(effects
				(font
					(size 1 1)
					(thickness 0.15)
				)
				(justify mirror)
			)
		)
		(property "License" "Apache-2.0"
			(at 232.35 -13.6 0)
			(layer "B.Fab")
			(hide yes)
			(effects
				(font
					(size 1 1)
					(thickness 0.15)
				)
				(justify mirror)
			)
		)
		(property "MPN" "GRM155R61H104KE14D"
			(at 232.35 -13.6 0)
			(layer "B.Fab")
			(hide yes)
			(effects
				(font
					(size 1 1)
					(thickness 0.15)
				)
				(justify mirror)
			)
		)
		(property "Manufacturer" "Murata"
			(at 232.35 -13.6 0)
			(layer "B.Fab")
			(hide yes)
			(effects
				(font
					(size 1 1)
					(thickness 0.15)
				)
				(justify mirror)
			)
		)
		(property "Val" "100n"
			(at 232.35 -13.6 0)
			(layer "B.Fab")
			(hide yes)
			(effects
				(font
					(size 1 1)
					(thickness 0.15)
				)
				(justify mirror)
			)
		)
		(property "Voltage" "50V"
			(at 232.35 -13.6 0)
			(layer "B.Fab")
			(hide yes)
			(effects
				(font
					(size 1 1)
					(thickness 0.15)
				)
				(justify mirror)
			)
		)
		(sheetname "/Interfaces/")
		(sheetfile "interfaces.kicad_sch")
		(attr smd)
		(fp_rect
			(start -0.925 0.47)
			(end 0.925 -0.47)
			(stroke
				(width 0.05)
				(type default)
			)
			(fill no)
			(layer "B.CrtYd")
		)
		(fp_line
			(start 0.504 -0.248)
			(end -0.494 -0.248)
			(stroke
				(width 0.15)
				(type solid)
			)
			(layer "B.Fab")
		)
		(fp_line
			(start -0.494 -0.248)
			(end -0.494 0.25)
			(stroke
				(width 0.15)
				(type solid)
			)
			(layer "B.Fab")
		)
		(fp_line
			(start 0.504 0.25)
			(end 0.504 -0.248)
			(stroke
				(width 0.15)
				(type solid)
			)
			(layer "B.Fab")
		)
		(fp_line
			(start -0.494 0.25)
			(end 0.504 0.25)
			(stroke
				(width 0.15)
				(type solid)
			)
			(layer "B.Fab")
		)
		(pad "1" smd roundrect
			(at -0.48 0 90)
			(size 0.59 0.64)
			(layers "B.Cu" "B.Mask" "B.Paste")
			(roundrect_rratio 0.25)
			(net 1 "GND")
			(pintype "passive")
		)
		(pad "2" smd roundrect
			(at 0.48 0 90)
			(size 0.59 0.64)
			(layers "B.Cu" "B.Mask" "B.Paste")
			(roundrect_rratio 0.25)
			(net 2 "VCC3V3")
			(pintype "passive")
		)
	)
	(footprint "antmicro-footprints:C_0402_1005Metric"
		(layer "B.Cu")
		(at 121.865 114.45 -90)
		(descr "Capacitor SMD 0402")
		(tags "capacitor SMD 0402")
		(property "Reference" "C11"
			(at 0.825 -0.31375 90)
			(layer "B.SilkS")
			(effects
				(font
					(size 0.7 0.7)
					(thickness 0.15)
				)
				(justify left bottom mirror)
			)
		)
		(property "Value" "C_100n_0402"
			(at 0 -1.4 90)
			(layer "B.Fab")
			(effects
				(font
					(size 0.7 0.7)
					(thickness 0.15)
				)
				(justify left bottom mirror)
			)
		)
		(property "Datasheet" "https://www.murata.com/products/productdetail?partno=GRM155R61H104KE14%23"
			(at 0 0 270)
			(layer "F.Fab")
			(hide yes)
			(effects
				(font
					(size 1.27 1.27)
					(thickness 0.15)
				)
			)
		)
		(property "Description" "SMD Multilayer Ceramic Capacitor, 0.1 µF, 50 V, 0402 [1005 Metric], ± 10%, X5R, GRM Series"
			(at 0 0 270)
			(layer "F.Fab")
			(hide yes)
			(effects
				(font
					(size 1.27 1.27)
					(thickness 0.15)
				)
			)
		)
		(property "Author" "Antmicro"
			(at 7.415 236.315 0)
			(layer "B.Fab")
			(hide yes)
			(effects
				(font
					(size 1 1)
					(thickness 0.15)
				)
				(justify mirror)
			)
		)
		(property "Dielectric" "X5R"
			(at 7.415 236.315 0)
			(layer "B.Fab")
			(hide yes)
			(effects
				(font
					(size 1 1)
					(thickness 0.15)
				)
				(justify mirror)
			)
		)
		(property "License" "Apache-2.0"
			(at 7.415 236.315 0)
			(layer "B.Fab")
			(hide yes)
			(effects
				(font
					(size 1 1)
					(thickness 0.15)
				)
				(justify mirror)
			)
		)
		(property "MPN" "GRM155R61H104KE14D"
			(at 7.415 236.315 0)
			(layer "B.Fab")
			(hide yes)
			(effects
				(font
					(size 1 1)
					(thickness 0.15)
				)
				(justify mirror)
			)
		)
		(property "Manufacturer" "Murata"
			(at 7.415 236.315 0)
			(layer "B.Fab")
			(hide yes)
			(effects
				(font
					(size 1 1)
					(thickness 0.15)
				)
				(justify mirror)
			)
		)
		(property "Val" "100n"
			(at 7.415 236.315 0)
			(layer "B.Fab")
			(hide yes)
			(effects
				(font
					(size 1 1)
					(thickness 0.15)
				)
				(justify mirror)
			)
		)
		(property "Voltage" "50V"
			(at 7.415 236.315 0)
			(layer "B.Fab")
			(hide yes)
			(effects
				(font
					(size 1 1)
					(thickness 0.15)
				)
				(justify mirror)
			)
		)
		(sheetname "/Interfaces/")
		(sheetfile "interfaces.kicad_sch")
		(attr smd)
		(fp_rect
			(start -0.925 0.47)
			(end 0.925 -0.47)
			(stroke
				(width 0.05)
				(type default)
			)
			(fill no)
			(layer "B.CrtYd")
		)
		(fp_line
			(start -0.494 0.25)
			(end 0.504 0.25)
			(stroke
				(width 0.15)
				(type solid)
			)
			(layer "B.Fab")
		)
		(fp_line
			(start 0.504 0.25)
			(end 0.504 -0.248)
			(stroke
				(width 0.15)
				(type solid)
			)
			(layer "B.Fab")
		)
		(fp_line
			(start -0.494 -0.248)
			(end -0.494 0.25)
			(stroke
				(width 0.15)
				(type solid)
			)
			(layer "B.Fab")
		)
		(fp_line
			(start 0.504 -0.248)
			(end -0.494 -0.248)
			(stroke
				(width 0.15)
				(type solid)
			)
			(layer "B.Fab")
		)
		(pad "1" smd roundrect
			(at -0.48 0 270)
			(size 0.59 0.64)
			(layers "B.Cu" "B.Mask" "B.Paste")
			(roundrect_rratio 0.25)
			(net 1 "GND")
			(pintype "passive")
		)
		(pad "2" smd roundrect
			(at 0.48 0 270)
			(size 0.59 0.64)
			(layers "B.Cu" "B.Mask" "B.Paste")
			(roundrect_rratio 0.25)
			(net 2 "VCC3V3")
			(pintype "passive")
		)
	)
	(footprint "antmicro-footprints:C_0402_1005Metric"
		(layer "B.Cu")
		(at 129.175 126.775 180)
		(descr "Capacitor SMD 0402")
		(tags "capacitor SMD 0402")
		(property "Reference" "C12"
			(at -1.125 0.575 0)
			(layer "B.SilkS")
			(effects
				(font
					(size 0.7 0.7)
					(thickness 0.15)
				)
				(justify left bottom mirror)
			)
		)
		(property "Value" "C_100n_0402"
			(at 0 -1.4 0)
			(layer "B.Fab")
			(effects
				(font
					(size 0.7 0.7)
					(thickness 0.15)
				)
				(justify left bottom mirror)
			)
		)
		(property "Datasheet" "https://www.murata.com/products/productdetail?partno=GRM155R61H104KE14%23"
			(at 0 0 180)
			(layer "F.Fab")
			(hide yes)
			(effects
				(font
					(size 1.27 1.27)
					(thickness 0.15)
				)
			)
		)
		(property "Description" "SMD Multilayer Ceramic Capacitor, 0.1 µF, 50 V, 0402 [1005 Metric], ± 10%, X5R, GRM Series"
			(at 0 0 180)
			(layer "F.Fab")
			(hide yes)
			(effects
				(font
					(size 1.27 1.27)
					(thickness 0.15)
				)
			)
		)
		(property "Author" "Antmicro"
			(at 258.35 253.55 0)
			(layer "B.Fab")
			(hide yes)
			(effects
				(font
					(size 1 1)
					(thickness 0.15)
				)
				(justify mirror)
			)
		)
		(property "Dielectric" "X5R"
			(at 258.35 253.55 0)
			(layer "B.Fab")
			(hide yes)
			(effects
				(font
					(size 1 1)
					(thickness 0.15)
				)
				(justify mirror)
			)
		)
		(property "License" "Apache-2.0"
			(at 258.35 253.55 0)
			(layer "B.Fab")
			(hide yes)
			(effects
				(font
					(size 1 1)
					(thickness 0.15)
				)
				(justify mirror)
			)
		)
		(property "MPN" "GRM155R61H104KE14D"
			(at 258.35 253.55 0)
			(layer "B.Fab")
			(hide yes)
			(effects
				(font
					(size 1 1)
					(thickness 0.15)
				)
				(justify mirror)
			)
		)
		(property "Manufacturer" "Murata"
			(at 258.35 253.55 0)
			(layer "B.Fab")
			(hide yes)
			(effects
				(font
					(size 1 1)
					(thickness 0.15)
				)
				(justify mirror)
			)
		)
		(property "Val" "100n"
			(at 258.35 253.55 0)
			(layer "B.Fab")
			(hide yes)
			(effects
				(font
					(size 1 1)
					(thickness 0.15)
				)
				(justify mirror)
			)
		)
		(property "Voltage" "50V"
			(at 258.35 253.55 0)
			(layer "B.Fab")
			(hide yes)
			(effects
				(font
					(size 1 1)
					(thickness 0.15)
				)
				(justify mirror)
			)
		)
		(sheetname "/Interfaces/")
		(sheetfile "interfaces.kicad_sch")
		(attr smd)
		(fp_rect
			(start -0.925 0.47)
			(end 0.925 -0.47)
			(stroke
				(width 0.05)
				(type default)
			)
			(fill no)
			(layer "B.CrtYd")
		)
		(fp_line
			(start 0.504 0.25)
			(end 0.504 -0.248)
			(stroke
				(width 0.15)
				(type solid)
			)
			(layer "B.Fab")
		)
		(fp_line
			(start 0.504 -0.248)
			(end -0.494 -0.248)
			(stroke
				(width 0.15)
				(type solid)
			)
			(layer "B.Fab")
		)
		(fp_line
			(start -0.494 0.25)
			(end 0.504 0.25)
			(stroke
				(width 0.15)
				(type solid)
			)
			(layer "B.Fab")
		)
		(fp_line
			(start -0.494 -0.248)
			(end -0.494 0.25)
			(stroke
				(width 0.15)
				(type solid)
			)
			(layer "B.Fab")
		)
		(pad "1" smd roundrect
			(at -0.48 0 180)
			(size 0.59 0.64)
			(layers "B.Cu" "B.Mask" "B.Paste")
			(roundrect_rratio 0.25)
			(net 1 "GND")
			(pintype "passive")
		)
		(pad "2" smd roundrect
			(at 0.48 0 180)
			(size 0.59 0.64)
			(layers "B.Cu" "B.Mask" "B.Paste")
			(roundrect_rratio 0.25)
			(net 2 "VCC3V3")
			(pintype "passive")
		)
	)
	(footprint "antmicro-footprints:C_0402_1005Metric"
		(layer "B.Cu")
		(at 126.95 113.465 -90)
		(descr "Capacitor SMD 0402")
		(tags "capacitor SMD 0402")
		(property "Reference" "C13"
			(at 0.825 -0.31375 90)
			(layer "B.SilkS")
			(effects
				(font
					(size 0.7 0.7)
					(thickness 0.15)
				)
				(justify left bottom mirror)
			)
		)
		(property "Value" "C_100n_0402"
			(at 0 -1.4 90)
			(layer "B.Fab")
			(effects
				(font
					(size 0.7 0.7)
					(thickness 0.15)
				)
				(justify left bottom mirror)
			)
		)
		(property "Datasheet" "https://www.murata.com/products/productdetail?partno=GRM155R61H104KE14%23"
			(at 0 0 270)
			(layer "F.Fab")
			(hide yes)
			(effects
				(font
					(size 1.27 1.27)
					(thickness 0.15)
				)
			)
		)
		(property "Description" "SMD Multilayer Ceramic Capacitor, 0.1 µF, 50 V, 0402 [1005 Metric], ± 10%, X5R, GRM Series"
			(at 0 0 270)
			(layer "F.Fab")
			(hide yes)
			(effects
				(font
					(size 1.27 1.27)
					(thickness 0.15)
				)
			)
		)
		(property "Author" "Antmicro"
			(at 13.485 240.415 0)
			(layer "B.Fab")
			(hide yes)
			(effects
				(font
					(size 1 1)
					(thickness 0.15)
				)
				(justify mirror)
			)
		)
		(property "Dielectric" "X5R"
			(at 13.485 240.415 0)
			(layer "B.Fab")
			(hide yes)
			(effects
				(font
					(size 1 1)
					(thickness 0.15)
				)
				(justify mirror)
			)
		)
		(property "License" "Apache-2.0"
			(at 13.485 240.415 0)
			(layer "B.Fab")
			(hide yes)
			(effects
				(font
					(size 1 1)
					(thickness 0.15)
				)
				(justify mirror)
			)
		)
		(property "MPN" "GRM155R61H104KE14D"
			(at 13.485 240.415 0)
			(layer "B.Fab")
			(hide yes)
			(effects
				(font
					(size 1 1)
					(thickness 0.15)
				)
				(justify mirror)
			)
		)
		(property "Manufacturer" "Murata"
			(at 13.485 240.415 0)
			(layer "B.Fab")
			(hide yes)
			(effects
				(font
					(size 1 1)
					(thickness 0.15)
				)
				(justify mirror)
			)
		)
		(property "Val" "100n"
			(at 13.485 240.415 0)
			(layer "B.Fab")
			(hide yes)
			(effects
				(font
					(size 1 1)
					(thickness 0.15)
				)
				(justify mirror)
			)
		)
		(property "Voltage" "50V"
			(at 13.485 240.415 0)
			(layer "B.Fab")
			(hide yes)
			(effects
				(font
					(size 1 1)
					(thickness 0.15)
				)
				(justify mirror)
			)
		)
		(sheetname "/Interfaces/")
		(sheetfile "interfaces.kicad_sch")
		(attr smd)
		(fp_rect
			(start -0.925 0.47)
			(end 0.925 -0.47)
			(stroke
				(width 0.05)
				(type default)
			)
			(fill no)
			(layer "B.CrtYd")
		)
		(fp_line
			(start -0.494 0.25)
			(end 0.504 0.25)
			(stroke
				(width 0.15)
				(type solid)
			)
			(layer "B.Fab")
		)
		(fp_line
			(start 0.504 0.25)
			(end 0.504 -0.248)
			(stroke
				(width 0.15)
				(type solid)
			)
			(layer "B.Fab")
		)
		(fp_line
			(start -0.494 -0.248)
			(end -0.494 0.25)
			(stroke
				(width 0.15)
				(type solid)
			)
			(layer "B.Fab")
		)
		(fp_line
			(start 0.504 -0.248)
			(end -0.494 -0.248)
			(stroke
				(width 0.15)
				(type solid)
			)
			(layer "B.Fab")
		)
		(pad "1" smd roundrect
			(at -0.48 0 270)
			(size 0.59 0.64)
			(layers "B.Cu" "B.Mask" "B.Paste")
			(roundrect_rratio 0.25)
			(net 1 "GND")
			(pintype "passive")
		)
		(pad "2" smd roundrect
			(at 0.48 0 270)
			(size 0.59 0.64)
			(layers "B.Cu" "B.Mask" "B.Paste")
			(roundrect_rratio 0.25)
			(net 2 "VCC3V3")
			(pintype "passive")
		)
	)
	(footprint "antmicro-footprints:C_0402_1005Metric"
		(layer "B.Cu")
		(at 139.774 125.514)
		(descr "Capacitor SMD 0402")
		(tags "capacitor SMD 0402")
		(property "Reference" "C18"
			(at 0.826 0.386 0)
			(layer "B.SilkS")
			(effects
				(font
					(size 0.7 0.7)
					(thickness 0.15)
				)
				(justify right bottom mirror)
			)
		)
		(property "Value" "C_100n_0402"
			(at 0 -1.4 0)
			(layer "B.Fab")
			(effects
				(font
					(size 0.7 0.7)
					(thickness 0.15)
				)
				(justify right bottom mirror)
			)
		)
		(property "Datasheet" "https://www.murata.com/products/productdetail?partno=GRM155R61H104KE14%23"
			(at 0 0 0)
			(layer "F.Fab")
			(hide yes)
			(effects
				(font
					(size 1.27 1.27)
					(thickness 0.15)
				)
			)
		)
		(property "Description" "SMD Multilayer Ceramic Capacitor, 0.1 µF, 50 V, 0402 [1005 Metric], ± 10%, X5R, GRM Series"
			(at 0 0 0)
			(layer "F.Fab")
			(hide yes)
			(effects
				(font
					(size 1.27 1.27)
					(thickness 0.15)
				)
			)
		)
		(property "Author" "Antmicro"
			(at 0 0 0)
			(layer "B.Fab")
			(hide yes)
			(effects
				(font
					(size 1 1)
					(thickness 0.15)
				)
				(justify mirror)
			)
		)
		(property "Dielectric" "X5R"
			(at 0 0 0)
			(layer "B.Fab")
			(hide yes)
			(effects
				(font
					(size 1 1)
					(thickness 0.15)
				)
				(justify mirror)
			)
		)
		(property "License" "Apache-2.0"
			(at 0 0 0)
			(layer "B.Fab")
			(hide yes)
			(effects
				(font
					(size 1 1)
					(thickness 0.15)
				)
				(justify mirror)
			)
		)
		(property "MPN" "GRM155R61H104KE14D"
			(at 0 0 0)
			(layer "B.Fab")
			(hide yes)
			(effects
				(font
					(size 1 1)
					(thickness 0.15)
				)
				(justify mirror)
			)
		)
		(property "Manufacturer" "Murata"
			(at 0 0 0)
			(layer "B.Fab")
			(hide yes)
			(effects
				(font
					(size 1 1)
					(thickness 0.15)
				)
				(justify mirror)
			)
		)
		(property "Val" "100n"
			(at 0 0 0)
			(layer "B.Fab")
			(hide yes)
			(effects
				(font
					(size 1 1)
					(thickness 0.15)
				)
				(justify mirror)
			)
		)
		(property "Voltage" "50V"
			(at 0 0 0)
			(layer "B.Fab")
			(hide yes)
			(effects
				(font
					(size 1 1)
					(thickness 0.15)
				)
				(justify mirror)
			)
		)
		(sheetname "/Interfaces/")
		(sheetfile "interfaces.kicad_sch")
		(attr smd)
		(fp_rect
			(start -0.925 0.47)
			(end 0.925 -0.47)
			(stroke
				(width 0.05)
				(type default)
			)
			(fill no)
			(layer "B.CrtYd")
		)
		(fp_line
			(start -0.494 -0.248)
			(end -0.494 0.25)
			(stroke
				(width 0.15)
				(type solid)
			)
			(layer "B.Fab")
		)
		(fp_line
			(start -0.494 0.25)
			(end 0.504 0.25)
			(stroke
				(width 0.15)
				(type solid)
			)
			(layer "B.Fab")
		)
		(fp_line
			(start 0.504 -0.248)
			(end -0.494 -0.248)
			(stroke
				(width 0.15)
				(type solid)
			)
			(layer "B.Fab")
		)
		(fp_line
			(start 0.504 0.25)
			(end 0.504 -0.248)
			(stroke
				(width 0.15)
				(type solid)
			)
			(layer "B.Fab")
		)
		(pad "1" smd roundrect
			(at -0.48 0)
			(size 0.59 0.64)
			(layers "B.Cu" "B.Mask" "B.Paste")
			(roundrect_rratio 0.25)
			(net 1 "GND")
			(pintype "passive")
		)
		(pad "2" smd roundrect
			(at 0.48 0)
			(size 0.59 0.64)
			(layers "B.Cu" "B.Mask" "B.Paste")
			(roundrect_rratio 0.25)
			(net 2 "VCC3V3")
			(pintype "passive")
		)
	)
	(footprint "antmicro-footprints:C_0402_1005Metric"
		(layer "B.Cu")
		(at 127.175 110.675)
		(descr "Capacitor SMD 0402")
		(tags "capacitor SMD 0402")
		(property "Reference" "C19"
			(at -1.075 -0.575 0)
			(layer "B.SilkS")
			(effects
				(font
					(size 0.7 0.7)
					(thickness 0.15)
				)
				(justify right bottom mirror)
			)
		)
		(property "Value" "C_100n_0402"
			(at 0 -1.4 0)
			(layer "B.Fab")
			(effects
				(font
					(size 0.7 0.7)
					(thickness 0.15)
				)
				(justify right bottom mirror)
			)
		)
		(property "Datasheet" "https://www.murata.com/products/productdetail?partno=GRM155R61H104KE14%23"
			(at 0 0 0)
			(layer "F.Fab")
			(hide yes)
			(effects
				(font
					(size 1.27 1.27)
					(thickness 0.15)
				)
			)
		)
		(property "Description" "SMD Multilayer Ceramic Capacitor, 0.1 µF, 50 V, 0402 [1005 Metric], ± 10%, X5R, GRM Series"
			(at 0 0 0)
			(layer "F.Fab")
			(hide yes)
			(effects
				(font
					(size 1.27 1.27)
					(thickness 0.15)
				)
			)
		)
		(property "Author" "Antmicro"
			(at 0 0 0)
			(layer "B.Fab")
			(hide yes)
			(effects
				(font
					(size 1 1)
					(thickness 0.15)
				)
				(justify mirror)
			)
		)
		(property "Dielectric" "X5R"
			(at 0 0 0)
			(layer "B.Fab")
			(hide yes)
			(effects
				(font
					(size 1 1)
					(thickness 0.15)
				)
				(justify mirror)
			)
		)
		(property "License" "Apache-2.0"
			(at 0 0 0)
			(layer "B.Fab")
			(hide yes)
			(effects
				(font
					(size 1 1)
					(thickness 0.15)
				)
				(justify mirror)
			)
		)
		(property "MPN" "GRM155R61H104KE14D"
			(at 0 0 0)
			(layer "B.Fab")
			(hide yes)
			(effects
				(font
					(size 1 1)
					(thickness 0.15)
				)
				(justify mirror)
			)
		)
		(property "Manufacturer" "Murata"
			(at 0 0 0)
			(layer "B.Fab")
			(hide yes)
			(effects
				(font
					(size 1 1)
					(thickness 0.15)
				)
				(justify mirror)
			)
		)
		(property "Val" "100n"
			(at 0 0 0)
			(layer "B.Fab")
			(hide yes)
			(effects
				(font
					(size 1 1)
					(thickness 0.15)
				)
				(justify mirror)
			)
		)
		(property "Voltage" "50V"
			(at 0 0 0)
			(layer "B.Fab")
			(hide yes)
			(effects
				(font
					(size 1 1)
					(thickness 0.15)
				)
				(justify mirror)
			)
		)
		(sheetname "/Interfaces/")
		(sheetfile "interfaces.kicad_sch")
		(attr smd)
		(fp_rect
			(start -0.925 0.47)
			(end 0.925 -0.47)
			(stroke
				(width 0.05)
				(type default)
			)
			(fill no)
			(layer "B.CrtYd")
		)
		(fp_line
			(start -0.494 -0.248)
			(end -0.494 0.25)
			(stroke
				(width 0.15)
				(type solid)
			)
			(layer "B.Fab")
		)
		(fp_line
			(start -0.494 0.25)
			(end 0.504 0.25)
			(stroke
				(width 0.15)
				(type solid)
			)
			(layer "B.Fab")
		)
		(fp_line
			(start 0.504 -0.248)
			(end -0.494 -0.248)
			(stroke
				(width 0.15)
				(type solid)
			)
			(layer "B.Fab")
		)
		(fp_line
			(start 0.504 0.25)
			(end 0.504 -0.248)
			(stroke
				(width 0.15)
				(type solid)
			)
			(layer "B.Fab")
		)
		(pad "1" smd roundrect
			(at -0.48 0)
			(size 0.59 0.64)
			(layers "B.Cu" "B.Mask" "B.Paste")
			(roundrect_rratio 0.25)
			(net 1 "GND")
			(pintype "passive")
		)
		(pad "2" smd roundrect
			(at 0.48 0)
			(size 0.59 0.64)
			(layers "B.Cu" "B.Mask" "B.Paste")
			(roundrect_rratio 0.25)
			(net 2 "VCC3V3")
			(pintype "passive")
		)
	)
	(footprint "antmicro-footprints:C_0402_1005Metric"
		(layer "B.Cu")
		(at 123 125.4 90)
		(descr "Capacitor SMD 0402")
		(tags "capacitor SMD 0402")
		(property "Reference" "C21"
			(at 0.8 0.4 90)
			(layer "B.SilkS")
			(effects
				(font
					(size 0.7 0.7)
					(thickness 0.15)
				)
				(justify right bottom mirror)
			)
		)
		(property "Value" "C_100n_0402"
			(at 0 -1.4 90)
			(layer "B.Fab")
			(effects
				(font
					(size 0.7 0.7)
					(thickness 0.15)
				)
				(justify right bottom mirror)
			)
		)
		(property "Datasheet" "https://www.murata.com/products/productdetail?partno=GRM155R61H104KE14%23"
			(at 0 0 90)
			(layer "F.Fab")
			(hide yes)
			(effects
				(font
					(size 1.27 1.27)
					(thickness 0.15)
				)
			)
		)
		(property "Description" "SMD Multilayer Ceramic Capacitor, 0.1 µF, 50 V, 0402 [1005 Metric], ± 10%, X5R, GRM Series"
			(at 0 0 90)
			(layer "F.Fab")
			(hide yes)
			(effects
				(font
					(size 1.27 1.27)
					(thickness 0.15)
				)
			)
		)
		(property "Author" "Antmicro"
			(at 248.4 2.4 0)
			(layer "B.Fab")
			(hide yes)
			(effects
				(font
					(size 1 1)
					(thickness 0.15)
				)
				(justify mirror)
			)
		)
		(property "Dielectric" "X5R"
			(at 248.4 2.4 0)
			(layer "B.Fab")
			(hide yes)
			(effects
				(font
					(size 1 1)
					(thickness 0.15)
				)
				(justify mirror)
			)
		)
		(property "License" "Apache-2.0"
			(at 248.4 2.4 0)
			(layer "B.Fab")
			(hide yes)
			(effects
				(font
					(size 1 1)
					(thickness 0.15)
				)
				(justify mirror)
			)
		)
		(property "MPN" "GRM155R61H104KE14D"
			(at 248.4 2.4 0)
			(layer "B.Fab")
			(hide yes)
			(effects
				(font
					(size 1 1)
					(thickness 0.15)
				)
				(justify mirror)
			)
		)
		(property "Manufacturer" "Murata"
			(at 248.4 2.4 0)
			(layer "B.Fab")
			(hide yes)
			(effects
				(font
					(size 1 1)
					(thickness 0.15)
				)
				(justify mirror)
			)
		)
		(property "Val" "100n"
			(at 248.4 2.4 0)
			(layer "B.Fab")
			(hide yes)
			(effects
				(font
					(size 1 1)
					(thickness 0.15)
				)
				(justify mirror)
			)
		)
		(property "Voltage" "50V"
			(at 248.4 2.4 0)
			(layer "B.Fab")
			(hide yes)
			(effects
				(font
					(size 1 1)
					(thickness 0.15)
				)
				(justify mirror)
			)
		)
		(sheetname "/Interfaces/")
		(sheetfile "interfaces.kicad_sch")
		(attr smd)
		(fp_rect
			(start -0.925 0.47)
			(end 0.925 -0.47)
			(stroke
				(width 0.05)
				(type default)
			)
			(fill no)
			(layer "B.CrtYd")
		)
		(fp_line
			(start 0.504 -0.248)
			(end -0.494 -0.248)
			(stroke
				(width 0.15)
				(type solid)
			)
			(layer "B.Fab")
		)
		(fp_line
			(start -0.494 -0.248)
			(end -0.494 0.25)
			(stroke
				(width 0.15)
				(type solid)
			)
			(layer "B.Fab")
		)
		(fp_line
			(start 0.504 0.25)
			(end 0.504 -0.248)
			(stroke
				(width 0.15)
				(type solid)
			)
			(layer "B.Fab")
		)
		(fp_line
			(start -0.494 0.25)
			(end 0.504 0.25)
			(stroke
				(width 0.15)
				(type solid)
			)
			(layer "B.Fab")
		)
		(pad "1" smd roundrect
			(at -0.48 0 90)
			(size 0.59 0.64)
			(layers "B.Cu" "B.Mask" "B.Paste")
			(roundrect_rratio 0.25)
			(net 1 "GND")
			(pintype "passive")
		)
		(pad "2" smd roundrect
			(at 0.48 0 90)
			(size 0.59 0.64)
			(layers "B.Cu" "B.Mask" "B.Paste")
			(roundrect_rratio 0.25)
			(net 2 "VCC3V3")
			(pintype "passive")
		)
	)
	(footprint "antmicro-footprints:C_0402_1005Metric"
		(layer "B.Cu")
		(at 121.875 109.36 90)
		(descr "Capacitor SMD 0402")
		(tags "capacitor SMD 0402")
		(property "Reference" "C23"
			(at 0.86 0.425 90)
			(layer "B.SilkS")
			(effects
				(font
					(size 0.7 0.7)
					(thickness 0.15)
				)
				(justify right bottom mirror)
			)
		)
		(property "Value" "C_4u7_0402"
			(at 0 -1.4 90)
			(layer "B.Fab")
			(effects
				(font
					(size 0.7 0.7)
					(thickness 0.15)
				)
				(justify right bottom mirror)
			)
		)
		(property "Datasheet" "https://www.murata.com/products/productdetail?partno=GRM155R61A475MEAA%23"
			(at 0 0 90)
			(layer "F.Fab")
			(hide yes)
			(effects
				(font
					(size 1.27 1.27)
					(thickness 0.15)
				)
			)
		)
		(property "Description" "SMD Multilayer Ceramic Capacitor, 4.7 µF, 10 V, 0402 [1005 Metric], ± 20%, X5R, GRM Series"
			(at 0 0 90)
			(layer "F.Fab")
			(hide yes)
			(effects
				(font
					(size 1.27 1.27)
					(thickness 0.15)
				)
			)
		)
		(property "Author" "Antmicro"
			(at 231.235 -12.515 0)
			(layer "B.Fab")
			(hide yes)
			(effects
				(font
					(size 1 1)
					(thickness 0.15)
				)
				(justify mirror)
			)
		)
		(property "Dielectric" ""
			(at 231.235 -12.515 0)
			(layer "B.Fab")
			(hide yes)
			(effects
				(font
					(size 1 1)
					(thickness 0.15)
				)
				(justify mirror)
			)
		)
		(property "License" "Apache-2.0"
			(at 231.235 -12.515 0)
			(layer "B.Fab")
			(hide yes)
			(effects
				(font
					(size 1 1)
					(thickness 0.15)
				)
				(justify mirror)
			)
		)
		(property "MPN" "GRM155R61A475MEAAD"
			(at 231.235 -12.515 0)
			(layer "B.Fab")
			(hide yes)
			(effects
				(font
					(size 1 1)
					(thickness 0.15)
				)
				(justify mirror)
			)
		)
		(property "Manufacturer" "Murata"
			(at 231.235 -12.515 0)
			(layer "B.Fab")
			(hide yes)
			(effects
				(font
					(size 1 1)
					(thickness 0.15)
				)
				(justify mirror)
			)
		)
		(property "Val" "4u7"
			(at 231.235 -12.515 0)
			(layer "B.Fab")
			(hide yes)
			(effects
				(font
					(size 1 1)
					(thickness 0.15)
				)
				(justify mirror)
			)
		)
		(property "Voltage" ""
			(at 231.235 -12.515 0)
			(layer "B.Fab")
			(hide yes)
			(effects
				(font
					(size 1 1)
					(thickness 0.15)
				)
				(justify mirror)
			)
		)
		(sheetname "/Interfaces/")
		(sheetfile "interfaces.kicad_sch")
		(attr smd)
		(fp_rect
			(start -0.925 0.47)
			(end 0.925 -0.47)
			(stroke
				(width 0.05)
				(type default)
			)
			(fill no)
			(layer "B.CrtYd")
		)
		(fp_line
			(start 0.504 -0.248)
			(end -0.494 -0.248)
			(stroke
				(width 0.15)
				(type solid)
			)
			(layer "B.Fab")
		)
		(fp_line
			(start -0.494 -0.248)
			(end -0.494 0.25)
			(stroke
				(width 0.15)
				(type solid)
			)
			(layer "B.Fab")
		)
		(fp_line
			(start 0.504 0.25)
			(end 0.504 -0.248)
			(stroke
				(width 0.15)
				(type solid)
			)
			(layer "B.Fab")
		)
		(fp_line
			(start -0.494 0.25)
			(end 0.504 0.25)
			(stroke
				(width 0.15)
				(type solid)
			)
			(layer "B.Fab")
		)
		(pad "1" smd roundrect
			(at -0.48 0 90)
			(size 0.59 0.64)
			(layers "B.Cu" "B.Mask" "B.Paste")
			(roundrect_rratio 0.25)
			(net 1 "GND")
			(pintype "passive")
		)
		(pad "2" smd roundrect
			(at 0.48 0 90)
			(size 0.59 0.64)
			(layers "B.Cu" "B.Mask" "B.Paste")
			(roundrect_rratio 0.25)
			(net 2 "VCC3V3")
			(pintype "passive")
		)
	)
	(footprint "antmicro-footprints:C_0402_1005Metric"
		(layer "B.Cu")
		(at 122.335 129.665 -90)
		(descr "Capacitor SMD 0402")
		(tags "capacitor SMD 0402")
		(property "Reference" "C24"
			(at 0.835 -0.385 90)
			(layer "B.SilkS")
			(effects
				(font
					(size 0.7 0.7)
					(thickness 0.15)
				)
				(justify left bottom mirror)
			)
		)
		(property "Value" "C_100n_0402"
			(at 0 -1.4 90)
			(layer "B.Fab")
			(effects
				(font
					(size 0.7 0.7)
					(thickness 0.15)
				)
				(justify left bottom mirror)
			)
		)
		(property "Datasheet" "https://www.murata.com/products/productdetail?partno=GRM155R61H104KE14%23"
			(at 0 0 270)
			(layer "F.Fab")
			(hide yes)
			(effects
				(font
					(size 1.27 1.27)
					(thickness 0.15)
				)
			)
		)
		(property "Description" "SMD Multilayer Ceramic Capacitor, 0.1 µF, 50 V, 0402 [1005 Metric], ± 10%, X5R, GRM Series"
			(at 0 0 270)
			(layer "F.Fab")
			(hide yes)
			(effects
				(font
					(size 1.27 1.27)
					(thickness 0.15)
				)
			)
		)
		(property "Author" "Antmicro"
			(at -7.33 252 0)
			(layer "B.Fab")
			(hide yes)
			(effects
				(font
					(size 1 1)
					(thickness 0.15)
				)
				(justify mirror)
			)
		)
		(property "Dielectric" "X5R"
			(at -7.33 252 0)
			(layer "B.Fab")
			(hide yes)
			(effects
				(font
					(size 1 1)
					(thickness 0.15)
				)
				(justify mirror)
			)
		)
		(property "License" "Apache-2.0"
			(at -7.33 252 0)
			(layer "B.Fab")
			(hide yes)
			(effects
				(font
					(size 1 1)
					(thickness 0.15)
				)
				(justify mirror)
			)
		)
		(property "MPN" "GRM155R61H104KE14D"
			(at -7.33 252 0)
			(layer "B.Fab")
			(hide yes)
			(effects
				(font
					(size 1 1)
					(thickness 0.15)
				)
				(justify mirror)
			)
		)
		(property "Manufacturer" "Murata"
			(at -7.33 252 0)
			(layer "B.Fab")
			(hide yes)
			(effects
				(font
					(size 1 1)
					(thickness 0.15)
				)
				(justify mirror)
			)
		)
		(property "Val" "100n"
			(at -7.33 252 0)
			(layer "B.Fab")
			(hide yes)
			(effects
				(font
					(size 1 1)
					(thickness 0.15)
				)
				(justify mirror)
			)
		)
		(property "Voltage" "50V"
			(at -7.33 252 0)
			(layer "B.Fab")
			(hide yes)
			(effects
				(font
					(size 1 1)
					(thickness 0.15)
				)
				(justify mirror)
			)
		)
		(sheetname "/Interfaces/")
		(sheetfile "interfaces.kicad_sch")
		(attr smd)
		(fp_rect
			(start -0.925 0.47)
			(end 0.925 -0.47)
			(stroke
				(width 0.05)
				(type default)
			)
			(fill no)
			(layer "B.CrtYd")
		)
		(fp_line
			(start -0.494 0.25)
			(end 0.504 0.25)
			(stroke
				(width 0.15)
				(type solid)
			)
			(layer "B.Fab")
		)
		(fp_line
			(start 0.504 0.25)
			(end 0.504 -0.248)
			(stroke
				(width 0.15)
				(type solid)
			)
			(layer "B.Fab")
		)
		(fp_line
			(start -0.494 -0.248)
			(end -0.494 0.25)
			(stroke
				(width 0.15)
				(type solid)
			)
			(layer "B.Fab")
		)
		(fp_line
			(start 0.504 -0.248)
			(end -0.494 -0.248)
			(stroke
				(width 0.15)
				(type solid)
			)
			(layer "B.Fab")
		)
		(pad "1" smd roundrect
			(at -0.48 0 270)
			(size 0.59 0.64)
			(layers "B.Cu" "B.Mask" "B.Paste")
			(roundrect_rratio 0.25)
			(net 1 "GND")
			(pintype "passive")
		)
		(pad "2" smd roundrect
			(at 0.48 0 270)
			(size 0.59 0.64)
			(layers "B.Cu" "B.Mask" "B.Paste")
			(roundrect_rratio 0.25)
			(net 2 "VCC3V3")
			(pintype "passive")
		)
	)
	(footprint "antmicro-footprints:C_0402_1005Metric"
		(layer "B.Cu")
		(at 124.9075 113.475 -90)
		(descr "Capacitor SMD 0402")
		(tags "capacitor SMD 0402")
		(property "Reference" "C25"
			(at 0.825 -0.31375 90)
			(layer "B.SilkS")
			(effects
				(font
					(size 0.7 0.7)
					(thickness 0.15)
				)
				(justify left bottom mirror)
			)
		)
		(property "Value" "C_100n_0402"
			(at 0 -1.4 90)
			(layer "B.Fab")
			(effects
				(font
					(size 0.7 0.7)
					(thickness 0.15)
				)
				(justify left bottom mirror)
			)
		)
		(property "Datasheet" "https://www.murata.com/products/productdetail?partno=GRM155R61H104KE14%23"
			(at 0 0 270)
			(layer "F.Fab")
			(hide yes)
			(effects
				(font
					(size 1.27 1.27)
					(thickness 0.15)
				)
			)
		)
		(property "Description" "SMD Multilayer Ceramic Capacitor, 0.1 µF, 50 V, 0402 [1005 Metric], ± 10%, X5R, GRM Series"
			(at 0 0 270)
			(layer "F.Fab")
			(hide yes)
			(effects
				(font
					(size 1.27 1.27)
					(thickness 0.15)
				)
			)
		)
		(property "Author" "Antmicro"
			(at 11.4325 238.3825 0)
			(layer "B.Fab")
			(hide yes)
			(effects
				(font
					(size 1 1)
					(thickness 0.15)
				)
				(justify mirror)
			)
		)
		(property "Dielectric" "X5R"
			(at 11.4325 238.3825 0)
			(layer "B.Fab")
			(hide yes)
			(effects
				(font
					(size 1 1)
					(thickness 0.15)
				)
				(justify mirror)
			)
		)
		(property "License" "Apache-2.0"
			(at 11.4325 238.3825 0)
			(layer "B.Fab")
			(hide yes)
			(effects
				(font
					(size 1 1)
					(thickness 0.15)
				)
				(justify mirror)
			)
		)
		(property "MPN" "GRM155R61H104KE14D"
			(at 11.4325 238.3825 0)
			(layer "B.Fab")
			(hide yes)
			(effects
				(font
					(size 1 1)
					(thickness 0.15)
				)
				(justify mirror)
			)
		)
		(property "Manufacturer" "Murata"
			(at 11.4325 238.3825 0)
			(layer "B.Fab")
			(hide yes)
			(effects
				(font
					(size 1 1)
					(thickness 0.15)
				)
				(justify mirror)
			)
		)
		(property "Val" "100n"
			(at 11.4325 238.3825 0)
			(layer "B.Fab")
			(hide yes)
			(effects
				(font
					(size 1 1)
					(thickness 0.15)
				)
				(justify mirror)
			)
		)
		(property "Voltage" "50V"
			(at 11.4325 238.3825 0)
			(layer "B.Fab")
			(hide yes)
			(effects
				(font
					(size 1 1)
					(thickness 0.15)
				)
				(justify mirror)
			)
		)
		(sheetname "/Interfaces/")
		(sheetfile "interfaces.kicad_sch")
		(attr smd)
		(fp_rect
			(start -0.925 0.47)
			(end 0.925 -0.47)
			(stroke
				(width 0.05)
				(type default)
			)
			(fill no)
			(layer "B.CrtYd")
		)
		(fp_line
			(start -0.494 0.25)
			(end 0.504 0.25)
			(stroke
				(width 0.15)
				(type solid)
			)
			(layer "B.Fab")
		)
		(fp_line
			(start 0.504 0.25)
			(end 0.504 -0.248)
			(stroke
				(width 0.15)
				(type solid)
			)
			(layer "B.Fab")
		)
		(fp_line
			(start -0.494 -0.248)
			(end -0.494 0.25)
			(stroke
				(width 0.15)
				(type solid)
			)
			(layer "B.Fab")
		)
		(fp_line
			(start 0.504 -0.248)
			(end -0.494 -0.248)
			(stroke
				(width 0.15)
				(type solid)
			)
			(layer "B.Fab")
		)
		(pad "1" smd roundrect
			(at -0.48 0 270)
			(size 0.59 0.64)
			(layers "B.Cu" "B.Mask" "B.Paste")
			(roundrect_rratio 0.25)
			(net 1 "GND")
			(pintype "passive")
		)
		(pad "2" smd roundrect
			(at 0.48 0 270)
			(size 0.59 0.64)
			(layers "B.Cu" "B.Mask" "B.Paste")
			(roundrect_rratio 0.25)
			(net 12 "Net-(U17-VDDA1.8)")
			(pintype "passive")
		)
	)
	(footprint "antmicro-footprints:C_0402_1005Metric"
		(layer "B.Cu")
		(at 124 125.4 90)
		(descr "Capacitor SMD 0402")
		(tags "capacitor SMD 0402")
		(property "Reference" "C26"
			(at 0.8 0.4 90)
			(layer "B.SilkS")
			(effects
				(font
					(size 0.7 0.7)
					(thickness 0.15)
				)
				(justify right bottom mirror)
			)
		)
		(property "Value" "C_100n_0402"
			(at 0 -1.4 90)
			(layer "B.Fab")
			(effects
				(font
					(size 0.7 0.7)
					(thickness 0.15)
				)
				(justify right bottom mirror)
			)
		)
		(property "Datasheet" "https://www.murata.com/products/productdetail?partno=GRM155R61H104KE14%23"
			(at 0 0 90)
			(layer "F.Fab")
			(hide yes)
			(effects
				(font
					(size 1.27 1.27)
					(thickness 0.15)
				)
			)
		)
		(property "Description" "SMD Multilayer Ceramic Capacitor, 0.1 µF, 50 V, 0402 [1005 Metric], ± 10%, X5R, GRM Series"
			(at 0 0 90)
			(layer "F.Fab")
			(hide yes)
			(effects
				(font
					(size 1.27 1.27)
					(thickness 0.15)
				)
			)
		)
		(property "Author" "Antmicro"
			(at 249.4 1.4 0)
			(layer "B.Fab")
			(hide yes)
			(effects
				(font
					(size 1 1)
					(thickness 0.15)
				)
				(justify mirror)
			)
		)
		(property "Dielectric" "X5R"
			(at 249.4 1.4 0)
			(layer "B.Fab")
			(hide yes)
			(effects
				(font
					(size 1 1)
					(thickness 0.15)
				)
				(justify mirror)
			)
		)
		(property "License" "Apache-2.0"
			(at 249.4 1.4 0)
			(layer "B.Fab")
			(hide yes)
			(effects
				(font
					(size 1 1)
					(thickness 0.15)
				)
				(justify mirror)
			)
		)
		(property "MPN" "GRM155R61H104KE14D"
			(at 249.4 1.4 0)
			(layer "B.Fab")
			(hide yes)
			(effects
				(font
					(size 1 1)
					(thickness 0.15)
				)
				(justify mirror)
			)
		)
		(property "Manufacturer" "Murata"
			(at 249.4 1.4 0)
			(layer "B.Fab")
			(hide yes)
			(effects
				(font
					(size 1 1)
					(thickness 0.15)
				)
				(justify mirror)
			)
		)
		(property "Val" "100n"
			(at 249.4 1.4 0)
			(layer "B.Fab")
			(hide yes)
			(effects
				(font
					(size 1 1)
					(thickness 0.15)
				)
				(justify mirror)
			)
		)
		(property "Voltage" "50V"
			(at 249.4 1.4 0)
			(layer "B.Fab")
			(hide yes)
			(effects
				(font
					(size 1 1)
					(thickness 0.15)
				)
				(justify mirror)
			)
		)
		(sheetname "/Interfaces/")
		(sheetfile "interfaces.kicad_sch")
		(attr smd)
		(fp_rect
			(start -0.925 0.47)
			(end 0.925 -0.47)
			(stroke
				(width 0.05)
				(type default)
			)
			(fill no)
			(layer "B.CrtYd")
		)
		(fp_line
			(start 0.504 -0.248)
			(end -0.494 -0.248)
			(stroke
				(width 0.15)
				(type solid)
			)
			(layer "B.Fab")
		)
		(fp_line
			(start -0.494 -0.248)
			(end -0.494 0.25)
			(stroke
				(width 0.15)
				(type solid)
			)
			(layer "B.Fab")
		)
		(fp_line
			(start 0.504 0.25)
			(end 0.504 -0.248)
			(stroke
				(width 0.15)
				(type solid)
			)
			(layer "B.Fab")
		)
		(fp_line
			(start -0.494 0.25)
			(end 0.504 0.25)
			(stroke
				(width 0.15)
				(type solid)
			)
			(layer "B.Fab")
		)
		(pad "1" smd roundrect
			(at -0.48 0 90)
			(size 0.59 0.64)
			(layers "B.Cu" "B.Mask" "B.Paste")
			(roundrect_rratio 0.25)
			(net 1 "GND")
			(pintype "passive")
		)
		(pad "2" smd roundrect
			(at 0.48 0 90)
			(size 0.59 0.64)
			(layers "B.Cu" "B.Mask" "B.Paste")
			(roundrect_rratio 0.25)
			(net 108 "Net-(C177-Pad2)")
			(pintype "passive")
		)
	)
	(footprint "antmicro-footprints:C_0402_1005Metric"
		(layer "B.Cu")
		(at 100.2 98.12 -90)
		(descr "Capacitor SMD 0402")
		(tags "capacitor SMD 0402")
		(property "Reference" "C218"
			(at -3.62 -0.3 90)
			(layer "B.SilkS")
			(effects
				(font
					(size 0.7 0.7)
					(thickness 0.15)
				)
				(justify left bottom mirror)
			)
		)
		(property "Value" "C_10n_0402"
			(at 0 -1.4 90)
			(layer "B.Fab")
			(effects
				(font
					(size 0.7 0.7)
					(thickness 0.15)
				)
				(justify left bottom mirror)
			)
		)
		(property "Datasheet" "https://www.murata.com/products/productdetail?partno=GRM155R71H103KA88%23"
			(at 0 0 270)
			(layer "F.Fab")
			(hide yes)
			(effects
				(font
					(size 1.27 1.27)
					(thickness 0.15)
				)
			)
		)
		(property "Description" "SMD Multilayer Ceramic Capacitor, 10000 pF, 50 V, 0402 [1005 Metric], ± 10%, X7R, GRM Series"
			(at 0 0 270)
			(layer "F.Fab")
			(hide yes)
			(effects
				(font
					(size 1.27 1.27)
					(thickness 0.15)
				)
			)
		)
		(property "Author" "Antmicro"
			(at 2.08 198.32 0)
			(layer "B.Fab")
			(hide yes)
			(effects
				(font
					(size 1 1)
					(thickness 0.15)
				)
				(justify mirror)
			)
		)
		(property "Dielectric" "X7R"
			(at 2.08 198.32 0)
			(layer "B.Fab")
			(hide yes)
			(effects
				(font
					(size 1 1)
					(thickness 0.15)
				)
				(justify mirror)
			)
		)
		(property "License" "Apache-2.0"
			(at 2.08 198.32 0)
			(layer "B.Fab")
			(hide yes)
			(effects
				(font
					(size 1 1)
					(thickness 0.15)
				)
				(justify mirror)
			)
		)
		(property "MPN" "GRM155R71H103KA88D"
			(at 2.08 198.32 0)
			(layer "B.Fab")
			(hide yes)
			(effects
				(font
					(size 1 1)
					(thickness 0.15)
				)
				(justify mirror)
			)
		)
		(property "Manufacturer" "Murata"
			(at 2.08 198.32 0)
			(layer "B.Fab")
			(hide yes)
			(effects
				(font
					(size 1 1)
					(thickness 0.15)
				)
				(justify mirror)
			)
		)
		(property "Val" "10n"
			(at 2.08 198.32 0)
			(layer "B.Fab")
			(hide yes)
			(effects
				(font
					(size 1 1)
					(thickness 0.15)
				)
				(justify mirror)
			)
		)
		(property "Voltage" "50V"
			(at 2.08 198.32 0)
			(layer "B.Fab")
			(hide yes)
			(effects
				(font
					(size 1 1)
					(thickness 0.15)
				)
				(justify mirror)
			)
		)
		(sheetname "/Ethernet/")
		(sheetfile "ethernet.kicad_sch")
		(attr smd)
		(fp_rect
			(start -0.925 0.47)
			(end 0.925 -0.47)
			(stroke
				(width 0.05)
				(type default)
			)
			(fill no)
			(layer "B.CrtYd")
		)
		(fp_line
			(start -0.494 0.25)
			(end 0.504 0.25)
			(stroke
				(width 0.15)
				(type solid)
			)
			(layer "B.Fab")
		)
		(fp_line
			(start 0.504 0.25)
			(end 0.504 -0.248)
			(stroke
				(width 0.15)
				(type solid)
			)
			(layer "B.Fab")
		)
		(fp_line
			(start -0.494 -0.248)
			(end -0.494 0.25)
			(stroke
				(width 0.15)
				(type solid)
			)
			(layer "B.Fab")
		)
		(fp_line
			(start 0.504 -0.248)
			(end -0.494 -0.248)
			(stroke
				(width 0.15)
				(type solid)
			)
			(layer "B.Fab")
		)
		(pad "1" smd roundrect
			(at -0.48 0 270)
			(size 0.59 0.64)
			(layers "B.Cu" "B.Mask" "B.Paste")
			(roundrect_rratio 0.25)
			(net 1 "GND")
			(pintype "passive")
		)
		(pad "2" smd roundrect
			(at 0.48 0 270)
			(size 0.59 0.64)
			(layers "B.Cu" "B.Mask" "B.Paste")
			(roundrect_rratio 0.25)
			(net 339 "VCC1V2")
			(pintype "passive")
		)
	)
	(footprint "antmicro-footprints:C_0402_1005Metric"
		(layer "B.Cu")
		(at 125.395 129.665 -90)
		(descr "Capacitor SMD 0402")
		(tags "capacitor SMD 0402")
		(property "Reference" "C22"
			(at 0.835 -0.385 90)
			(layer "B.SilkS")
			(effects
				(font
					(size 0.7 0.7)
					(thickness 0.15)
				)
				(justify left bottom mirror)
			)
		)
		(property "Value" "C_100n_0402"
			(at 0 -1.4 90)
			(layer "B.Fab")
			(effects
				(font
					(size 0.7 0.7)
					(thickness 0.15)
				)
				(justify left bottom mirror)
			)
		)
		(property "Datasheet" "https://www.murata.com/products/productdetail?partno=GRM155R61H104KE14%23"
			(at 0 0 270)
			(layer "F.Fab")
			(hide yes)
			(effects
				(font
					(size 1.27 1.27)
					(thickness 0.15)
				)
			)
		)
		(property "Description" "SMD Multilayer Ceramic Capacitor, 0.1 µF, 50 V, 0402 [1005 Metric], ± 10%, X5R, GRM Series"
			(at 0 0 270)
			(layer "F.Fab")
			(hide yes)
			(effects
				(font
					(size 1.27 1.27)
					(thickness 0.15)
				)
			)
		)
		(property "Author" "Antmicro"
			(at -4.27 255.06 0)
			(layer "B.Fab")
			(hide yes)
			(effects
				(font
					(size 1 1)
					(thickness 0.15)
				)
				(justify mirror)
			)
		)
		(property "Dielectric" "X5R"
			(at -4.27 255.06 0)
			(layer "B.Fab")
			(hide yes)
			(effects
				(font
					(size 1 1)
					(thickness 0.15)
				)
				(justify mirror)
			)
		)
		(property "License" "Apache-2.0"
			(at -4.27 255.06 0)
			(layer "B.Fab")
			(hide yes)
			(effects
				(font
					(size 1 1)
					(thickness 0.15)
				)
				(justify mirror)
			)
		)
		(property "MPN" "GRM155R61H104KE14D"
			(at -4.27 255.06 0)
			(layer "B.Fab")
			(hide yes)
			(effects
				(font
					(size 1 1)
					(thickness 0.15)
				)
				(justify mirror)
			)
		)
		(property "Manufacturer" "Murata"
			(at -4.27 255.06 0)
			(layer "B.Fab")
			(hide yes)
			(effects
				(font
					(size 1 1)
					(thickness 0.15)
				)
				(justify mirror)
			)
		)
		(property "Val" "100n"
			(at -4.27 255.06 0)
			(layer "B.Fab")
			(hide yes)
			(effects
				(font
					(size 1 1)
					(thickness 0.15)
				)
				(justify mirror)
			)
		)
		(property "Voltage" "50V"
			(at -4.27 255.06 0)
			(layer "B.Fab")
			(hide yes)
			(effects
				(font
					(size 1 1)
					(thickness 0.15)
				)
				(justify mirror)
			)
		)
		(sheetname "/Interfaces/")
		(sheetfile "interfaces.kicad_sch")
		(attr smd)
		(fp_rect
			(start -0.925 0.47)
			(end 0.925 -0.47)
			(stroke
				(width 0.05)
				(type default)
			)
			(fill no)
			(layer "B.CrtYd")
		)
		(fp_line
			(start -0.494 0.25)
			(end 0.504 0.25)
			(stroke
				(width 0.15)
				(type solid)
			)
			(layer "B.Fab")
		)
		(fp_line
			(start 0.504 0.25)
			(end 0.504 -0.248)
			(stroke
				(width 0.15)
				(type solid)
			)
			(layer "B.Fab")
		)
		(fp_line
			(start -0.494 -0.248)
			(end -0.494 0.25)
			(stroke
				(width 0.15)
				(type solid)
			)
			(layer "B.Fab")
		)
		(fp_line
			(start 0.504 -0.248)
			(end -0.494 -0.248)
			(stroke
				(width 0.15)
				(type solid)
			)
			(layer "B.Fab")
		)
		(pad "1" smd roundrect
			(at -0.48 0 270)
			(size 0.59 0.64)
			(layers "B.Cu" "B.Mask" "B.Paste")
			(roundrect_rratio 0.25)
			(net 1 "GND")
			(pintype "passive")
		)
		(pad "2" smd roundrect
			(at 0.48 0 270)
			(size 0.59 0.64)
			(layers "B.Cu" "B.Mask" "B.Paste")
			(roundrect_rratio 0.25)
			(net 11 "Net-(U18-VDDA1.8)")
			(pintype "passive")
		)
	)
	(footprint "antmicro-footprints:C_0402_1005Metric"
		(layer "B.Cu")
		(at 107.725 95.55 180)
		(descr "Capacitor SMD 0402")
		(tags "capacitor SMD 0402")
		(property "Reference" "C199"
			(at -5.875 2.8 0)
			(layer "B.SilkS")
			(effects
				(font
					(size 0.7 0.7)
					(thickness 0.15)
				)
				(justify left bottom mirror)
			)
		)
		(property "Value" "C_4u7_0402"
			(at 0 -1.4 0)
			(layer "B.Fab")
			(effects
				(font
					(size 0.7 0.7)
					(thickness 0.15)
				)
				(justify left bottom mirror)
			)
		)
		(property "Datasheet" "https://www.murata.com/products/productdetail?partno=GRM155R61A475MEAA%23"
			(at 0 0 180)
			(layer "F.Fab")
			(hide yes)
			(effects
				(font
					(size 1.27 1.27)
					(thickness 0.15)
				)
			)
		)
		(property "Description" "SMD Multilayer Ceramic Capacitor, 4.7 µF, 10 V, 0402 [1005 Metric], ± 20%, X5R, GRM Series"
			(at 0 0 180)
			(layer "F.Fab")
			(hide yes)
			(effects
				(font
					(size 1.27 1.27)
					(thickness 0.15)
				)
			)
		)
		(property "Author" "Antmicro"
			(at 215.45 191.1 0)
			(layer "B.Fab")
			(hide yes)
			(effects
				(font
					(size 1 1)
					(thickness 0.15)
				)
				(justify mirror)
			)
		)
		(property "Dielectric" ""
			(at 215.45 191.1 0)
			(layer "B.Fab")
			(hide yes)
			(effects
				(font
					(size 1 1)
					(thickness 0.15)
				)
				(justify mirror)
			)
		)
		(property "License" "Apache-2.0"
			(at 215.45 191.1 0)
			(layer "B.Fab")
			(hide yes)
			(effects
				(font
					(size 1 1)
					(thickness 0.15)
				)
				(justify mirror)
			)
		)
		(property "MPN" "GRM155R61A475MEAAD"
			(at 215.45 191.1 0)
			(layer "B.Fab")
			(hide yes)
			(effects
				(font
					(size 1 1)
					(thickness 0.15)
				)
				(justify mirror)
			)
		)
		(property "Manufacturer" "Murata"
			(at 215.45 191.1 0)
			(layer "B.Fab")
			(hide yes)
			(effects
				(font
					(size 1 1)
					(thickness 0.15)
				)
				(justify mirror)
			)
		)
		(property "Val" "4u7"
			(at 215.45 191.1 0)
			(layer "B.Fab")
			(hide yes)
			(effects
				(font
					(size 1 1)
					(thickness 0.15)
				)
				(justify mirror)
			)
		)
		(property "Voltage" ""
			(at 215.45 191.1 0)
			(layer "B.Fab")
			(hide yes)
			(effects
				(font
					(size 1 1)
					(thickness 0.15)
				)
				(justify mirror)
			)
		)
		(sheetname "/Ethernet/")
		(sheetfile "ethernet.kicad_sch")
		(attr smd)
		(fp_rect
			(start -0.925 0.47)
			(end 0.925 -0.47)
			(stroke
				(width 0.05)
				(type default)
			)
			(fill no)
			(layer "B.CrtYd")
		)
		(fp_line
			(start 0.504 0.25)
			(end 0.504 -0.248)
			(stroke
				(width 0.15)
				(type solid)
			)
			(layer "B.Fab")
		)
		(fp_line
			(start 0.504 -0.248)
			(end -0.494 -0.248)
			(stroke
				(width 0.15)
				(type solid)
			)
			(layer "B.Fab")
		)
		(fp_line
			(start -0.494 0.25)
			(end 0.504 0.25)
			(stroke
				(width 0.15)
				(type solid)
			)
			(layer "B.Fab")
		)
		(fp_line
			(start -0.494 -0.248)
			(end -0.494 0.25)
			(stroke
				(width 0.15)
				(type solid)
			)
			(layer "B.Fab")
		)
		(pad "1" smd roundrect
			(at -0.48 0 180)
			(size 0.59 0.64)
			(layers "B.Cu" "B.Mask" "B.Paste")
			(roundrect_rratio 0.25)
			(net 1 "GND")
			(pintype "passive")
		)
		(pad "2" smd roundrect
			(at 0.48 0 180)
			(size 0.59 0.64)
			(layers "B.Cu" "B.Mask" "B.Paste")
			(roundrect_rratio 0.25)
			(net 404 "/Ethernet/AVDDL_PLL")
			(pintype "passive")
		)
	)
	(footprint "antmicro-footprints:C_0402_1005Metric"
		(layer "B.Cu")
		(at 107.725 94.6 180)
		(descr "Capacitor SMD 0402")
		(tags "capacitor SMD 0402")
		(property "Reference" "C203"
			(at -5.875 2.8 0)
			(layer "B.SilkS")
			(effects
				(font
					(size 0.7 0.7)
					(thickness 0.15)
				)
				(justify left bottom mirror)
			)
		)
		(property "Value" "C_100n_0402"
			(at 0 -1.4 0)
			(layer "B.Fab")
			(effects
				(font
					(size 0.7 0.7)
					(thickness 0.15)
				)
				(justify left bottom mirror)
			)
		)
		(property "Datasheet" "https://www.murata.com/products/productdetail?partno=GRM155R61H104KE14%23"
			(at 0 0 180)
			(layer "F.Fab")
			(hide yes)
			(effects
				(font
					(size 1.27 1.27)
					(thickness 0.15)
				)
			)
		)
		(property "Description" "SMD Multilayer Ceramic Capacitor, 0.1 µF, 50 V, 0402 [1005 Metric], ± 10%, X5R, GRM Series"
			(at 0 0 180)
			(layer "F.Fab")
			(hide yes)
			(effects
				(font
					(size 1.27 1.27)
					(thickness 0.15)
				)
			)
		)
		(property "Author" "Antmicro"
			(at 215.45 189.2 0)
			(layer "B.Fab")
			(hide yes)
			(effects
				(font
					(size 1 1)
					(thickness 0.15)
				)
				(justify mirror)
			)
		)
		(property "Dielectric" "X5R"
			(at 215.45 189.2 0)
			(layer "B.Fab")
			(hide yes)
			(effects
				(font
					(size 1 1)
					(thickness 0.15)
				)
				(justify mirror)
			)
		)
		(property "License" "Apache-2.0"
			(at 215.45 189.2 0)
			(layer "B.Fab")
			(hide yes)
			(effects
				(font
					(size 1 1)
					(thickness 0.15)
				)
				(justify mirror)
			)
		)
		(property "MPN" "GRM155R61H104KE14D"
			(at 215.45 189.2 0)
			(layer "B.Fab")
			(hide yes)
			(effects
				(font
					(size 1 1)
					(thickness 0.15)
				)
				(justify mirror)
			)
		)
		(property "Manufacturer" "Murata"
			(at 215.45 189.2 0)
			(layer "B.Fab")
			(hide yes)
			(effects
				(font
					(size 1 1)
					(thickness 0.15)
				)
				(justify mirror)
			)
		)
		(property "Val" "100n"
			(at 215.45 189.2 0)
			(layer "B.Fab")
			(hide yes)
			(effects
				(font
					(size 1 1)
					(thickness 0.15)
				)
				(justify mirror)
			)
		)
		(property "Voltage" "50V"
			(at 215.45 189.2 0)
			(layer "B.Fab")
			(hide yes)
			(effects
				(font
					(size 1 1)
					(thickness 0.15)
				)
				(justify mirror)
			)
		)
		(sheetname "/Ethernet/")
		(sheetfile "ethernet.kicad_sch")
		(attr smd)
		(fp_rect
			(start -0.925 0.47)
			(end 0.925 -0.47)
			(stroke
				(width 0.05)
				(type default)
			)
			(fill no)
			(layer "B.CrtYd")
		)
		(fp_line
			(start 0.504 0.25)
			(end 0.504 -0.248)
			(stroke
				(width 0.15)
				(type solid)
			)
			(layer "B.Fab")
		)
		(fp_line
			(start 0.504 -0.248)
			(end -0.494 -0.248)
			(stroke
				(width 0.15)
				(type solid)
			)
			(layer "B.Fab")
		)
		(fp_line
			(start -0.494 0.25)
			(end 0.504 0.25)
			(stroke
				(width 0.15)
				(type solid)
			)
			(layer "B.Fab")
		)
		(fp_line
			(start -0.494 -0.248)
			(end -0.494 0.25)
			(stroke
				(width 0.15)
				(type solid)
			)
			(layer "B.Fab")
		)
		(pad "1" smd roundrect
			(at -0.48 0 180)
			(size 0.59 0.64)
			(layers "B.Cu" "B.Mask" "B.Paste")
			(roundrect_rratio 0.25)
			(net 1 "GND")
			(pintype "passive")
		)
		(pad "2" smd roundrect
			(at 0.48 0 180)
			(size 0.59 0.64)
			(layers "B.Cu" "B.Mask" "B.Paste")
			(roundrect_rratio 0.25)
			(net 404 "/Ethernet/AVDDL_PLL")
			(pintype "passive")
		)
	)
	(footprint "antmicro-footprints:C_0402_1005Metric"
		(layer "B.Cu")
		(at 107.725 97.45 180)
		(descr "Capacitor SMD 0402")
		(tags "capacitor SMD 0402")
		(property "Reference" "C207"
			(at -5.875 2.8 0)
			(layer "B.SilkS")
			(effects
				(font
					(size 0.7 0.7)
					(thickness 0.15)
				)
				(justify left bottom mirror)
			)
		)
		(property "Value" "C_10n_0402"
			(at 0 -1.4 0)
			(layer "B.Fab")
			(effects
				(font
					(size 0.7 0.7)
					(thickness 0.15)
				)
				(justify left bottom mirror)
			)
		)
		(property "Datasheet" "https://www.murata.com/products/productdetail?partno=GRM155R71H103KA88%23"
			(at 0 0 180)
			(layer "F.Fab")
			(hide yes)
			(effects
				(font
					(size 1.27 1.27)
					(thickness 0.15)
				)
			)
		)
		(property "Description" "SMD Multilayer Ceramic Capacitor, 10000 pF, 50 V, 0402 [1005 Metric], ± 10%, X7R, GRM Series"
			(at 0 0 180)
			(layer "F.Fab")
			(hide yes)
			(effects
				(font
					(size 1.27 1.27)
					(thickness 0.15)
				)
			)
		)
		(property "Author" "Antmicro"
			(at 215.45 194.9 0)
			(layer "B.Fab")
			(hide yes)
			(effects
				(font
					(size 1 1)
					(thickness 0.15)
				)
				(justify mirror)
			)
		)
		(property "Dielectric" "X7R"
			(at 215.45 194.9 0)
			(layer "B.Fab")
			(hide yes)
			(effects
				(font
					(size 1 1)
					(thickness 0.15)
				)
				(justify mirror)
			)
		)
		(property "License" "Apache-2.0"
			(at 215.45 194.9 0)
			(layer "B.Fab")
			(hide yes)
			(effects
				(font
					(size 1 1)
					(thickness 0.15)
				)
				(justify mirror)
			)
		)
		(property "MPN" "GRM155R71H103KA88D"
			(at 215.45 194.9 0)
			(layer "B.Fab")
			(hide yes)
			(effects
				(font
					(size 1 1)
					(thickness 0.15)
				)
				(justify mirror)
			)
		)
		(property "Manufacturer" "Murata"
			(at 215.45 194.9 0)
			(layer "B.Fab")
			(hide yes)
			(effects
				(font
					(size 1 1)
					(thickness 0.15)
				)
				(justify mirror)
			)
		)
		(property "Val" "10n"
			(at 215.45 194.9 0)
			(layer "B.Fab")
			(hide yes)
			(effects
				(font
					(size 1 1)
					(thickness 0.15)
				)
				(justify mirror)
			)
		)
		(property "Voltage" "50V"
			(at 215.45 194.9 0)
			(layer "B.Fab")
			(hide yes)
			(effects
				(font
					(size 1 1)
					(thickness 0.15)
				)
				(justify mirror)
			)
		)
		(sheetname "/Ethernet/")
		(sheetfile "ethernet.kicad_sch")
		(attr smd)
		(fp_rect
			(start -0.925 0.47)
			(end 0.925 -0.47)
			(stroke
				(width 0.05)
				(type default)
			)
			(fill no)
			(layer "B.CrtYd")
		)
		(fp_line
			(start 0.504 0.25)
			(end 0.504 -0.248)
			(stroke
				(width 0.15)
				(type solid)
			)
			(layer "B.Fab")
		)
		(fp_line
			(start 0.504 -0.248)
			(end -0.494 -0.248)
			(stroke
				(width 0.15)
				(type solid)
			)
			(layer "B.Fab")
		)
		(fp_line
			(start -0.494 0.25)
			(end 0.504 0.25)
			(stroke
				(width 0.15)
				(type solid)
			)
			(layer "B.Fab")
		)
		(fp_line
			(start -0.494 -0.248)
			(end -0.494 0.25)
			(stroke
				(width 0.15)
				(type solid)
			)
			(layer "B.Fab")
		)
		(pad "1" smd roundrect
			(at -0.48 0 180)
			(size 0.59 0.64)
			(layers "B.Cu" "B.Mask" "B.Paste")
			(roundrect_rratio 0.25)
			(net 1 "GND")
			(pintype "passive")
		)
		(pad "2" smd roundrect
			(at 0.48 0 180)
			(size 0.59 0.64)
			(layers "B.Cu" "B.Mask" "B.Paste")
			(roundrect_rratio 0.25)
			(net 2 "VCC3V3")
			(pintype "passive")
		)
	)
	(footprint "antmicro-footprints:C_0402_1005Metric"
		(layer "B.Cu")
		(at 107.725 96.5 180)
		(descr "Capacitor SMD 0402")
		(tags "capacitor SMD 0402")
		(property "Reference" "C208"
			(at -5.875 2.8 0)
			(layer "B.SilkS")
			(effects
				(font
					(size 0.7 0.7)
					(thickness 0.15)
				)
				(justify left bottom mirror)
			)
		)
		(property "Value" "C_10n_0402"
			(at 0 -1.4 0)
			(layer "B.Fab")
			(effects
				(font
					(size 0.7 0.7)
					(thickness 0.15)
				)
				(justify left bottom mirror)
			)
		)
		(property "Datasheet" "https://www.murata.com/products/productdetail?partno=GRM155R71H103KA88%23"
			(at 0 0 180)
			(layer "F.Fab")
			(hide yes)
			(effects
				(font
					(size 1.27 1.27)
					(thickness 0.15)
				)
			)
		)
		(property "Description" "SMD Multilayer Ceramic Capacitor, 10000 pF, 50 V, 0402 [1005 Metric], ± 10%, X7R, GRM Series"
			(at 0 0 180)
			(layer "F.Fab")
			(hide yes)
			(effects
				(font
					(size 1.27 1.27)
					(thickness 0.15)
				)
			)
		)
		(property "Author" "Antmicro"
			(at 215.45 193 0)
			(layer "B.Fab")
			(hide yes)
			(effects
				(font
					(size 1 1)
					(thickness 0.15)
				)
				(justify mirror)
			)
		)
		(property "Dielectric" "X7R"
			(at 215.45 193 0)
			(layer "B.Fab")
			(hide yes)
			(effects
				(font
					(size 1 1)
					(thickness 0.15)
				)
				(justify mirror)
			)
		)
		(property "License" "Apache-2.0"
			(at 215.45 193 0)
			(layer "B.Fab")
			(hide yes)
			(effects
				(font
					(size 1 1)
					(thickness 0.15)
				)
				(justify mirror)
			)
		)
		(property "MPN" "GRM155R71H103KA88D"
			(at 215.45 193 0)
			(layer "B.Fab")
			(hide yes)
			(effects
				(font
					(size 1 1)
					(thickness 0.15)
				)
				(justify mirror)
			)
		)
		(property "Manufacturer" "Murata"
			(at 215.45 193 0)
			(layer "B.Fab")
			(hide yes)
			(effects
				(font
					(size 1 1)
					(thickness 0.15)
				)
				(justify mirror)
			)
		)
		(property "Val" "10n"
			(at 215.45 193 0)
			(layer "B.Fab")
			(hide yes)
			(effects
				(font
					(size 1 1)
					(thickness 0.15)
				)
				(justify mirror)
			)
		)
		(property "Voltage" "50V"
			(at 215.45 193 0)
			(layer "B.Fab")
			(hide yes)
			(effects
				(font
					(size 1 1)
					(thickness 0.15)
				)
				(justify mirror)
			)
		)
		(sheetname "/Ethernet/")
		(sheetfile "ethernet.kicad_sch")
		(attr smd)
		(fp_rect
			(start -0.925 0.47)
			(end 0.925 -0.47)
			(stroke
				(width 0.05)
				(type default)
			)
			(fill no)
			(layer "B.CrtYd")
		)
		(fp_line
			(start 0.504 0.25)
			(end 0.504 -0.248)
			(stroke
				(width 0.15)
				(type solid)
			)
			(layer "B.Fab")
		)
		(fp_line
			(start 0.504 -0.248)
			(end -0.494 -0.248)
			(stroke
				(width 0.15)
				(type solid)
			)
			(layer "B.Fab")
		)
		(fp_line
			(start -0.494 0.25)
			(end 0.504 0.25)
			(stroke
				(width 0.15)
				(type solid)
			)
			(layer "B.Fab")
		)
		(fp_line
			(start -0.494 -0.248)
			(end -0.494 0.25)
			(stroke
				(width 0.15)
				(type solid)
			)
			(layer "B.Fab")
		)
		(pad "1" smd roundrect
			(at -0.48 0 180)
			(size 0.59 0.64)
			(layers "B.Cu" "B.Mask" "B.Paste")
			(roundrect_rratio 0.25)
			(net 1 "GND")
			(pintype "passive")
		)
		(pad "2" smd roundrect
			(at 0.48 0 180)
			(size 0.59 0.64)
			(layers "B.Cu" "B.Mask" "B.Paste")
			(roundrect_rratio 0.25)
			(net 404 "/Ethernet/AVDDL_PLL")
			(pintype "passive")
		)
	)
	(footprint "antmicro-footprints:C_0402_1005Metric"
		(layer "B.Cu")
		(at 107.725 98.4 180)
		(descr "Capacitor SMD 0402")
		(tags "capacitor SMD 0402")
		(property "Reference" "C214"
			(at -5.875 2.8 0)
			(layer "B.SilkS")
			(effects
				(font
					(size 0.7 0.7)
					(thickness 0.15)
				)
				(justify left bottom mirror)
			)
		)
		(property "Value" "C_10n_0402"
			(at 0 -1.4 0)
			(layer "B.Fab")
			(effects
				(font
					(size 0.7 0.7)
					(thickness 0.15)
				)
				(justify left bottom mirror)
			)
		)
		(property "Datasheet" "https://www.murata.com/products/productdetail?partno=GRM155R71H103KA88%23"
			(at 0 0 180)
			(layer "F.Fab")
			(hide yes)
			(effects
				(font
					(size 1.27 1.27)
					(thickness 0.15)
				)
			)
		)
		(property "Description" "SMD Multilayer Ceramic Capacitor, 10000 pF, 50 V, 0402 [1005 Metric], ± 10%, X7R, GRM Series"
			(at 0 0 180)
			(layer "F.Fab")
			(hide yes)
			(effects
				(font
					(size 1.27 1.27)
					(thickness 0.15)
				)
			)
		)
		(property "Author" "Antmicro"
			(at 215.45 196.8 0)
			(layer "B.Fab")
			(hide yes)
			(effects
				(font
					(size 1 1)
					(thickness 0.15)
				)
				(justify mirror)
			)
		)
		(property "Dielectric" "X7R"
			(at 215.45 196.8 0)
			(layer "B.Fab")
			(hide yes)
			(effects
				(font
					(size 1 1)
					(thickness 0.15)
				)
				(justify mirror)
			)
		)
		(property "License" "Apache-2.0"
			(at 215.45 196.8 0)
			(layer "B.Fab")
			(hide yes)
			(effects
				(font
					(size 1 1)
					(thickness 0.15)
				)
				(justify mirror)
			)
		)
		(property "MPN" "GRM155R71H103KA88D"
			(at 215.45 196.8 0)
			(layer "B.Fab")
			(hide yes)
			(effects
				(font
					(size 1 1)
					(thickness 0.15)
				)
				(justify mirror)
			)
		)
		(property "Manufacturer" "Murata"
			(at 215.45 196.8 0)
			(layer "B.Fab")
			(hide yes)
			(effects
				(font
					(size 1 1)
					(thickness 0.15)
				)
				(justify mirror)
			)
		)
		(property "Val" "10n"
			(at 215.45 196.8 0)
			(layer "B.Fab")
			(hide yes)
			(effects
				(font
					(size 1 1)
					(thickness 0.15)
				)
				(justify mirror)
			)
		)
		(property "Voltage" "50V"
			(at 215.45 196.8 0)
			(layer "B.Fab")
			(hide yes)
			(effects
				(font
					(size 1 1)
					(thickness 0.15)
				)
				(justify mirror)
			)
		)
		(sheetname "/Ethernet/")
		(sheetfile "ethernet.kicad_sch")
		(attr smd)
		(fp_rect
			(start -0.925 0.47)
			(end 0.925 -0.47)
			(stroke
				(width 0.05)
				(type default)
			)
			(fill no)
			(layer "B.CrtYd")
		)
		(fp_line
			(start 0.504 0.25)
			(end 0.504 -0.248)
			(stroke
				(width 0.15)
				(type solid)
			)
			(layer "B.Fab")
		)
		(fp_line
			(start 0.504 -0.248)
			(end -0.494 -0.248)
			(stroke
				(width 0.15)
				(type solid)
			)
			(layer "B.Fab")
		)
		(fp_line
			(start -0.494 0.25)
			(end 0.504 0.25)
			(stroke
				(width 0.15)
				(type solid)
			)
			(layer "B.Fab")
		)
		(fp_line
			(start -0.494 -0.248)
			(end -0.494 0.25)
			(stroke
				(width 0.15)
				(type solid)
			)
			(layer "B.Fab")
		)
		(pad "1" smd roundrect
			(at -0.48 0 180)
			(size 0.59 0.64)
			(layers "B.Cu" "B.Mask" "B.Paste")
			(roundrect_rratio 0.25)
			(net 1 "GND")
			(pintype "passive")
		)
		(pad "2" smd roundrect
			(at 0.48 0 180)
			(size 0.59 0.64)
			(layers "B.Cu" "B.Mask" "B.Paste")
			(roundrect_rratio 0.25)
			(net 339 "VCC1V2")
			(pintype "passive")
		)
	)
	(footprint "antmicro-footprints:FB_0603_1608Metric"
		(layer "B.Cu")
		(at 108.019 93.327)
		(property "Reference" "FB5"
			(at 3.481 -2.527 0)
			(layer "B.SilkS")
			(effects
				(font
					(size 0.7 0.7)
					(thickness 0.15)
				)
				(justify right bottom mirror)
			)
		)
		(property "Value" "FB_120Z_2A_Murata-BLM18PG_0603"
			(at 0 -1.7 0)
			(layer "B.Fab")
			(effects
				(font
					(size 0.7 0.7)
					(thickness 0.15)
				)
				(justify right bottom mirror)
			)
		)
		(property "Datasheet" "https://www.murata.com/en-us/products/productdata/8796738650142/ENFA0003.pdf"
			(at 0 0 0)
			(layer "F.Fab")
			(hide yes)
			(effects
				(font
					(size 1.27 1.27)
					(thickness 0.15)
				)
			)
		)
		(property "Description" "Ferrite Bead, 0603 [1608 Metric], 120 ohm, 2 A, BLM18P, 0.05 ohm, ± 25%, DC power line"
			(at 0 0 0)
			(layer "F.Fab")
			(hide yes)
			(effects
				(font
					(size 1.27 1.27)
					(thickness 0.15)
				)
			)
		)
		(property "Author" "Antmicro"
			(at 0 0 0)
			(layer "B.Fab")
			(hide yes)
			(effects
				(font
					(size 1 1)
					(thickness 0.15)
				)
				(justify mirror)
			)
		)
		(property "Current" ""
			(at 0 0 0)
			(layer "B.Fab")
			(hide yes)
			(effects
				(font
					(size 1 1)
					(thickness 0.15)
				)
				(justify mirror)
			)
		)
		(property "License" "Apache-2.0"
			(at 0 0 0)
			(layer "B.Fab")
			(hide yes)
			(effects
				(font
					(size 1 1)
					(thickness 0.15)
				)
				(justify mirror)
			)
		)
		(property "MPN" "BLM18PG121SN1D"
			(at 0 0 0)
			(layer "B.Fab")
			(hide yes)
			(effects
				(font
					(size 1 1)
					(thickness 0.15)
				)
				(justify mirror)
			)
		)
		(property "Manufacturer" "Murata"
			(at 0 0 0)
			(layer "B.Fab")
			(hide yes)
			(effects
				(font
					(size 1 1)
					(thickness 0.15)
				)
				(justify mirror)
			)
		)
		(property "Val" "120Z/2A"
			(at 0 0 0)
			(layer "B.Fab")
			(hide yes)
			(effects
				(font
					(size 1 1)
					(thickness 0.15)
				)
				(justify mirror)
			)
		)
		(sheetname "/Ethernet/")
		(sheetfile "ethernet.kicad_sch")
		(attr smd)
		(fp_line
			(start -0.15 -0.4)
			(end 0.15 -0.4)
			(stroke
				(width 0.15)
				(type solid)
			)
			(layer "B.SilkS")
		)
		(fp_line
			(start -0.15 0.4)
			(end 0.15 0.4)
			(stroke
				(width 0.15)
				(type solid)
			)
			(layer "B.SilkS")
		)
		(fp_rect
			(start -1.25 0.65)
			(end 1.25 -0.65)
			(stroke
				(width 0.05)
				(type solid)
			)
			(fill no)
			(layer "B.CrtYd")
		)
		(fp_line
			(start -0.803 -0.406)
			(end -0.803 0.408)
			(stroke
				(width 0.15)
				(type solid)
			)
			(layer "B.Fab")
		)
		(fp_line
			(start 0.8 -0.406)
			(end -0.803 -0.406)
			(stroke
				(width 0.15)
				(type solid)
			)
			(layer "B.Fab")
		)
		(fp_line
			(start 0.8 0.408)
			(end -0.803 0.408)
			(stroke
				(width 0.15)
				(type solid)
			)
			(layer "B.Fab")
		)
		(fp_line
			(start 0.8 0.408)
			(end 0.8 -0.406)
			(stroke
				(width 0.15)
				(type solid)
			)
			(layer "B.Fab")
		)
		(pad "1" smd roundrect
			(at -0.7 0)
			(size 0.8 1)
			(layers "B.Cu" "B.Mask" "B.Paste")
			(roundrect_rratio 0.2)
			(net 404 "/Ethernet/AVDDL_PLL")
			(pintype "passive")
		)
		(pad "2" smd roundrect
			(at 0.7 0)
			(size 0.8 1)
			(layers "B.Cu" "B.Mask" "B.Paste")
			(roundrect_rratio 0.2)
			(net 339 "VCC1V2")
			(pintype "passive")
		)
	)
	(footprint "antmicro-footprints:C_0402_1005Metric"
		(layer "B.Cu")
		(at 107.725 99.35 180)
		(descr "Capacitor SMD 0402")
		(tags "capacitor SMD 0402")
		(property "Reference" "C196"
			(at -5.875 2.8 0)
			(layer "B.SilkS")
			(effects
				(font
					(size 0.7 0.7)
					(thickness 0.15)
				)
				(justify left bottom mirror)
			)
		)
		(property "Value" "C_4u7_0402"
			(at 0 -1.4 0)
			(layer "B.Fab")
			(effects
				(font
					(size 0.7 0.7)
					(thickness 0.15)
				)
				(justify left bottom mirror)
			)
		)
		(property "Datasheet" "https://www.murata.com/products/productdetail?partno=GRM155R61A475MEAA%23"
			(at 0 0 180)
			(layer "F.Fab")
			(hide yes)
			(effects
				(font
					(size 1.27 1.27)
					(thickness 0.15)
				)
			)
		)
		(property "Description" "SMD Multilayer Ceramic Capacitor, 4.7 µF, 10 V, 0402 [1005 Metric], ± 20%, X5R, GRM Series"
			(at 0 0 180)
			(layer "F.Fab")
			(hide yes)
			(effects
				(font
					(size 1.27 1.27)
					(thickness 0.15)
				)
			)
		)
		(property "Author" "Antmicro"
			(at 215.45 198.7 0)
			(layer "B.Fab")
			(hide yes)
			(effects
				(font
					(size 1 1)
					(thickness 0.15)
				)
				(justify mirror)
			)
		)
		(property "Dielectric" ""
			(at 215.45 198.7 0)
			(layer "B.Fab")
			(hide yes)
			(effects
				(font
					(size 1 1)
					(thickness 0.15)
				)
				(justify mirror)
			)
		)
		(property "License" "Apache-2.0"
			(at 215.45 198.7 0)
			(layer "B.Fab")
			(hide yes)
			(effects
				(font
					(size 1 1)
					(thickness 0.15)
				)
				(justify mirror)
			)
		)
		(property "MPN" "GRM155R61A475MEAAD"
			(at 215.45 198.7 0)
			(layer "B.Fab")
			(hide yes)
			(effects
				(font
					(size 1 1)
					(thickness 0.15)
				)
				(justify mirror)
			)
		)
		(property "Manufacturer" "Murata"
			(at 215.45 198.7 0)
			(layer "B.Fab")
			(hide yes)
			(effects
				(font
					(size 1 1)
					(thickness 0.15)
				)
				(justify mirror)
			)
		)
		(property "Val" "4u7"
			(at 215.45 198.7 0)
			(layer "B.Fab")
			(hide yes)
			(effects
				(font
					(size 1 1)
					(thickness 0.15)
				)
				(justify mirror)
			)
		)
		(property "Voltage" ""
			(at 215.45 198.7 0)
			(layer "B.Fab")
			(hide yes)
			(effects
				(font
					(size 1 1)
					(thickness 0.15)
				)
				(justify mirror)
			)
		)
		(sheetname "/Ethernet/")
		(sheetfile "ethernet.kicad_sch")
		(attr smd)
		(fp_rect
			(start -0.925 0.47)
			(end 0.925 -0.47)
			(stroke
				(width 0.05)
				(type default)
			)
			(fill no)
			(layer "B.CrtYd")
		)
		(fp_line
			(start 0.504 0.25)
			(end 0.504 -0.248)
			(stroke
				(width 0.15)
				(type solid)
			)
			(layer "B.Fab")
		)
		(fp_line
			(start 0.504 -0.248)
			(end -0.494 -0.248)
			(stroke
				(width 0.15)
				(type solid)
			)
			(layer "B.Fab")
		)
		(fp_line
			(start -0.494 0.25)
			(end 0.504 0.25)
			(stroke
				(width 0.15)
				(type solid)
			)
			(layer "B.Fab")
		)
		(fp_line
			(start -0.494 -0.248)
			(end -0.494 0.25)
			(stroke
				(width 0.15)
				(type solid)
			)
			(layer "B.Fab")
		)
		(pad "1" smd roundrect
			(at -0.48 0 180)
			(size 0.59 0.64)
			(layers "B.Cu" "B.Mask" "B.Paste")
			(roundrect_rratio 0.25)
			(net 1 "GND")
			(pintype "passive")
		)
		(pad "2" smd roundrect
			(at 0.48 0 180)
			(size 0.59 0.64)
			(layers "B.Cu" "B.Mask" "B.Paste")
			(roundrect_rratio 0.25)
			(net 339 "VCC1V2")
			(pintype "passive")
		)
	)
	(footprint "antmicro-footprints:R_0402_1005Metric"
		(layer "B.Cu")
		(at 77.975 147.175)
		(descr "Resistor SMD 0402")
		(tags "resistor SMD 0402")
		(property "Reference" "R133"
			(at -3.575 0.325 0)
			(layer "B.SilkS")
			(effects
				(font
					(size 0.7 0.7)
					(thickness 0.15)
				)
				(justify right bottom mirror)
			)
		)
		(property "Value" "R_2k2_0402"
			(at 0 -1.4 0)
			(layer "B.Fab")
			(effects
				(font
					(size 0.7 0.7)
					(thickness 0.15)
				)
				(justify right bottom mirror)
			)
		)
		(property "Datasheet" "https://www.bourns.com/docs/product-datasheets/cr.pdf"
			(at 0 0 0)
			(layer "F.Fab")
			(hide yes)
			(effects
				(font
					(size 1.27 1.27)
					(thickness 0.15)
				)
			)
		)
		(property "Description" "SMD Chip Resistor, 2.2 kohm, ± 1%, 62.5 mW, 0402 [1005 Metric], Thick Film, General Purpose"
			(at 0 0 0)
			(layer "F.Fab")
			(hide yes)
			(effects
				(font
					(size 1.27 1.27)
					(thickness 0.15)
				)
			)
		)
		(property "Author" "Antmicro"
			(at 0 0 0)
			(layer "B.Fab")
			(hide yes)
			(effects
				(font
					(size 1 1)
					(thickness 0.15)
				)
				(justify mirror)
			)
		)
		(property "License" "Apache-2.0"
			(at 0 0 0)
			(layer "B.Fab")
			(hide yes)
			(effects
				(font
					(size 1 1)
					(thickness 0.15)
				)
				(justify mirror)
			)
		)
		(property "MPN" "CR0402-FX-2201GLF"
			(at 0 0 0)
			(layer "B.Fab")
			(hide yes)
			(effects
				(font
					(size 1 1)
					(thickness 0.15)
				)
				(justify mirror)
			)
		)
		(property "Manufacturer" "Bourns"
			(at 0 0 0)
			(layer "B.Fab")
			(hide yes)
			(effects
				(font
					(size 1 1)
					(thickness 0.15)
				)
				(justify mirror)
			)
		)
		(property "Tolerance" "1%"
			(at 0 0 0)
			(layer "B.Fab")
			(hide yes)
			(effects
				(font
					(size 1 1)
					(thickness 0.15)
				)
				(justify mirror)
			)
		)
		(property "Val" "2k2"
			(at 0 0 0)
			(layer "B.Fab")
			(hide yes)
			(effects
				(font
					(size 1 1)
					(thickness 0.15)
				)
				(justify mirror)
			)
		)
		(property "DNP" ""
			(at 0 0 0)
			(unlocked yes)
			(layer "B.Fab")
			(hide yes)
			(effects
				(font
					(size 1 1)
					(thickness 0.15)
				)
				(justify mirror)
			)
		)
		(sheetname "/FPGA banks 13-16/")
		(sheetfile "fpga-banks-13-16.kicad_sch")
		(attr smd)
		(fp_rect
			(start -0.925 0.47)
			(end 0.925 -0.47)
			(stroke
				(width 0.05)
				(type default)
			)
			(fill no)
			(layer "B.CrtYd")
		)
		(fp_rect
			(start -0.5 0.25)
			(end 0.5 -0.25)
			(stroke
				(width 0.15)
				(type solid)
			)
			(fill no)
			(layer "B.Fab")
		)
		(pad "1" smd roundrect
			(at -0.48 0)
			(size 0.59 0.64)
			(layers "B.Cu" "B.Mask" "B.Paste")
			(roundrect_rratio 0.25)
			(net 2 "VCC3V3")
			(pintype "passive")
		)
		(pad "2" smd roundrect
			(at 0.48 0)
			(size 0.59 0.64)
			(layers "B.Cu" "B.Mask" "B.Paste")
			(roundrect_rratio 0.25)
			(net 344 "Net-(U14A-IO_L6P_T0_FCS_B_14)")
			(pintype "passive")
		)
	)
	(footprint "antmicro-footprints:R_0402_1005Metric"
		(layer "B.Cu")
		(at 71.195 135.315)
		(descr "Resistor SMD 0402")
		(tags "resistor SMD 0402")
		(property "Reference" "R31"
			(at -2.95 0.425 0)
			(layer "B.SilkS")
			(effects
				(font
					(size 0.7 0.7)
					(thickness 0.15)
				)
				(justify right bottom mirror)
			)
		)
		(property "Value" "R_10k_0402"
			(at 0 -1.4 0)
			(layer "B.Fab")
			(effects
				(font
					(size 0.7 0.7)
					(thickness 0.15)
				)
				(justify right bottom mirror)
			)
		)
		(property "Datasheet" "https://www.bourns.com/docs/product-datasheets/cr.pdf"
			(at 0 0 0)
			(layer "F.Fab")
			(hide yes)
			(effects
				(font
					(size 1.27 1.27)
					(thickness 0.15)
				)
			)
		)
		(property "Description" "SMD Chip Resistor, 10 kohm, ± 1%, 62.5 mW, 0402 [1005 Metric], Thick Film, General Purpose"
			(at 0 0 0)
			(layer "F.Fab")
			(hide yes)
			(effects
				(font
					(size 1.27 1.27)
					(thickness 0.15)
				)
			)
		)
		(property "Author" "Antmicro"
			(at 0 0 0)
			(layer "B.Fab")
			(hide yes)
			(effects
				(font
					(size 1 1)
					(thickness 0.15)
				)
				(justify mirror)
			)
		)
		(property "License" "Apache-2.0"
			(at 0 0 0)
			(layer "B.Fab")
			(hide yes)
			(effects
				(font
					(size 1 1)
					(thickness 0.15)
				)
				(justify mirror)
			)
		)
		(property "MPN" "CR0402-FX-1002GLF"
			(at 0 0 0)
			(layer "B.Fab")
			(hide yes)
			(effects
				(font
					(size 1 1)
					(thickness 0.15)
				)
				(justify mirror)
			)
		)
		(property "Manufacturer" "Bourns"
			(at 0 0 0)
			(layer "B.Fab")
			(hide yes)
			(effects
				(font
					(size 1 1)
					(thickness 0.15)
				)
				(justify mirror)
			)
		)
		(property "Tolerance" "1%"
			(at 0 0 0)
			(layer "B.Fab")
			(hide yes)
			(effects
				(font
					(size 1 1)
					(thickness 0.15)
				)
				(justify mirror)
			)
		)
		(property "Val" "10k"
			(at 0 0 0)
			(layer "B.Fab")
			(hide yes)
			(effects
				(font
					(size 1 1)
					(thickness 0.15)
				)
				(justify mirror)
			)
		)
		(sheetname "/RoT/")
		(sheetfile "rot.kicad_sch")
		(attr smd)
		(fp_rect
			(start -0.925 0.47)
			(end 0.925 -0.47)
			(stroke
				(width 0.05)
				(type default)
			)
			(fill no)
			(layer "B.CrtYd")
		)
		(fp_rect
			(start -0.5 0.25)
			(end 0.5 -0.25)
			(stroke
				(width 0.15)
				(type solid)
			)
			(fill no)
			(layer "B.Fab")
		)
		(pad "1" smd roundrect
			(at -0.48 0)
			(size 0.59 0.64)
			(layers "B.Cu" "B.Mask" "B.Paste")
			(roundrect_rratio 0.25)
			(net 136 "QSPIA2_D0")
			(pintype "passive")
		)
		(pad "2" smd roundrect
			(at 0.48 0)
			(size 0.59 0.64)
			(layers "B.Cu" "B.Mask" "B.Paste")
			(roundrect_rratio 0.25)
			(net 2 "VCC3V3")
			(pintype "passive")
		)
	)
	(footprint "antmicro-footprints:R_0402_1005Metric"
		(layer "B.Cu")
		(at 71.21 136.315 180)
		(descr "Resistor SMD 0402")
		(tags "resistor SMD 0402")
		(property "Reference" "R27"
			(at 0.81 -0.385 0)
			(layer "B.SilkS")
			(effects
				(font
					(size 0.7 0.7)
					(thickness 0.15)
				)
				(justify left bottom mirror)
			)
		)
		(property "Value" "R_1k_0402"
			(at 0 -1.4 0)
			(layer "B.Fab")
			(effects
				(font
					(size 0.7 0.7)
					(thickness 0.15)
				)
				(justify left bottom mirror)
			)
		)
		(property "Datasheet" "https://www.bourns.com/docs/product-datasheets/cr.pdf"
			(at 0 0 180)
			(layer "F.Fab")
			(hide yes)
			(effects
				(font
					(size 1.27 1.27)
					(thickness 0.15)
				)
			)
		)
		(property "Description" "SMD Chip Resistor, 1 kohm, ± 1%, 63 mW, 0402 [1005 Metric], Thick Film, General Purpose"
			(at 0 0 180)
			(layer "F.Fab")
			(hide yes)
			(effects
				(font
					(size 1.27 1.27)
					(thickness 0.15)
				)
			)
		)
		(property "Author" "Antmicro"
			(at 142.42 272.63 0)
			(layer "B.Fab")
			(hide yes)
			(effects
				(font
					(size 1 1)
					(thickness 0.15)
				)
				(justify mirror)
			)
		)
		(property "License" "Apache-2.0"
			(at 142.42 272.63 0)
			(layer "B.Fab")
			(hide yes)
			(effects
				(font
					(size 1 1)
					(thickness 0.15)
				)
				(justify mirror)
			)
		)
		(property "MPN" "CR0402-FX-1001GLF"
			(at 142.42 272.63 0)
			(layer "B.Fab")
			(hide yes)
			(effects
				(font
					(size 1 1)
					(thickness 0.15)
				)
				(justify mirror)
			)
		)
		(property "Manufacturer" "Bourns"
			(at 142.42 272.63 0)
			(layer "B.Fab")
			(hide yes)
			(effects
				(font
					(size 1 1)
					(thickness 0.15)
				)
				(justify mirror)
			)
		)
		(property "Tolerance" "1%"
			(at 142.42 272.63 0)
			(layer "B.Fab")
			(hide yes)
			(effects
				(font
					(size 1 1)
					(thickness 0.15)
				)
				(justify mirror)
			)
		)
		(property "Val" "1k"
			(at 142.42 272.63 0)
			(layer "B.Fab")
			(hide yes)
			(effects
				(font
					(size 1 1)
					(thickness 0.15)
				)
				(justify mirror)
			)
		)
		(sheetname "/RoT/")
		(sheetfile "rot.kicad_sch")
		(attr smd)
		(fp_rect
			(start -0.925 0.47)
			(end 0.925 -0.47)
			(stroke
				(width 0.05)
				(type default)
			)
			(fill no)
			(layer "B.CrtYd")
		)
		(fp_rect
			(start -0.5 0.25)
			(end 0.5 -0.25)
			(stroke
				(width 0.15)
				(type solid)
			)
			(fill no)
			(layer "B.Fab")
		)
		(pad "1" smd roundrect
			(at -0.48 0 180)
			(size 0.59 0.64)
			(layers "B.Cu" "B.Mask" "B.Paste")
			(roundrect_rratio 0.25)
			(net 2 "VCC3V3")
			(pintype "passive")
		)
		(pad "2" smd roundrect
			(at 0.48 0 180)
			(size 0.59 0.64)
			(layers "B.Cu" "B.Mask" "B.Paste")
			(roundrect_rratio 0.25)
			(net 130 "QSPIA_CLK")
			(pintype "passive")
		)
	)
	(footprint "antmicro-footprints:R_0402_1005Metric"
		(layer "B.Cu")
		(at 71.21 138.315 180)
		(descr "Resistor SMD 0402")
		(tags "resistor SMD 0402")
		(property "Reference" "R23"
			(at 0.81 -0.385 0)
			(layer "B.SilkS")
			(effects
				(font
					(size 0.7 0.7)
					(thickness 0.15)
				)
				(justify left bottom mirror)
			)
		)
		(property "Value" "R_4k7_0402"
			(at 0 -1.4 0)
			(layer "B.Fab")
			(effects
				(font
					(size 0.7 0.7)
					(thickness 0.15)
				)
				(justify left bottom mirror)
			)
		)
		(property "Datasheet" "https://www.bourns.com/docs/product-datasheets/cr.pdf"
			(at 0 0 180)
			(layer "F.Fab")
			(hide yes)
			(effects
				(font
					(size 1.27 1.27)
					(thickness 0.15)
				)
			)
		)
		(property "Description" "SMD Chip Resistor, 4.7 kohm, ± 1%, 62.5 mW, 0402 [1005 Metric], Thick Film, General Purpose"
			(at 0 0 180)
			(layer "F.Fab")
			(hide yes)
			(effects
				(font
					(size 1.27 1.27)
					(thickness 0.15)
				)
			)
		)
		(property "Author" "Antmicro"
			(at 142.42 276.63 0)
			(layer "B.Fab")
			(hide yes)
			(effects
				(font
					(size 1 1)
					(thickness 0.15)
				)
				(justify mirror)
			)
		)
		(property "License" "Apache-2.0"
			(at 142.42 276.63 0)
			(layer "B.Fab")
			(hide yes)
			(effects
				(font
					(size 1 1)
					(thickness 0.15)
				)
				(justify mirror)
			)
		)
		(property "MPN" "CR0402-FX-4701GLF"
			(at 142.42 276.63 0)
			(layer "B.Fab")
			(hide yes)
			(effects
				(font
					(size 1 1)
					(thickness 0.15)
				)
				(justify mirror)
			)
		)
		(property "Manufacturer" "Bourns"
			(at 142.42 276.63 0)
			(layer "B.Fab")
			(hide yes)
			(effects
				(font
					(size 1 1)
					(thickness 0.15)
				)
				(justify mirror)
			)
		)
		(property "Tolerance" "1%"
			(at 142.42 276.63 0)
			(layer "B.Fab")
			(hide yes)
			(effects
				(font
					(size 1 1)
					(thickness 0.15)
				)
				(justify mirror)
			)
		)
		(property "Val" "4k7"
			(at 142.42 276.63 0)
			(layer "B.Fab")
			(hide yes)
			(effects
				(font
					(size 1 1)
					(thickness 0.15)
				)
				(justify mirror)
			)
		)
		(sheetname "/RoT/")
		(sheetfile "rot.kicad_sch")
		(attr smd)
		(fp_rect
			(start -0.925 0.47)
			(end 0.925 -0.47)
			(stroke
				(width 0.05)
				(type default)
			)
			(fill no)
			(layer "B.CrtYd")
		)
		(fp_rect
			(start -0.5 0.25)
			(end 0.5 -0.25)
			(stroke
				(width 0.15)
				(type solid)
			)
			(fill no)
			(layer "B.Fab")
		)
		(pad "1" smd roundrect
			(at -0.48 0 180)
			(size 0.59 0.64)
			(layers "B.Cu" "B.Mask" "B.Paste")
			(roundrect_rratio 0.25)
			(net 2 "VCC3V3")
			(pintype "passive")
		)
		(pad "2" smd roundrect
			(at 0.48 0 180)
			(size 0.59 0.64)
			(layers "B.Cu" "B.Mask" "B.Paste")
			(roundrect_rratio 0.25)
			(net 140 "QSPIA2_CS_N")
			(pintype "passive")
		)
	)
	(footprint "antmicro-footprints:R_0402_1005Metric"
		(layer "B.Cu")
		(at 71.21 139.315)
		(descr "Resistor SMD 0402")
		(tags "resistor SMD 0402")
		(property "Reference" "R43"
			(at -2.95 0.425 0)
			(layer "B.SilkS")
			(effects
				(font
					(size 0.7 0.7)
					(thickness 0.15)
				)
				(justify right bottom mirror)
			)
		)
		(property "Value" "R_10k_0402"
			(at 0 -1.4 0)
			(layer "B.Fab")
			(effects
				(font
					(size 0.7 0.7)
					(thickness 0.15)
				)
				(justify right bottom mirror)
			)
		)
		(property "Datasheet" "https://www.bourns.com/docs/product-datasheets/cr.pdf"
			(at 0 0 0)
			(layer "F.Fab")
			(hide yes)
			(effects
				(font
					(size 1.27 1.27)
					(thickness 0.15)
				)
			)
		)
		(property "Description" "SMD Chip Resistor, 10 kohm, ± 1%, 62.5 mW, 0402 [1005 Metric], Thick Film, General Purpose"
			(at 0 0 0)
			(layer "F.Fab")
			(hide yes)
			(effects
				(font
					(size 1.27 1.27)
					(thickness 0.15)
				)
			)
		)
		(property "Author" "Antmicro"
			(at 0 0 0)
			(layer "B.Fab")
			(hide yes)
			(effects
				(font
					(size 1 1)
					(thickness 0.15)
				)
				(justify mirror)
			)
		)
		(property "License" "Apache-2.0"
			(at 0 0 0)
			(layer "B.Fab")
			(hide yes)
			(effects
				(font
					(size 1 1)
					(thickness 0.15)
				)
				(justify mirror)
			)
		)
		(property "MPN" "CR0402-FX-1002GLF"
			(at 0 0 0)
			(layer "B.Fab")
			(hide yes)
			(effects
				(font
					(size 1 1)
					(thickness 0.15)
				)
				(justify mirror)
			)
		)
		(property "Manufacturer" "Bourns"
			(at 0 0 0)
			(layer "B.Fab")
			(hide yes)
			(effects
				(font
					(size 1 1)
					(thickness 0.15)
				)
				(justify mirror)
			)
		)
		(property "Tolerance" "1%"
			(at 0 0 0)
			(layer "B.Fab")
			(hide yes)
			(effects
				(font
					(size 1 1)
					(thickness 0.15)
				)
				(justify mirror)
			)
		)
		(property "Val" "10k"
			(at 0 0 0)
			(layer "B.Fab")
			(hide yes)
			(effects
				(font
					(size 1 1)
					(thickness 0.15)
				)
				(justify mirror)
			)
		)
		(sheetname "/RoT/")
		(sheetfile "rot.kicad_sch")
		(attr smd)
		(fp_rect
			(start -0.925 0.47)
			(end 0.925 -0.47)
			(stroke
				(width 0.05)
				(type default)
			)
			(fill no)
			(layer "B.CrtYd")
		)
		(fp_rect
			(start -0.5 0.25)
			(end 0.5 -0.25)
			(stroke
				(width 0.15)
				(type solid)
			)
			(fill no)
			(layer "B.Fab")
		)
		(pad "1" smd roundrect
			(at -0.48 0)
			(size 0.59 0.64)
			(layers "B.Cu" "B.Mask" "B.Paste")
			(roundrect_rratio 0.25)
			(net 137 "QSPIA2_D1")
			(pintype "passive")
		)
		(pad "2" smd roundrect
			(at 0.48 0)
			(size 0.59 0.64)
			(layers "B.Cu" "B.Mask" "B.Paste")
			(roundrect_rratio 0.25)
			(net 2 "VCC3V3")
			(pintype "passive")
		)
	)
	(footprint "antmicro-footprints:R_0402_1005Metric"
		(layer "B.Cu")
		(at 71.21 137.315)
		(descr "Resistor SMD 0402")
		(tags "resistor SMD 0402")
		(property "Reference" "R39"
			(at -2.95 0.425 0)
			(layer "B.SilkS")
			(effects
				(font
					(size 0.7 0.7)
					(thickness 0.15)
				)
				(justify right bottom mirror)
			)
		)
		(property "Value" "R_10k_0402"
			(at 0 -1.4 0)
			(layer "B.Fab")
			(effects
				(font
					(size 0.7 0.7)
					(thickness 0.15)
				)
				(justify right bottom mirror)
			)
		)
		(property "Datasheet" "https://www.bourns.com/docs/product-datasheets/cr.pdf"
			(at 0 0 0)
			(layer "F.Fab")
			(hide yes)
			(effects
				(font
					(size 1.27 1.27)
					(thickness 0.15)
				)
			)
		)
		(property "Description" "SMD Chip Resistor, 10 kohm, ± 1%, 62.5 mW, 0402 [1005 Metric], Thick Film, General Purpose"
			(at 0 0 0)
			(layer "F.Fab")
			(hide yes)
			(effects
				(font
					(size 1.27 1.27)
					(thickness 0.15)
				)
			)
		)
		(property "Author" "Antmicro"
			(at 0 0 0)
			(layer "B.Fab")
			(hide yes)
			(effects
				(font
					(size 1 1)
					(thickness 0.15)
				)
				(justify mirror)
			)
		)
		(property "License" "Apache-2.0"
			(at 0 0 0)
			(layer "B.Fab")
			(hide yes)
			(effects
				(font
					(size 1 1)
					(thickness 0.15)
				)
				(justify mirror)
			)
		)
		(property "MPN" "CR0402-FX-1002GLF"
			(at 0 0 0)
			(layer "B.Fab")
			(hide yes)
			(effects
				(font
					(size 1 1)
					(thickness 0.15)
				)
				(justify mirror)
			)
		)
		(property "Manufacturer" "Bourns"
			(at 0 0 0)
			(layer "B.Fab")
			(hide yes)
			(effects
				(font
					(size 1 1)
					(thickness 0.15)
				)
				(justify mirror)
			)
		)
		(property "Tolerance" "1%"
			(at 0 0 0)
			(layer "B.Fab")
			(hide yes)
			(effects
				(font
					(size 1 1)
					(thickness 0.15)
				)
				(justify mirror)
			)
		)
		(property "Val" "10k"
			(at 0 0 0)
			(layer "B.Fab")
			(hide yes)
			(effects
				(font
					(size 1 1)
					(thickness 0.15)
				)
				(justify mirror)
			)
		)
		(sheetname "/RoT/")
		(sheetfile "rot.kicad_sch")
		(attr smd)
		(fp_rect
			(start -0.925 0.47)
			(end 0.925 -0.47)
			(stroke
				(width 0.05)
				(type default)
			)
			(fill no)
			(layer "B.CrtYd")
		)
		(fp_rect
			(start -0.5 0.25)
			(end 0.5 -0.25)
			(stroke
				(width 0.15)
				(type solid)
			)
			(fill no)
			(layer "B.Fab")
		)
		(pad "1" smd roundrect
			(at -0.48 0)
			(size 0.59 0.64)
			(layers "B.Cu" "B.Mask" "B.Paste")
			(roundrect_rratio 0.25)
			(net 139 "QSPIA2_D3")
			(pintype "passive")
		)
		(pad "2" smd roundrect
			(at 0.48 0)
			(size 0.59 0.64)
			(layers "B.Cu" "B.Mask" "B.Paste")
			(roundrect_rratio 0.25)
			(net 2 "VCC3V3")
			(pintype "passive")
		)
	)
	(footprint "antmicro-footprints:R_0402_1005Metric"
		(layer "B.Cu")
		(at 71.21 140.315)
		(descr "Resistor SMD 0402")
		(tags "resistor SMD 0402")
		(property "Reference" "R35"
			(at -2.95 0.425 0)
			(layer "B.SilkS")
			(effects
				(font
					(size 0.7 0.7)
					(thickness 0.15)
				)
				(justify right bottom mirror)
			)
		)
		(property "Value" "R_10k_0402"
			(at 0 -1.4 0)
			(layer "B.Fab")
			(effects
				(font
					(size 0.7 0.7)
					(thickness 0.15)
				)
				(justify right bottom mirror)
			)
		)
		(property "Datasheet" "https://www.bourns.com/docs/product-datasheets/cr.pdf"
			(at 0 0 0)
			(layer "F.Fab")
			(hide yes)
			(effects
				(font
					(size 1.27 1.27)
					(thickness 0.15)
				)
			)
		)
		(property "Description" "SMD Chip Resistor, 10 kohm, ± 1%, 62.5 mW, 0402 [1005 Metric], Thick Film, General Purpose"
			(at 0 0 0)
			(layer "F.Fab")
			(hide yes)
			(effects
				(font
					(size 1.27 1.27)
					(thickness 0.15)
				)
			)
		)
		(property "Author" "Antmicro"
			(at 0 0 0)
			(layer "B.Fab")
			(hide yes)
			(effects
				(font
					(size 1 1)
					(thickness 0.15)
				)
				(justify mirror)
			)
		)
		(property "License" "Apache-2.0"
			(at 0 0 0)
			(layer "B.Fab")
			(hide yes)
			(effects
				(font
					(size 1 1)
					(thickness 0.15)
				)
				(justify mirror)
			)
		)
		(property "MPN" "CR0402-FX-1002GLF"
			(at 0 0 0)
			(layer "B.Fab")
			(hide yes)
			(effects
				(font
					(size 1 1)
					(thickness 0.15)
				)
				(justify mirror)
			)
		)
		(property "Manufacturer" "Bourns"
			(at 0 0 0)
			(layer "B.Fab")
			(hide yes)
			(effects
				(font
					(size 1 1)
					(thickness 0.15)
				)
				(justify mirror)
			)
		)
		(property "Tolerance" "1%"
			(at 0 0 0)
			(layer "B.Fab")
			(hide yes)
			(effects
				(font
					(size 1 1)
					(thickness 0.15)
				)
				(justify mirror)
			)
		)
		(property "Val" "10k"
			(at 0 0 0)
			(layer "B.Fab")
			(hide yes)
			(effects
				(font
					(size 1 1)
					(thickness 0.15)
				)
				(justify mirror)
			)
		)
		(sheetname "/RoT/")
		(sheetfile "rot.kicad_sch")
		(attr smd)
		(fp_rect
			(start -0.925 0.47)
			(end 0.925 -0.47)
			(stroke
				(width 0.05)
				(type default)
			)
			(fill no)
			(layer "B.CrtYd")
		)
		(fp_rect
			(start -0.5 0.25)
			(end 0.5 -0.25)
			(stroke
				(width 0.15)
				(type solid)
			)
			(fill no)
			(layer "B.Fab")
		)
		(pad "1" smd roundrect
			(at -0.48 0)
			(size 0.59 0.64)
			(layers "B.Cu" "B.Mask" "B.Paste")
			(roundrect_rratio 0.25)
			(net 138 "QSPIA2_D2")
			(pintype "passive")
		)
		(pad "2" smd roundrect
			(at 0.48 0)
			(size 0.59 0.64)
			(layers "B.Cu" "B.Mask" "B.Paste")
			(roundrect_rratio 0.25)
			(net 2 "VCC3V3")
			(pintype "passive")
		)
	)
	(footprint "antmicro-footprints:R_0402_1005Metric"
		(layer "B.Cu")
		(at 71.19 116.125)
		(descr "Resistor SMD 0402")
		(tags "resistor SMD 0402")
		(property "Reference" "R29"
			(at -2.99 0.375 0)
			(layer "B.SilkS")
			(effects
				(font
					(size 0.7 0.7)
					(thickness 0.15)
				)
				(justify right bottom mirror)
			)
		)
		(property "Value" "R_10k_0402"
			(at 0 -1.4 0)
			(layer "B.Fab")
			(effects
				(font
					(size 0.7 0.7)
					(thickness 0.15)
				)
				(justify right bottom mirror)
			)
		)
		(property "Datasheet" "https://www.bourns.com/docs/product-datasheets/cr.pdf"
			(at 0 0 0)
			(layer "F.Fab")
			(hide yes)
			(effects
				(font
					(size 1.27 1.27)
					(thickness 0.15)
				)
			)
		)
		(property "Description" "SMD Chip Resistor, 10 kohm, ± 1%, 62.5 mW, 0402 [1005 Metric], Thick Film, General Purpose"
			(at 0 0 0)
			(layer "F.Fab")
			(hide yes)
			(effects
				(font
					(size 1.27 1.27)
					(thickness 0.15)
				)
			)
		)
		(property "Author" "Antmicro"
			(at 0 0 0)
			(layer "B.Fab")
			(hide yes)
			(effects
				(font
					(size 1 1)
					(thickness 0.15)
				)
				(justify mirror)
			)
		)
		(property "License" "Apache-2.0"
			(at 0 0 0)
			(layer "B.Fab")
			(hide yes)
			(effects
				(font
					(size 1 1)
					(thickness 0.15)
				)
				(justify mirror)
			)
		)
		(property "MPN" "CR0402-FX-1002GLF"
			(at 0 0 0)
			(layer "B.Fab")
			(hide yes)
			(effects
				(font
					(size 1 1)
					(thickness 0.15)
				)
				(justify mirror)
			)
		)
		(property "Manufacturer" "Bourns"
			(at 0 0 0)
			(layer "B.Fab")
			(hide yes)
			(effects
				(font
					(size 1 1)
					(thickness 0.15)
				)
				(justify mirror)
			)
		)
		(property "Tolerance" "1%"
			(at 0 0 0)
			(layer "B.Fab")
			(hide yes)
			(effects
				(font
					(size 1 1)
					(thickness 0.15)
				)
				(justify mirror)
			)
		)
		(property "Val" "10k"
			(at 0 0 0)
			(layer "B.Fab")
			(hide yes)
			(effects
				(font
					(size 1 1)
					(thickness 0.15)
				)
				(justify mirror)
			)
		)
		(sheetname "/RoT/")
		(sheetfile "rot.kicad_sch")
		(attr smd)
		(fp_rect
			(start -0.925 0.47)
			(end 0.925 -0.47)
			(stroke
				(width 0.05)
				(type default)
			)
			(fill no)
			(layer "B.CrtYd")
		)
		(fp_rect
			(start -0.5 0.25)
			(end 0.5 -0.25)
			(stroke
				(width 0.15)
				(type solid)
			)
			(fill no)
			(layer "B.Fab")
		)
		(pad "1" smd roundrect
			(at -0.48 0)
			(size 0.59 0.64)
			(layers "B.Cu" "B.Mask" "B.Paste")
			(roundrect_rratio 0.25)
			(net 125 "QSPIB2_D0")
			(pintype "passive")
		)
		(pad "2" smd roundrect
			(at 0.48 0)
			(size 0.59 0.64)
			(layers "B.Cu" "B.Mask" "B.Paste")
			(roundrect_rratio 0.25)
			(net 2 "VCC3V3")
			(pintype "passive")
		)
	)
	(footprint "antmicro-footprints:R_0402_1005Metric"
		(layer "B.Cu")
		(at 71.19 117.125 180)
		(descr "Resistor SMD 0402")
		(tags "resistor SMD 0402")
		(property "Reference" "R25"
			(at 0.79 -0.375 0)
			(layer "B.SilkS")
			(effects
				(font
					(size 0.7 0.7)
					(thickness 0.15)
				)
				(justify left bottom mirror)
			)
		)
		(property "Value" "R_1k_0402"
			(at 0 -1.4 0)
			(layer "B.Fab")
			(effects
				(font
					(size 0.7 0.7)
					(thickness 0.15)
				)
				(justify left bottom mirror)
			)
		)
		(property "Datasheet" "https://www.bourns.com/docs/product-datasheets/cr.pdf"
			(at 0 0 180)
			(layer "F.Fab")
			(hide yes)
			(effects
				(font
					(size 1.27 1.27)
					(thickness 0.15)
				)
			)
		)
		(property "Description" "SMD Chip Resistor, 1 kohm, ± 1%, 63 mW, 0402 [1005 Metric], Thick Film, General Purpose"
			(at 0 0 180)
			(layer "F.Fab")
			(hide yes)
			(effects
				(font
					(size 1.27 1.27)
					(thickness 0.15)
				)
			)
		)
		(property "Author" "Antmicro"
			(at 142.38 234.25 0)
			(layer "B.Fab")
			(hide yes)
			(effects
				(font
					(size 1 1)
					(thickness 0.15)
				)
				(justify mirror)
			)
		)
		(property "License" "Apache-2.0"
			(at 142.38 234.25 0)
			(layer "B.Fab")
			(hide yes)
			(effects
				(font
					(size 1 1)
					(thickness 0.15)
				)
				(justify mirror)
			)
		)
		(property "MPN" "CR0402-FX-1001GLF"
			(at 142.38 234.25 0)
			(layer "B.Fab")
			(hide yes)
			(effects
				(font
					(size 1 1)
					(thickness 0.15)
				)
				(justify mirror)
			)
		)
		(property "Manufacturer" "Bourns"
			(at 142.38 234.25 0)
			(layer "B.Fab")
			(hide yes)
			(effects
				(font
					(size 1 1)
					(thickness 0.15)
				)
				(justify mirror)
			)
		)
		(property "Tolerance" "1%"
			(at 142.38 234.25 0)
			(layer "B.Fab")
			(hide yes)
			(effects
				(font
					(size 1 1)
					(thickness 0.15)
				)
				(justify mirror)
			)
		)
		(property "Val" "1k"
			(at 142.38 234.25 0)
			(layer "B.Fab")
			(hide yes)
			(effects
				(font
					(size 1 1)
					(thickness 0.15)
				)
				(justify mirror)
			)
		)
		(sheetname "/RoT/")
		(sheetfile "rot.kicad_sch")
		(attr smd)
		(fp_rect
			(start -0.925 0.47)
			(end 0.925 -0.47)
			(stroke
				(width 0.05)
				(type default)
			)
			(fill no)
			(layer "B.CrtYd")
		)
		(fp_rect
			(start -0.5 0.25)
			(end 0.5 -0.25)
			(stroke
				(width 0.15)
				(type solid)
			)
			(fill no)
			(layer "B.Fab")
		)
		(pad "1" smd roundrect
			(at -0.48 0 180)
			(size 0.59 0.64)
			(layers "B.Cu" "B.Mask" "B.Paste")
			(roundrect_rratio 0.25)
			(net 2 "VCC3V3")
			(pintype "passive")
		)
		(pad "2" smd roundrect
			(at 0.48 0 180)
			(size 0.59 0.64)
			(layers "B.Cu" "B.Mask" "B.Paste")
			(roundrect_rratio 0.25)
			(net 119 "QSPIB_CLK")
			(pintype "passive")
		)
	)
	(footprint "antmicro-footprints:R_0402_1005Metric"
		(layer "B.Cu")
		(at 71.19 119.125 180)
		(descr "Resistor SMD 0402")
		(tags "resistor SMD 0402")
		(property "Reference" "R21"
			(at 0.79 -0.375 0)
			(layer "B.SilkS")
			(effects
				(font
					(size 0.7 0.7)
					(thickness 0.15)
				)
				(justify left bottom mirror)
			)
		)
		(property "Value" "R_4k7_0402"
			(at 0 -1.4 0)
			(layer "B.Fab")
			(effects
				(font
					(size 0.7 0.7)
					(thickness 0.15)
				)
				(justify left bottom mirror)
			)
		)
		(property "Datasheet" "https://www.bourns.com/docs/product-datasheets/cr.pdf"
			(at 0 0 180)
			(layer "F.Fab")
			(hide yes)
			(effects
				(font
					(size 1.27 1.27)
					(thickness 0.15)
				)
			)
		)
		(property "Description" "SMD Chip Resistor, 4.7 kohm, ± 1%, 62.5 mW, 0402 [1005 Metric], Thick Film, General Purpose"
			(at 0 0 180)
			(layer "F.Fab")
			(hide yes)
			(effects
				(font
					(size 1.27 1.27)
					(thickness 0.15)
				)
			)
		)
		(property "Author" "Antmicro"
			(at 142.38 238.25 0)
			(layer "B.Fab")
			(hide yes)
			(effects
				(font
					(size 1 1)
					(thickness 0.15)
				)
				(justify mirror)
			)
		)
		(property "License" "Apache-2.0"
			(at 142.38 238.25 0)
			(layer "B.Fab")
			(hide yes)
			(effects
				(font
					(size 1 1)
					(thickness 0.15)
				)
				(justify mirror)
			)
		)
		(property "MPN" "CR0402-FX-4701GLF"
			(at 142.38 238.25 0)
			(layer "B.Fab")
			(hide yes)
			(effects
				(font
					(size 1 1)
					(thickness 0.15)
				)
				(justify mirror)
			)
		)
		(property "Manufacturer" "Bourns"
			(at 142.38 238.25 0)
			(layer "B.Fab")
			(hide yes)
			(effects
				(font
					(size 1 1)
					(thickness 0.15)
				)
				(justify mirror)
			)
		)
		(property "Tolerance" "1%"
			(at 142.38 238.25 0)
			(layer "B.Fab")
			(hide yes)
			(effects
				(font
					(size 1 1)
					(thickness 0.15)
				)
				(justify mirror)
			)
		)
		(property "Val" "4k7"
			(at 142.38 238.25 0)
			(layer "B.Fab")
			(hide yes)
			(effects
				(font
					(size 1 1)
					(thickness 0.15)
				)
				(justify mirror)
			)
		)
		(sheetname "/RoT/")
		(sheetfile "rot.kicad_sch")
		(attr smd)
		(fp_rect
			(start -0.925 0.47)
			(end 0.925 -0.47)
			(stroke
				(width 0.05)
				(type default)
			)
			(fill no)
			(layer "B.CrtYd")
		)
		(fp_rect
			(start -0.5 0.25)
			(end 0.5 -0.25)
			(stroke
				(width 0.15)
				(type solid)
			)
			(fill no)
			(layer "B.Fab")
		)
		(pad "1" smd roundrect
			(at -0.48 0 180)
			(size 0.59 0.64)
			(layers "B.Cu" "B.Mask" "B.Paste")
			(roundrect_rratio 0.25)
			(net 2 "VCC3V3")
			(pintype "passive")
		)
		(pad "2" smd roundrect
			(at 0.48 0 180)
			(size 0.59 0.64)
			(layers "B.Cu" "B.Mask" "B.Paste")
			(roundrect_rratio 0.25)
			(net 129 "QSPIB2_CS_N")
			(pintype "passive")
		)
	)
	(footprint "antmicro-footprints:R_0402_1005Metric"
		(layer "B.Cu")
		(at 71.19 120.125)
		(descr "Resistor SMD 0402")
		(tags "resistor SMD 0402")
		(property "Reference" "R41"
			(at -2.99 0.375 0)
			(layer "B.SilkS")
			(effects
				(font
					(size 0.7 0.7)
					(thickness 0.15)
				)
				(justify right bottom mirror)
			)
		)
		(property "Value" "R_10k_0402"
			(at 0 -1.4 0)
			(layer "B.Fab")
			(effects
				(font
					(size 0.7 0.7)
					(thickness 0.15)
				)
				(justify right bottom mirror)
			)
		)
		(property "Datasheet" "https://www.bourns.com/docs/product-datasheets/cr.pdf"
			(at 0 0 0)
			(layer "F.Fab")
			(hide yes)
			(effects
				(font
					(size 1.27 1.27)
					(thickness 0.15)
				)
			)
		)
		(property "Description" "SMD Chip Resistor, 10 kohm, ± 1%, 62.5 mW, 0402 [1005 Metric], Thick Film, General Purpose"
			(at 0 0 0)
			(layer "F.Fab")
			(hide yes)
			(effects
				(font
					(size 1.27 1.27)
					(thickness 0.15)
				)
			)
		)
		(property "Author" "Antmicro"
			(at 0 0 0)
			(layer "B.Fab")
			(hide yes)
			(effects
				(font
					(size 1 1)
					(thickness 0.15)
				)
				(justify mirror)
			)
		)
		(property "License" "Apache-2.0"
			(at 0 0 0)
			(layer "B.Fab")
			(hide yes)
			(effects
				(font
					(size 1 1)
					(thickness 0.15)
				)
				(justify mirror)
			)
		)
		(property "MPN" "CR0402-FX-1002GLF"
			(at 0 0 0)
			(layer "B.Fab")
			(hide yes)
			(effects
				(font
					(size 1 1)
					(thickness 0.15)
				)
				(justify mirror)
			)
		)
		(property "Manufacturer" "Bourns"
			(at 0 0 0)
			(layer "B.Fab")
			(hide yes)
			(effects
				(font
					(size 1 1)
					(thickness 0.15)
				)
				(justify mirror)
			)
		)
		(property "Tolerance" "1%"
			(at 0 0 0)
			(layer "B.Fab")
			(hide yes)
			(effects
				(font
					(size 1 1)
					(thickness 0.15)
				)
				(justify mirror)
			)
		)
		(property "Val" "10k"
			(at 0 0 0)
			(layer "B.Fab")
			(hide yes)
			(effects
				(font
					(size 1 1)
					(thickness 0.15)
				)
				(justify mirror)
			)
		)
		(sheetname "/RoT/")
		(sheetfile "rot.kicad_sch")
		(attr smd)
		(fp_rect
			(start -0.925 0.47)
			(end 0.925 -0.47)
			(stroke
				(width 0.05)
				(type default)
			)
			(fill no)
			(layer "B.CrtYd")
		)
		(fp_rect
			(start -0.5 0.25)
			(end 0.5 -0.25)
			(stroke
				(width 0.15)
				(type solid)
			)
			(fill no)
			(layer "B.Fab")
		)
		(pad "1" smd roundrect
			(at -0.48 0)
			(size 0.59 0.64)
			(layers "B.Cu" "B.Mask" "B.Paste")
			(roundrect_rratio 0.25)
			(net 126 "QSPIB2_D1")
			(pintype "passive")
		)
		(pad "2" smd roundrect
			(at 0.48 0)
			(size 0.59 0.64)
			(layers "B.Cu" "B.Mask" "B.Paste")
			(roundrect_rratio 0.25)
			(net 2 "VCC3V3")
			(pintype "passive")
		)
	)
	(footprint "antmicro-footprints:R_0402_1005Metric"
		(layer "B.Cu")
		(at 71.19 118.125)
		(descr "Resistor SMD 0402")
		(tags "resistor SMD 0402")
		(property "Reference" "R37"
			(at -2.99 0.375 0)
			(layer "B.SilkS")
			(effects
				(font
					(size 0.7 0.7)
					(thickness 0.15)
				)
				(justify right bottom mirror)
			)
		)
		(property "Value" "R_10k_0402"
			(at 0 -1.4 0)
			(layer "B.Fab")
			(effects
				(font
					(size 0.7 0.7)
					(thickness 0.15)
				)
				(justify right bottom mirror)
			)
		)
		(property "Datasheet" "https://www.bourns.com/docs/product-datasheets/cr.pdf"
			(at 0 0 0)
			(layer "F.Fab")
			(hide yes)
			(effects
				(font
					(size 1.27 1.27)
					(thickness 0.15)
				)
			)
		)
		(property "Description" "SMD Chip Resistor, 10 kohm, ± 1%, 62.5 mW, 0402 [1005 Metric], Thick Film, General Purpose"
			(at 0 0 0)
			(layer "F.Fab")
			(hide yes)
			(effects
				(font
					(size 1.27 1.27)
					(thickness 0.15)
				)
			)
		)
		(property "Author" "Antmicro"
			(at 0 0 0)
			(layer "B.Fab")
			(hide yes)
			(effects
				(font
					(size 1 1)
					(thickness 0.15)
				)
				(justify mirror)
			)
		)
		(property "License" "Apache-2.0"
			(at 0 0 0)
			(layer "B.Fab")
			(hide yes)
			(effects
				(font
					(size 1 1)
					(thickness 0.15)
				)
				(justify mirror)
			)
		)
		(property "MPN" "CR0402-FX-1002GLF"
			(at 0 0 0)
			(layer "B.Fab")
			(hide yes)
			(effects
				(font
					(size 1 1)
					(thickness 0.15)
				)
				(justify mirror)
			)
		)
		(property "Manufacturer" "Bourns"
			(at 0 0 0)
			(layer "B.Fab")
			(hide yes)
			(effects
				(font
					(size 1 1)
					(thickness 0.15)
				)
				(justify mirror)
			)
		)
		(property "Tolerance" "1%"
			(at 0 0 0)
			(layer "B.Fab")
			(hide yes)
			(effects
				(font
					(size 1 1)
					(thickness 0.15)
				)
				(justify mirror)
			)
		)
		(property "Val" "10k"
			(at 0 0 0)
			(layer "B.Fab")
			(hide yes)
			(effects
				(font
					(size 1 1)
					(thickness 0.15)
				)
				(justify mirror)
			)
		)
		(sheetname "/RoT/")
		(sheetfile "rot.kicad_sch")
		(attr smd)
		(fp_rect
			(start -0.925 0.47)
			(end 0.925 -0.47)
			(stroke
				(width 0.05)
				(type default)
			)
			(fill no)
			(layer "B.CrtYd")
		)
		(fp_rect
			(start -0.5 0.25)
			(end 0.5 -0.25)
			(stroke
				(width 0.15)
				(type solid)
			)
			(fill no)
			(layer "B.Fab")
		)
		(pad "1" smd roundrect
			(at -0.48 0)
			(size 0.59 0.64)
			(layers "B.Cu" "B.Mask" "B.Paste")
			(roundrect_rratio 0.25)
			(net 128 "QSPIB2_D3")
			(pintype "passive")
		)
		(pad "2" smd roundrect
			(at 0.48 0)
			(size 0.59 0.64)
			(layers "B.Cu" "B.Mask" "B.Paste")
			(roundrect_rratio 0.25)
			(net 2 "VCC3V3")
			(pintype "passive")
		)
	)
	(footprint "antmicro-footprints:R_0402_1005Metric"
		(layer "B.Cu")
		(at 71.19 121.125)
		(descr "Resistor SMD 0402")
		(tags "resistor SMD 0402")
		(property "Reference" "R33"
			(at -2.99 0.375 0)
			(layer "B.SilkS")
			(effects
				(font
					(size 0.7 0.7)
					(thickness 0.15)
				)
				(justify right bottom mirror)
			)
		)
		(property "Value" "R_10k_0402"
			(at 0 -1.4 0)
			(layer "B.Fab")
			(effects
				(font
					(size 0.7 0.7)
					(thickness 0.15)
				)
				(justify right bottom mirror)
			)
		)
		(property "Datasheet" "https://www.bourns.com/docs/product-datasheets/cr.pdf"
			(at 0 0 0)
			(layer "F.Fab")
			(hide yes)
			(effects
				(font
					(size 1.27 1.27)
					(thickness 0.15)
				)
			)
		)
		(property "Description" "SMD Chip Resistor, 10 kohm, ± 1%, 62.5 mW, 0402 [1005 Metric], Thick Film, General Purpose"
			(at 0 0 0)
			(layer "F.Fab")
			(hide yes)
			(effects
				(font
					(size 1.27 1.27)
					(thickness 0.15)
				)
			)
		)
		(property "Author" "Antmicro"
			(at 0 0 0)
			(layer "B.Fab")
			(hide yes)
			(effects
				(font
					(size 1 1)
					(thickness 0.15)
				)
				(justify mirror)
			)
		)
		(property "License" "Apache-2.0"
			(at 0 0 0)
			(layer "B.Fab")
			(hide yes)
			(effects
				(font
					(size 1 1)
					(thickness 0.15)
				)
				(justify mirror)
			)
		)
		(property "MPN" "CR0402-FX-1002GLF"
			(at 0 0 0)
			(layer "B.Fab")
			(hide yes)
			(effects
				(font
					(size 1 1)
					(thickness 0.15)
				)
				(justify mirror)
			)
		)
		(property "Manufacturer" "Bourns"
			(at 0 0 0)
			(layer "B.Fab")
			(hide yes)
			(effects
				(font
					(size 1 1)
					(thickness 0.15)
				)
				(justify mirror)
			)
		)
		(property "Tolerance" "1%"
			(at 0 0 0)
			(layer "B.Fab")
			(hide yes)
			(effects
				(font
					(size 1 1)
					(thickness 0.15)
				)
				(justify mirror)
			)
		)
		(property "Val" "10k"
			(at 0 0 0)
			(layer "B.Fab")
			(hide yes)
			(effects
				(font
					(size 1 1)
					(thickness 0.15)
				)
				(justify mirror)
			)
		)
		(sheetname "/RoT/")
		(sheetfile "rot.kicad_sch")
		(attr smd)
		(fp_rect
			(start -0.925 0.47)
			(end 0.925 -0.47)
			(stroke
				(width 0.05)
				(type default)
			)
			(fill no)
			(layer "B.CrtYd")
		)
		(fp_rect
			(start -0.5 0.25)
			(end 0.5 -0.25)
			(stroke
				(width 0.15)
				(type solid)
			)
			(fill no)
			(layer "B.Fab")
		)
		(pad "1" smd roundrect
			(at -0.48 0)
			(size 0.59 0.64)
			(layers "B.Cu" "B.Mask" "B.Paste")
			(roundrect_rratio 0.25)
			(net 127 "QSPIB2_D2")
			(pintype "passive")
		)
		(pad "2" smd roundrect
			(at 0.48 0)
			(size 0.59 0.64)
			(layers "B.Cu" "B.Mask" "B.Paste")
			(roundrect_rratio 0.25)
			(net 2 "VCC3V3")
			(pintype "passive")
		)
	)
	(footprint "antmicro-footprints:C_0402_1005Metric"
		(layer "B.Cu")
		(at 64.605 117.59 90)
		(descr "Capacitor SMD 0402")
		(tags "capacitor SMD 0402")
		(property "Reference" "C35"
			(at -1.01 -0.605 90)
			(layer "B.SilkS")
			(effects
				(font
					(size 0.7 0.7)
					(thickness 0.15)
				)
				(justify right bottom mirror)
			)
		)
		(property "Value" "C_470n_0402"
			(at 0 -1.4 90)
			(layer "B.Fab")
			(effects
				(font
					(size 0.7 0.7)
					(thickness 0.15)
				)
				(justify right bottom mirror)
			)
		)
		(property "Datasheet" "https://product.tdk.com/en/search/capacitor/ceramic/mlcc/info?part_no=C1005X5R1E474M050BB"
			(at 0 0 90)
			(layer "F.Fab")
			(hide yes)
			(effects
				(font
					(size 1.27 1.27)
					(thickness 0.15)
				)
			)
		)
		(property "Description" "SMD Multilayer Ceramic Capacitor, 0.47 µF, 25 V, 0402 [1005 Metric], ± 20%, X5R, C"
			(at 0 0 90)
			(layer "F.Fab")
			(hide yes)
			(effects
				(font
					(size 1.27 1.27)
					(thickness 0.15)
				)
			)
		)
		(property "Author" "Antmicro"
			(at 182.195 52.985 0)
			(layer "B.Fab")
			(hide yes)
			(effects
				(font
					(size 1 1)
					(thickness 0.15)
				)
				(justify mirror)
			)
		)
		(property "Dielectric" ""
			(at 182.195 52.985 0)
			(layer "B.Fab")
			(hide yes)
			(effects
				(font
					(size 1 1)
					(thickness 0.15)
				)
				(justify mirror)
			)
		)
		(property "License" "Apache-2.0"
			(at 182.195 52.985 0)
			(layer "B.Fab")
			(hide yes)
			(effects
				(font
					(size 1 1)
					(thickness 0.15)
				)
				(justify mirror)
			)
		)
		(property "MPN" "C1005X5R1E474M050BB"
			(at 182.195 52.985 0)
			(layer "B.Fab")
			(hide yes)
			(effects
				(font
					(size 1 1)
					(thickness 0.15)
				)
				(justify mirror)
			)
		)
		(property "Manufacturer" "TDK"
			(at 182.195 52.985 0)
			(layer "B.Fab")
			(hide yes)
			(effects
				(font
					(size 1 1)
					(thickness 0.15)
				)
				(justify mirror)
			)
		)
		(property "Val" "470n"
			(at 182.195 52.985 0)
			(layer "B.Fab")
			(hide yes)
			(effects
				(font
					(size 1 1)
					(thickness 0.15)
				)
				(justify mirror)
			)
		)
		(property "Voltage" ""
			(at 182.195 52.985 0)
			(layer "B.Fab")
			(hide yes)
			(effects
				(font
					(size 1 1)
					(thickness 0.15)
				)
				(justify mirror)
			)
		)
		(sheetname "/RoT/")
		(sheetfile "rot.kicad_sch")
		(attr smd)
		(fp_rect
			(start -0.925 0.47)
			(end 0.925 -0.47)
			(stroke
				(width 0.05)
				(type default)
			)
			(fill no)
			(layer "B.CrtYd")
		)
		(fp_line
			(start 0.504 -0.248)
			(end -0.494 -0.248)
			(stroke
				(width 0.15)
				(type solid)
			)
			(layer "B.Fab")
		)
		(fp_line
			(start -0.494 -0.248)
			(end -0.494 0.25)
			(stroke
				(width 0.15)
				(type solid)
			)
			(layer "B.Fab")
		)
		(fp_line
			(start 0.504 0.25)
			(end 0.504 -0.248)
			(stroke
				(width 0.15)
				(type solid)
			)
			(layer "B.Fab")
		)
		(fp_line
			(start -0.494 0.25)
			(end 0.504 0.25)
			(stroke
				(width 0.15)
				(type solid)
			)
			(layer "B.Fab")
		)
		(pad "1" smd roundrect
			(at -0.48 0 90)
			(size 0.59 0.64)
			(layers "B.Cu" "B.Mask" "B.Paste")
			(roundrect_rratio 0.25)
			(net 1 "GND")
			(pintype "passive")
		)
		(pad "2" smd roundrect
			(at 0.48 0 90)
			(size 0.59 0.64)
			(layers "B.Cu" "B.Mask" "B.Paste")
			(roundrect_rratio 0.25)
			(net 2 "VCC3V3")
			(pintype "passive")
		)
	)
	(footprint "antmicro-footprints:R_0402_1005Metric"
		(layer "B.Cu")
		(at 71.24 144.925)
		(descr "Resistor SMD 0402")
		(tags "resistor SMD 0402")
		(property "Reference" "R32"
			(at -2.95 0.425 0)
			(layer "B.SilkS")
			(effects
				(font
					(size 0.7 0.7)
					(thickness 0.15)
				)
				(justify right bottom mirror)
			)
		)
		(property "Value" "R_10k_0402"
			(at 0 -1.4 0)
			(layer "B.Fab")
			(effects
				(font
					(size 0.7 0.7)
					(thickness 0.15)
				)
				(justify right bottom mirror)
			)
		)
		(property "Datasheet" "https://www.bourns.com/docs/product-datasheets/cr.pdf"
			(at 0 0 0)
			(layer "F.Fab")
			(hide yes)
			(effects
				(font
					(size 1.27 1.27)
					(thickness 0.15)
				)
			)
		)
		(property "Description" "SMD Chip Resistor, 10 kohm, ± 1%, 62.5 mW, 0402 [1005 Metric], Thick Film, General Purpose"
			(at 0 0 0)
			(layer "F.Fab")
			(hide yes)
			(effects
				(font
					(size 1.27 1.27)
					(thickness 0.15)
				)
			)
		)
		(property "Author" "Antmicro"
			(at 0 0 0)
			(layer "B.Fab")
			(hide yes)
			(effects
				(font
					(size 1 1)
					(thickness 0.15)
				)
				(justify mirror)
			)
		)
		(property "License" "Apache-2.0"
			(at 0 0 0)
			(layer "B.Fab")
			(hide yes)
			(effects
				(font
					(size 1 1)
					(thickness 0.15)
				)
				(justify mirror)
			)
		)
		(property "MPN" "CR0402-FX-1002GLF"
			(at 0 0 0)
			(layer "B.Fab")
			(hide yes)
			(effects
				(font
					(size 1 1)
					(thickness 0.15)
				)
				(justify mirror)
			)
		)
		(property "Manufacturer" "Bourns"
			(at 0 0 0)
			(layer "B.Fab")
			(hide yes)
			(effects
				(font
					(size 1 1)
					(thickness 0.15)
				)
				(justify mirror)
			)
		)
		(property "Tolerance" "1%"
			(at 0 0 0)
			(layer "B.Fab")
			(hide yes)
			(effects
				(font
					(size 1 1)
					(thickness 0.15)
				)
				(justify mirror)
			)
		)
		(property "Val" "10k"
			(at 0 0 0)
			(layer "B.Fab")
			(hide yes)
			(effects
				(font
					(size 1 1)
					(thickness 0.15)
				)
				(justify mirror)
			)
		)
		(sheetname "/RoT/")
		(sheetfile "rot.kicad_sch")
		(attr smd)
		(fp_rect
			(start -0.925 0.47)
			(end 0.925 -0.47)
			(stroke
				(width 0.05)
				(type default)
			)
			(fill no)
			(layer "B.CrtYd")
		)
		(fp_rect
			(start -0.5 0.25)
			(end 0.5 -0.25)
			(stroke
				(width 0.15)
				(type solid)
			)
			(fill no)
			(layer "B.Fab")
		)
		(pad "1" smd roundrect
			(at -0.48 0)
			(size 0.59 0.64)
			(layers "B.Cu" "B.Mask" "B.Paste")
			(roundrect_rratio 0.25)
			(net 131 "QSPIA1_D0")
			(pintype "passive")
		)
		(pad "2" smd roundrect
			(at 0.48 0)
			(size 0.59 0.64)
			(layers "B.Cu" "B.Mask" "B.Paste")
			(roundrect_rratio 0.25)
			(net 2 "VCC3V3")
			(pintype "passive")
		)
	)
	(footprint "antmicro-footprints:R_0402_1005Metric"
		(layer "B.Cu")
		(at 71.15 125.675)
		(descr "Resistor SMD 0402")
		(tags "resistor SMD 0402")
		(property "Reference" "R30"
			(at -2.95 0.425 0)
			(layer "B.SilkS")
			(effects
				(font
					(size 0.7 0.7)
					(thickness 0.15)
				)
				(justify right bottom mirror)
			)
		)
		(property "Value" "R_10k_0402"
			(at 0 -1.4 0)
			(layer "B.Fab")
			(effects
				(font
					(size 0.7 0.7)
					(thickness 0.15)
				)
				(justify right bottom mirror)
			)
		)
		(property "Datasheet" "https://www.bourns.com/docs/product-datasheets/cr.pdf"
			(at 0 0 0)
			(layer "F.Fab")
			(hide yes)
			(effects
				(font
					(size 1.27 1.27)
					(thickness 0.15)
				)
			)
		)
		(property "Description" "SMD Chip Resistor, 10 kohm, ± 1%, 62.5 mW, 0402 [1005 Metric], Thick Film, General Purpose"
			(at 0 0 0)
			(layer "F.Fab")
			(hide yes)
			(effects
				(font
					(size 1.27 1.27)
					(thickness 0.15)
				)
			)
		)
		(property "Author" "Antmicro"
			(at 0 0 0)
			(layer "B.Fab")
			(hide yes)
			(effects
				(font
					(size 1 1)
					(thickness 0.15)
				)
				(justify mirror)
			)
		)
		(property "License" "Apache-2.0"
			(at 0 0 0)
			(layer "B.Fab")
			(hide yes)
			(effects
				(font
					(size 1 1)
					(thickness 0.15)
				)
				(justify mirror)
			)
		)
		(property "MPN" "CR0402-FX-1002GLF"
			(at 0 0 0)
			(layer "B.Fab")
			(hide yes)
			(effects
				(font
					(size 1 1)
					(thickness 0.15)
				)
				(justify mirror)
			)
		)
		(property "Manufacturer" "Bourns"
			(at 0 0 0)
			(layer "B.Fab")
			(hide yes)
			(effects
				(font
					(size 1 1)
					(thickness 0.15)
				)
				(justify mirror)
			)
		)
		(property "Tolerance" "1%"
			(at 0 0 0)
			(layer "B.Fab")
			(hide yes)
			(effects
				(font
					(size 1 1)
					(thickness 0.15)
				)
				(justify mirror)
			)
		)
		(property "Val" "10k"
			(at 0 0 0)
			(layer "B.Fab")
			(hide yes)
			(effects
				(font
					(size 1 1)
					(thickness 0.15)
				)
				(justify mirror)
			)
		)
		(sheetname "/RoT/")
		(sheetfile "rot.kicad_sch")
		(attr smd)
		(fp_rect
			(start -0.925 0.47)
			(end 0.925 -0.47)
			(stroke
				(width 0.05)
				(type default)
			)
			(fill no)
			(layer "B.CrtYd")
		)
		(fp_rect
			(start -0.5 0.25)
			(end 0.5 -0.25)
			(stroke
				(width 0.15)
				(type solid)
			)
			(fill no)
			(layer "B.Fab")
		)
		(pad "1" smd roundrect
			(at -0.48 0)
			(size 0.59 0.64)
			(layers "B.Cu" "B.Mask" "B.Paste")
			(roundrect_rratio 0.25)
			(net 120 "QSPIB1_D0")
			(pintype "passive")
		)
		(pad "2" smd roundrect
			(at 0.48 0)
			(size 0.59 0.64)
			(layers "B.Cu" "B.Mask" "B.Paste")
			(roundrect_rratio 0.25)
			(net 2 "VCC3V3")
			(pintype "passive")
		)
	)
	(footprint "antmicro-footprints:R_0402_1005Metric"
		(layer "B.Cu")
		(at 71.24 145.925 180)
		(descr "Resistor SMD 0402")
		(tags "resistor SMD 0402")
		(property "Reference" "R28"
			(at 0.74 -0.375 0)
			(layer "B.SilkS")
			(effects
				(font
					(size 0.7 0.7)
					(thickness 0.15)
				)
				(justify left bottom mirror)
			)
		)
		(property "Value" "R_1k_0402"
			(at 0 -1.4 0)
			(layer "B.Fab")
			(effects
				(font
					(size 0.7 0.7)
					(thickness 0.15)
				)
				(justify left bottom mirror)
			)
		)
		(property "Datasheet" "https://www.bourns.com/docs/product-datasheets/cr.pdf"
			(at 0 0 180)
			(layer "F.Fab")
			(hide yes)
			(effects
				(font
					(size 1.27 1.27)
					(thickness 0.15)
				)
			)
		)
		(property "Description" "SMD Chip Resistor, 1 kohm, ± 1%, 63 mW, 0402 [1005 Metric], Thick Film, General Purpose"
			(at 0 0 180)
			(layer "F.Fab")
			(hide yes)
			(effects
				(font
					(size 1.27 1.27)
					(thickness 0.15)
				)
			)
		)
		(property "Author" "Antmicro"
			(at 142.48 291.85 0)
			(layer "B.Fab")
			(hide yes)
			(effects
				(font
					(size 1 1)
					(thickness 0.15)
				)
				(justify mirror)
			)
		)
		(property "License" "Apache-2.0"
			(at 142.48 291.85 0)
			(layer "B.Fab")
			(hide yes)
			(effects
				(font
					(size 1 1)
					(thickness 0.15)
				)
				(justify mirror)
			)
		)
		(property "MPN" "CR0402-FX-1001GLF"
			(at 142.48 291.85 0)
			(layer "B.Fab")
			(hide yes)
			(effects
				(font
					(size 1 1)
					(thickness 0.15)
				)
				(justify mirror)
			)
		)
		(property "Manufacturer" "Bourns"
			(at 142.48 291.85 0)
			(layer "B.Fab")
			(hide yes)
			(effects
				(font
					(size 1 1)
					(thickness 0.15)
				)
				(justify mirror)
			)
		)
		(property "Tolerance" "1%"
			(at 142.48 291.85 0)
			(layer "B.Fab")
			(hide yes)
			(effects
				(font
					(size 1 1)
					(thickness 0.15)
				)
				(justify mirror)
			)
		)
		(property "Val" "1k"
			(at 142.48 291.85 0)
			(layer "B.Fab")
			(hide yes)
			(effects
				(font
					(size 1 1)
					(thickness 0.15)
				)
				(justify mirror)
			)
		)
		(sheetname "/RoT/")
		(sheetfile "rot.kicad_sch")
		(attr smd)
		(fp_rect
			(start -0.925 0.47)
			(end 0.925 -0.47)
			(stroke
				(width 0.05)
				(type default)
			)
			(fill no)
			(layer "B.CrtYd")
		)
		(fp_rect
			(start -0.5 0.25)
			(end 0.5 -0.25)
			(stroke
				(width 0.15)
				(type solid)
			)
			(fill no)
			(layer "B.Fab")
		)
		(pad "1" smd roundrect
			(at -0.48 0 180)
			(size 0.59 0.64)
			(layers "B.Cu" "B.Mask" "B.Paste")
			(roundrect_rratio 0.25)
			(net 2 "VCC3V3")
			(pintype "passive")
		)
		(pad "2" smd roundrect
			(at 0.48 0 180)
			(size 0.59 0.64)
			(layers "B.Cu" "B.Mask" "B.Paste")
			(roundrect_rratio 0.25)
			(net 130 "QSPIA_CLK")
			(pintype "passive")
		)
	)
	(footprint "antmicro-footprints:R_0402_1005Metric"
		(layer "B.Cu")
		(at 71.15 126.675 180)
		(descr "Resistor SMD 0402")
		(tags "resistor SMD 0402")
		(property "Reference" "R26"
			(at 0.75 -0.425 0)
			(layer "B.SilkS")
			(effects
				(font
					(size 0.7 0.7)
					(thickness 0.15)
				)
				(justify left bottom mirror)
			)
		)
		(property "Value" "R_1k_0402"
			(at 0 -1.4 0)
			(layer "B.Fab")
			(effects
				(font
					(size 0.7 0.7)
					(thickness 0.15)
				)
				(justify left bottom mirror)
			)
		)
		(property "Datasheet" "https://www.bourns.com/docs/product-datasheets/cr.pdf"
			(at 0 0 180)
			(layer "F.Fab")
			(hide yes)
			(effects
				(font
					(size 1.27 1.27)
					(thickness 0.15)
				)
			)
		)
		(property "Description" "SMD Chip Resistor, 1 kohm, ± 1%, 63 mW, 0402 [1005 Metric], Thick Film, General Purpose"
			(at 0 0 180)
			(layer "F.Fab")
			(hide yes)
			(effects
				(font
					(size 1.27 1.27)
					(thickness 0.15)
				)
			)
		)
		(property "Author" "Antmicro"
			(at 142.3 253.35 0)
			(layer "B.Fab")
			(hide yes)
			(effects
				(font
					(size 1 1)
					(thickness 0.15)
				)
				(justify mirror)
			)
		)
		(property "License" "Apache-2.0"
			(at 142.3 253.35 0)
			(layer "B.Fab")
			(hide yes)
			(effects
				(font
					(size 1 1)
					(thickness 0.15)
				)
				(justify mirror)
			)
		)
		(property "MPN" "CR0402-FX-1001GLF"
			(at 142.3 253.35 0)
			(layer "B.Fab")
			(hide yes)
			(effects
				(font
					(size 1 1)
					(thickness 0.15)
				)
				(justify mirror)
			)
		)
		(property "Manufacturer" "Bourns"
			(at 142.3 253.35 0)
			(layer "B.Fab")
			(hide yes)
			(effects
				(font
					(size 1 1)
					(thickness 0.15)
				)
				(justify mirror)
			)
		)
		(property "Tolerance" "1%"
			(at 142.3 253.35 0)
			(layer "B.Fab")
			(hide yes)
			(effects
				(font
					(size 1 1)
					(thickness 0.15)
				)
				(justify mirror)
			)
		)
		(property "Val" "1k"
			(at 142.3 253.35 0)
			(layer "B.Fab")
			(hide yes)
			(effects
				(font
					(size 1 1)
					(thickness 0.15)
				)
				(justify mirror)
			)
		)
		(sheetname "/RoT/")
		(sheetfile "rot.kicad_sch")
		(attr smd)
		(fp_rect
			(start -0.925 0.47)
			(end 0.925 -0.47)
			(stroke
				(width 0.05)
				(type default)
			)
			(fill no)
			(layer "B.CrtYd")
		)
		(fp_rect
			(start -0.5 0.25)
			(end 0.5 -0.25)
			(stroke
				(width 0.15)
				(type solid)
			)
			(fill no)
			(layer "B.Fab")
		)
		(pad "1" smd roundrect
			(at -0.48 0 180)
			(size 0.59 0.64)
			(layers "B.Cu" "B.Mask" "B.Paste")
			(roundrect_rratio 0.25)
			(net 2 "VCC3V3")
			(pintype "passive")
		)
		(pad "2" smd roundrect
			(at 0.48 0 180)
			(size 0.59 0.64)
			(layers "B.Cu" "B.Mask" "B.Paste")
			(roundrect_rratio 0.25)
			(net 119 "QSPIB_CLK")
			(pintype "passive")
		)
	)
	(footprint "antmicro-footprints:R_0402_1005Metric"
		(layer "B.Cu")
		(at 71.24 147.925 180)
		(descr "Resistor SMD 0402")
		(tags "resistor SMD 0402")
		(property "Reference" "R24"
			(at 0.74 -0.375 0)
			(layer "B.SilkS")
			(effects
				(font
					(size 0.7 0.7)
					(thickness 0.15)
				)
				(justify left bottom mirror)
			)
		)
		(property "Value" "R_4k7_0402"
			(at 0 -1.4 0)
			(layer "B.Fab")
			(effects
				(font
					(size 0.7 0.7)
					(thickness 0.15)
				)
				(justify left bottom mirror)
			)
		)
		(property "Datasheet" "https://www.bourns.com/docs/product-datasheets/cr.pdf"
			(at 0 0 180)
			(layer "F.Fab")
			(hide yes)
			(effects
				(font
					(size 1.27 1.27)
					(thickness 0.15)
				)
			)
		)
		(property "Description" "SMD Chip Resistor, 4.7 kohm, ± 1%, 62.5 mW, 0402 [1005 Metric], Thick Film, General Purpose"
			(at 0 0 180)
			(layer "F.Fab")
			(hide yes)
			(effects
				(font
					(size 1.27 1.27)
					(thickness 0.15)
				)
			)
		)
		(property "Author" "Antmicro"
			(at 142.48 295.85 0)
			(layer "B.Fab")
			(hide yes)
			(effects
				(font
					(size 1 1)
					(thickness 0.15)
				)
				(justify mirror)
			)
		)
		(property "License" "Apache-2.0"
			(at 142.48 295.85 0)
			(layer "B.Fab")
			(hide yes)
			(effects
				(font
					(size 1 1)
					(thickness 0.15)
				)
				(justify mirror)
			)
		)
		(property "MPN" "CR0402-FX-4701GLF"
			(at 142.48 295.85 0)
			(layer "B.Fab")
			(hide yes)
			(effects
				(font
					(size 1 1)
					(thickness 0.15)
				)
				(justify mirror)
			)
		)
		(property "Manufacturer" "Bourns"
			(at 142.48 295.85 0)
			(layer "B.Fab")
			(hide yes)
			(effects
				(font
					(size 1 1)
					(thickness 0.15)
				)
				(justify mirror)
			)
		)
		(property "Tolerance" "1%"
			(at 142.48 295.85 0)
			(layer "B.Fab")
			(hide yes)
			(effects
				(font
					(size 1 1)
					(thickness 0.15)
				)
				(justify mirror)
			)
		)
		(property "Val" "4k7"
			(at 142.48 295.85 0)
			(layer "B.Fab")
			(hide yes)
			(effects
				(font
					(size 1 1)
					(thickness 0.15)
				)
				(justify mirror)
			)
		)
		(sheetname "/RoT/")
		(sheetfile "rot.kicad_sch")
		(attr smd)
		(fp_rect
			(start -0.925 0.47)
			(end 0.925 -0.47)
			(stroke
				(width 0.05)
				(type default)
			)
			(fill no)
			(layer "B.CrtYd")
		)
		(fp_rect
			(start -0.5 0.25)
			(end 0.5 -0.25)
			(stroke
				(width 0.15)
				(type solid)
			)
			(fill no)
			(layer "B.Fab")
		)
		(pad "1" smd roundrect
			(at -0.48 0 180)
			(size 0.59 0.64)
			(layers "B.Cu" "B.Mask" "B.Paste")
			(roundrect_rratio 0.25)
			(net 2 "VCC3V3")
			(pintype "passive")
		)
		(pad "2" smd roundrect
			(at 0.48 0 180)
			(size 0.59 0.64)
			(layers "B.Cu" "B.Mask" "B.Paste")
			(roundrect_rratio 0.25)
			(net 135 "QSPIA1_CS_N")
			(pintype "passive")
		)
	)
	(footprint "antmicro-footprints:R_0402_1005Metric"
		(layer "B.Cu")
		(at 71.15 128.675 180)
		(descr "Resistor SMD 0402")
		(tags "resistor SMD 0402")
		(property "Reference" "R22"
			(at 0.75 -0.425 0)
			(layer "B.SilkS")
			(effects
				(font
					(size 0.7 0.7)
					(thickness 0.15)
				)
				(justify left bottom mirror)
			)
		)
		(property "Value" "R_4k7_0402"
			(at 0 -1.4 0)
			(layer "B.Fab")
			(effects
				(font
					(size 0.7 0.7)
					(thickness 0.15)
				)
				(justify left bottom mirror)
			)
		)
		(property "Datasheet" "https://www.bourns.com/docs/product-datasheets/cr.pdf"
			(at 0 0 180)
			(layer "F.Fab")
			(hide yes)
			(effects
				(font
					(size 1.27 1.27)
					(thickness 0.15)
				)
			)
		)
		(property "Description" "SMD Chip Resistor, 4.7 kohm, ± 1%, 62.5 mW, 0402 [1005 Metric], Thick Film, General Purpose"
			(at 0 0 180)
			(layer "F.Fab")
			(hide yes)
			(effects
				(font
					(size 1.27 1.27)
					(thickness 0.15)
				)
			)
		)
		(property "Author" "Antmicro"
			(at 142.3 257.35 0)
			(layer "B.Fab")
			(hide yes)
			(effects
				(font
					(size 1 1)
					(thickness 0.15)
				)
				(justify mirror)
			)
		)
		(property "License" "Apache-2.0"
			(at 142.3 257.35 0)
			(layer "B.Fab")
			(hide yes)
			(effects
				(font
					(size 1 1)
					(thickness 0.15)
				)
				(justify mirror)
			)
		)
		(property "MPN" "CR0402-FX-4701GLF"
			(at 142.3 257.35 0)
			(layer "B.Fab")
			(hide yes)
			(effects
				(font
					(size 1 1)
					(thickness 0.15)
				)
				(justify mirror)
			)
		)
		(property "Manufacturer" "Bourns"
			(at 142.3 257.35 0)
			(layer "B.Fab")
			(hide yes)
			(effects
				(font
					(size 1 1)
					(thickness 0.15)
				)
				(justify mirror)
			)
		)
		(property "Tolerance" "1%"
			(at 142.3 257.35 0)
			(layer "B.Fab")
			(hide yes)
			(effects
				(font
					(size 1 1)
					(thickness 0.15)
				)
				(justify mirror)
			)
		)
		(property "Val" "4k7"
			(at 142.3 257.35 0)
			(layer "B.Fab")
			(hide yes)
			(effects
				(font
					(size 1 1)
					(thickness 0.15)
				)
				(justify mirror)
			)
		)
		(sheetname "/RoT/")
		(sheetfile "rot.kicad_sch")
		(attr smd)
		(fp_rect
			(start -0.925 0.47)
			(end 0.925 -0.47)
			(stroke
				(width 0.05)
				(type default)
			)
			(fill no)
			(layer "B.CrtYd")
		)
		(fp_rect
			(start -0.5 0.25)
			(end 0.5 -0.25)
			(stroke
				(width 0.15)
				(type solid)
			)
			(fill no)
			(layer "B.Fab")
		)
		(pad "1" smd roundrect
			(at -0.48 0 180)
			(size 0.59 0.64)
			(layers "B.Cu" "B.Mask" "B.Paste")
			(roundrect_rratio 0.25)
			(net 2 "VCC3V3")
			(pintype "passive")
		)
		(pad "2" smd roundrect
			(at 0.48 0 180)
			(size 0.59 0.64)
			(layers "B.Cu" "B.Mask" "B.Paste")
			(roundrect_rratio 0.25)
			(net 124 "QSPIB1_CS_N")
			(pintype "passive")
		)
	)
	(footprint "antmicro-footprints:R_0402_1005Metric"
		(layer "B.Cu")
		(at 71.24 148.925)
		(descr "Resistor SMD 0402")
		(tags "resistor SMD 0402")
		(property "Reference" "R44"
			(at -2.95 0.425 0)
			(layer "B.SilkS")
			(effects
				(font
					(size 0.7 0.7)
					(thickness 0.15)
				)
				(justify right bottom mirror)
			)
		)
		(property "Value" "R_10k_0402"
			(at 0 -1.4 0)
			(layer "B.Fab")
			(effects
				(font
					(size 0.7 0.7)
					(thickness 0.15)
				)
				(justify right bottom mirror)
			)
		)
		(property "Datasheet" "https://www.bourns.com/docs/product-datasheets/cr.pdf"
			(at 0 0 0)
			(layer "F.Fab")
			(hide yes)
			(effects
				(font
					(size 1.27 1.27)
					(thickness 0.15)
				)
			)
		)
		(property "Description" "SMD Chip Resistor, 10 kohm, ± 1%, 62.5 mW, 0402 [1005 Metric], Thick Film, General Purpose"
			(at 0 0 0)
			(layer "F.Fab")
			(hide yes)
			(effects
				(font
					(size 1.27 1.27)
					(thickness 0.15)
				)
			)
		)
		(property "Author" "Antmicro"
			(at 0 0 0)
			(layer "B.Fab")
			(hide yes)
			(effects
				(font
					(size 1 1)
					(thickness 0.15)
				)
				(justify mirror)
			)
		)
		(property "License" "Apache-2.0"
			(at 0 0 0)
			(layer "B.Fab")
			(hide yes)
			(effects
				(font
					(size 1 1)
					(thickness 0.15)
				)
				(justify mirror)
			)
		)
		(property "MPN" "CR0402-FX-1002GLF"
			(at 0 0 0)
			(layer "B.Fab")
			(hide yes)
			(effects
				(font
					(size 1 1)
					(thickness 0.15)
				)
				(justify mirror)
			)
		)
		(property "Manufacturer" "Bourns"
			(at 0 0 0)
			(layer "B.Fab")
			(hide yes)
			(effects
				(font
					(size 1 1)
					(thickness 0.15)
				)
				(justify mirror)
			)
		)
		(property "Tolerance" "1%"
			(at 0 0 0)
			(layer "B.Fab")
			(hide yes)
			(effects
				(font
					(size 1 1)
					(thickness 0.15)
				)
				(justify mirror)
			)
		)
		(property "Val" "10k"
			(at 0 0 0)
			(layer "B.Fab")
			(hide yes)
			(effects
				(font
					(size 1 1)
					(thickness 0.15)
				)
				(justify mirror)
			)
		)
		(sheetname "/RoT/")
		(sheetfile "rot.kicad_sch")
		(attr smd)
		(fp_rect
			(start -0.925 0.47)
			(end 0.925 -0.47)
			(stroke
				(width 0.05)
				(type default)
			)
			(fill no)
			(layer "B.CrtYd")
		)
		(fp_rect
			(start -0.5 0.25)
			(end 0.5 -0.25)
			(stroke
				(width 0.15)
				(type solid)
			)
			(fill no)
			(layer "B.Fab")
		)
		(pad "1" smd roundrect
			(at -0.48 0)
			(size 0.59 0.64)
			(layers "B.Cu" "B.Mask" "B.Paste")
			(roundrect_rratio 0.25)
			(net 132 "QSPIA1_D1")
			(pintype "passive")
		)
		(pad "2" smd roundrect
			(at 0.48 0)
			(size 0.59 0.64)
			(layers "B.Cu" "B.Mask" "B.Paste")
			(roundrect_rratio 0.25)
			(net 2 "VCC3V3")
			(pintype "passive")
		)
	)
	(footprint "antmicro-footprints:R_0402_1005Metric"
		(layer "B.Cu")
		(at 71.15 129.675)
		(descr "Resistor SMD 0402")
		(tags "resistor SMD 0402")
		(property "Reference" "R42"
			(at -2.95 0.425 0)
			(layer "B.SilkS")
			(effects
				(font
					(size 0.7 0.7)
					(thickness 0.15)
				)
				(justify right bottom mirror)
			)
		)
		(property "Value" "R_10k_0402"
			(at 0 -1.4 0)
			(layer "B.Fab")
			(effects
				(font
					(size 0.7 0.7)
					(thickness 0.15)
				)
				(justify right bottom mirror)
			)
		)
		(property "Datasheet" "https://www.bourns.com/docs/product-datasheets/cr.pdf"
			(at 0 0 0)
			(layer "F.Fab")
			(hide yes)
			(effects
				(font
					(size 1.27 1.27)
					(thickness 0.15)
				)
			)
		)
		(property "Description" "SMD Chip Resistor, 10 kohm, ± 1%, 62.5 mW, 0402 [1005 Metric], Thick Film, General Purpose"
			(at 0 0 0)
			(layer "F.Fab")
			(hide yes)
			(effects
				(font
					(size 1.27 1.27)
					(thickness 0.15)
				)
			)
		)
		(property "Author" "Antmicro"
			(at 0 0 0)
			(layer "B.Fab")
			(hide yes)
			(effects
				(font
					(size 1 1)
					(thickness 0.15)
				)
				(justify mirror)
			)
		)
		(property "License" "Apache-2.0"
			(at 0 0 0)
			(layer "B.Fab")
			(hide yes)
			(effects
				(font
					(size 1 1)
					(thickness 0.15)
				)
				(justify mirror)
			)
		)
		(property "MPN" "CR0402-FX-1002GLF"
			(at 0 0 0)
			(layer "B.Fab")
			(hide yes)
			(effects
				(font
					(size 1 1)
					(thickness 0.15)
				)
				(justify mirror)
			)
		)
		(property "Manufacturer" "Bourns"
			(at 0 0 0)
			(layer "B.Fab")
			(hide yes)
			(effects
				(font
					(size 1 1)
					(thickness 0.15)
				)
				(justify mirror)
			)
		)
		(property "Tolerance" "1%"
			(at 0 0 0)
			(layer "B.Fab")
			(hide yes)
			(effects
				(font
					(size 1 1)
					(thickness 0.15)
				)
				(justify mirror)
			)
		)
		(property "Val" "10k"
			(at 0 0 0)
			(layer "B.Fab")
			(hide yes)
			(effects
				(font
					(size 1 1)
					(thickness 0.15)
				)
				(justify mirror)
			)
		)
		(sheetname "/RoT/")
		(sheetfile "rot.kicad_sch")
		(attr smd)
		(fp_rect
			(start -0.925 0.47)
			(end 0.925 -0.47)
			(stroke
				(width 0.05)
				(type default)
			)
			(fill no)
			(layer "B.CrtYd")
		)
		(fp_rect
			(start -0.5 0.25)
			(end 0.5 -0.25)
			(stroke
				(width 0.15)
				(type solid)
			)
			(fill no)
			(layer "B.Fab")
		)
		(pad "1" smd roundrect
			(at -0.48 0)
			(size 0.59 0.64)
			(layers "B.Cu" "B.Mask" "B.Paste")
			(roundrect_rratio 0.25)
			(net 121 "QSPIB1_D1")
			(pintype "passive")
		)
		(pad "2" smd roundrect
			(at 0.48 0)
			(size 0.59 0.64)
			(layers "B.Cu" "B.Mask" "B.Paste")
			(roundrect_rratio 0.25)
			(net 2 "VCC3V3")
			(pintype "passive")
		)
	)
	(footprint "antmicro-footprints:R_0402_1005Metric"
		(layer "B.Cu")
		(at 71.24 146.925)
		(descr "Resistor SMD 0402")
		(tags "resistor SMD 0402")
		(property "Reference" "R40"
			(at -2.95 0.425 0)
			(layer "B.SilkS")
			(effects
				(font
					(size 0.7 0.7)
					(thickness 0.15)
				)
				(justify right bottom mirror)
			)
		)
		(property "Value" "R_10k_0402"
			(at 0 -1.4 0)
			(layer "B.Fab")
			(effects
				(font
					(size 0.7 0.7)
					(thickness 0.15)
				)
				(justify right bottom mirror)
			)
		)
		(property "Datasheet" "https://www.bourns.com/docs/product-datasheets/cr.pdf"
			(at 0 0 0)
			(layer "F.Fab")
			(hide yes)
			(effects
				(font
					(size 1.27 1.27)
					(thickness 0.15)
				)
			)
		)
		(property "Description" "SMD Chip Resistor, 10 kohm, ± 1%, 62.5 mW, 0402 [1005 Metric], Thick Film, General Purpose"
			(at 0 0 0)
			(layer "F.Fab")
			(hide yes)
			(effects
				(font
					(size 1.27 1.27)
					(thickness 0.15)
				)
			)
		)
		(property "Author" "Antmicro"
			(at 0 0 0)
			(layer "B.Fab")
			(hide yes)
			(effects
				(font
					(size 1 1)
					(thickness 0.15)
				)
				(justify mirror)
			)
		)
		(property "License" "Apache-2.0"
			(at 0 0 0)
			(layer "B.Fab")
			(hide yes)
			(effects
				(font
					(size 1 1)
					(thickness 0.15)
				)
				(justify mirror)
			)
		)
		(property "MPN" "CR0402-FX-1002GLF"
			(at 0 0 0)
			(layer "B.Fab")
			(hide yes)
			(effects
				(font
					(size 1 1)
					(thickness 0.15)
				)
				(justify mirror)
			)
		)
		(property "Manufacturer" "Bourns"
			(at 0 0 0)
			(layer "B.Fab")
			(hide yes)
			(effects
				(font
					(size 1 1)
					(thickness 0.15)
				)
				(justify mirror)
			)
		)
		(property "Tolerance" "1%"
			(at 0 0 0)
			(layer "B.Fab")
			(hide yes)
			(effects
				(font
					(size 1 1)
					(thickness 0.15)
				)
				(justify mirror)
			)
		)
		(property "Val" "10k"
			(at 0 0 0)
			(layer "B.Fab")
			(hide yes)
			(effects
				(font
					(size 1 1)
					(thickness 0.15)
				)
				(justify mirror)
			)
		)
		(sheetname "/RoT/")
		(sheetfile "rot.kicad_sch")
		(attr smd)
		(fp_rect
			(start -0.925 0.47)
			(end 0.925 -0.47)
			(stroke
				(width 0.05)
				(type default)
			)
			(fill no)
			(layer "B.CrtYd")
		)
		(fp_rect
			(start -0.5 0.25)
			(end 0.5 -0.25)
			(stroke
				(width 0.15)
				(type solid)
			)
			(fill no)
			(layer "B.Fab")
		)
		(pad "1" smd roundrect
			(at -0.48 0)
			(size 0.59 0.64)
			(layers "B.Cu" "B.Mask" "B.Paste")
			(roundrect_rratio 0.25)
			(net 134 "QSPIA1_D3")
			(pintype "passive")
		)
		(pad "2" smd roundrect
			(at 0.48 0)
			(size 0.59 0.64)
			(layers "B.Cu" "B.Mask" "B.Paste")
			(roundrect_rratio 0.25)
			(net 2 "VCC3V3")
			(pintype "passive")
		)
	)
	(footprint "antmicro-footprints:R_0402_1005Metric"
		(layer "B.Cu")
		(at 71.15 127.675)
		(descr "Resistor SMD 0402")
		(tags "resistor SMD 0402")
		(property "Reference" "R38"
			(at -2.95 0.425 0)
			(layer "B.SilkS")
			(effects
				(font
					(size 0.7 0.7)
					(thickness 0.15)
				)
				(justify right bottom mirror)
			)
		)
		(property "Value" "R_10k_0402"
			(at 0 -1.4 0)
			(layer "B.Fab")
			(effects
				(font
					(size 0.7 0.7)
					(thickness 0.15)
				)
				(justify right bottom mirror)
			)
		)
		(property "Datasheet" "https://www.bourns.com/docs/product-datasheets/cr.pdf"
			(at 0 0 0)
			(layer "F.Fab")
			(hide yes)
			(effects
				(font
					(size 1.27 1.27)
					(thickness 0.15)
				)
			)
		)
		(property "Description" "SMD Chip Resistor, 10 kohm, ± 1%, 62.5 mW, 0402 [1005 Metric], Thick Film, General Purpose"
			(at 0 0 0)
			(layer "F.Fab")
			(hide yes)
			(effects
				(font
					(size 1.27 1.27)
					(thickness 0.15)
				)
			)
		)
		(property "Author" "Antmicro"
			(at 0 0 0)
			(layer "B.Fab")
			(hide yes)
			(effects
				(font
					(size 1 1)
					(thickness 0.15)
				)
				(justify mirror)
			)
		)
		(property "License" "Apache-2.0"
			(at 0 0 0)
			(layer "B.Fab")
			(hide yes)
			(effects
				(font
					(size 1 1)
					(thickness 0.15)
				)
				(justify mirror)
			)
		)
		(property "MPN" "CR0402-FX-1002GLF"
			(at 0 0 0)
			(layer "B.Fab")
			(hide yes)
			(effects
				(font
					(size 1 1)
					(thickness 0.15)
				)
				(justify mirror)
			)
		)
		(property "Manufacturer" "Bourns"
			(at 0 0 0)
			(layer "B.Fab")
			(hide yes)
			(effects
				(font
					(size 1 1)
					(thickness 0.15)
				)
				(justify mirror)
			)
		)
		(property "Tolerance" "1%"
			(at 0 0 0)
			(layer "B.Fab")
			(hide yes)
			(effects
				(font
					(size 1 1)
					(thickness 0.15)
				)
				(justify mirror)
			)
		)
		(property "Val" "10k"
			(at 0 0 0)
			(layer "B.Fab")
			(hide yes)
			(effects
				(font
					(size 1 1)
					(thickness 0.15)
				)
				(justify mirror)
			)
		)
		(sheetname "/RoT/")
		(sheetfile "rot.kicad_sch")
		(attr smd)
		(fp_rect
			(start -0.925 0.47)
			(end 0.925 -0.47)
			(stroke
				(width 0.05)
				(type default)
			)
			(fill no)
			(layer "B.CrtYd")
		)
		(fp_rect
			(start -0.5 0.25)
			(end 0.5 -0.25)
			(stroke
				(width 0.15)
				(type solid)
			)
			(fill no)
			(layer "B.Fab")
		)
		(pad "1" smd roundrect
			(at -0.48 0)
			(size 0.59 0.64)
			(layers "B.Cu" "B.Mask" "B.Paste")
			(roundrect_rratio 0.25)
			(net 123 "QSPIB1_D3")
			(pintype "passive")
		)
		(pad "2" smd roundrect
			(at 0.48 0)
			(size 0.59 0.64)
			(layers "B.Cu" "B.Mask" "B.Paste")
			(roundrect_rratio 0.25)
			(net 2 "VCC3V3")
			(pintype "passive")
		)
	)
	(footprint "antmicro-footprints:R_0402_1005Metric"
		(layer "B.Cu")
		(at 71.24 149.925)
		(descr "Resistor SMD 0402")
		(tags "resistor SMD 0402")
		(property "Reference" "R36"
			(at -2.95 0.425 0)
			(layer "B.SilkS")
			(effects
				(font
					(size 0.7 0.7)
					(thickness 0.15)
				)
				(justify right bottom mirror)
			)
		)
		(property "Value" "R_10k_0402"
			(at 0 -1.4 0)
			(layer "B.Fab")
			(effects
				(font
					(size 0.7 0.7)
					(thickness 0.15)
				)
				(justify right bottom mirror)
			)
		)
		(property "Datasheet" "https://www.bourns.com/docs/product-datasheets/cr.pdf"
			(at 0 0 0)
			(layer "F.Fab")
			(hide yes)
			(effects
				(font
					(size 1.27 1.27)
					(thickness 0.15)
				)
			)
		)
		(property "Description" "SMD Chip Resistor, 10 kohm, ± 1%, 62.5 mW, 0402 [1005 Metric], Thick Film, General Purpose"
			(at 0 0 0)
			(layer "F.Fab")
			(hide yes)
			(effects
				(font
					(size 1.27 1.27)
					(thickness 0.15)
				)
			)
		)
		(property "Author" "Antmicro"
			(at 0 0 0)
			(layer "B.Fab")
			(hide yes)
			(effects
				(font
					(size 1 1)
					(thickness 0.15)
				)
				(justify mirror)
			)
		)
		(property "License" "Apache-2.0"
			(at 0 0 0)
			(layer "B.Fab")
			(hide yes)
			(effects
				(font
					(size 1 1)
					(thickness 0.15)
				)
				(justify mirror)
			)
		)
		(property "MPN" "CR0402-FX-1002GLF"
			(at 0 0 0)
			(layer "B.Fab")
			(hide yes)
			(effects
				(font
					(size 1 1)
					(thickness 0.15)
				)
				(justify mirror)
			)
		)
		(property "Manufacturer" "Bourns"
			(at 0 0 0)
			(layer "B.Fab")
			(hide yes)
			(effects
				(font
					(size 1 1)
					(thickness 0.15)
				)
				(justify mirror)
			)
		)
		(property "Tolerance" "1%"
			(at 0 0 0)
			(layer "B.Fab")
			(hide yes)
			(effects
				(font
					(size 1 1)
					(thickness 0.15)
				)
				(justify mirror)
			)
		)
		(property "Val" "10k"
			(at 0 0 0)
			(layer "B.Fab")
			(hide yes)
			(effects
				(font
					(size 1 1)
					(thickness 0.15)
				)
				(justify mirror)
			)
		)
		(sheetname "/RoT/")
		(sheetfile "rot.kicad_sch")
		(attr smd)
		(fp_rect
			(start -0.925 0.47)
			(end 0.925 -0.47)
			(stroke
				(width 0.05)
				(type default)
			)
			(fill no)
			(layer "B.CrtYd")
		)
		(fp_rect
			(start -0.5 0.25)
			(end 0.5 -0.25)
			(stroke
				(width 0.15)
				(type solid)
			)
			(fill no)
			(layer "B.Fab")
		)
		(pad "1" smd roundrect
			(at -0.48 0)
			(size 0.59 0.64)
			(layers "B.Cu" "B.Mask" "B.Paste")
			(roundrect_rratio 0.25)
			(net 133 "QSPIA1_D2")
			(pintype "passive")
		)
		(pad "2" smd roundrect
			(at 0.48 0)
			(size 0.59 0.64)
			(layers "B.Cu" "B.Mask" "B.Paste")
			(roundrect_rratio 0.25)
			(net 2 "VCC3V3")
			(pintype "passive")
		)
	)
	(footprint "antmicro-footprints:R_0402_1005Metric"
		(layer "B.Cu")
		(at 71.15 130.675)
		(descr "Resistor SMD 0402")
		(tags "resistor SMD 0402")
		(property "Reference" "R34"
			(at -2.95 0.425 0)
			(layer "B.SilkS")
			(effects
				(font
					(size 0.7 0.7)
					(thickness 0.15)
				)
				(justify right bottom mirror)
			)
		)
		(property "Value" "R_10k_0402"
			(at 0 -1.4 0)
			(layer "B.Fab")
			(effects
				(font
					(size 0.7 0.7)
					(thickness 0.15)
				)
				(justify right bottom mirror)
			)
		)
		(property "Datasheet" "https://www.bourns.com/docs/product-datasheets/cr.pdf"
			(at 0 0 0)
			(layer "F.Fab")
			(hide yes)
			(effects
				(font
					(size 1.27 1.27)
					(thickness 0.15)
				)
			)
		)
		(property "Description" "SMD Chip Resistor, 10 kohm, ± 1%, 62.5 mW, 0402 [1005 Metric], Thick Film, General Purpose"
			(at 0 0 0)
			(layer "F.Fab")
			(hide yes)
			(effects
				(font
					(size 1.27 1.27)
					(thickness 0.15)
				)
			)
		)
		(property "Author" "Antmicro"
			(at 0 0 0)
			(layer "B.Fab")
			(hide yes)
			(effects
				(font
					(size 1 1)
					(thickness 0.15)
				)
				(justify mirror)
			)
		)
		(property "License" "Apache-2.0"
			(at 0 0 0)
			(layer "B.Fab")
			(hide yes)
			(effects
				(font
					(size 1 1)
					(thickness 0.15)
				)
				(justify mirror)
			)
		)
		(property "MPN" "CR0402-FX-1002GLF"
			(at 0 0 0)
			(layer "B.Fab")
			(hide yes)
			(effects
				(font
					(size 1 1)
					(thickness 0.15)
				)
				(justify mirror)
			)
		)
		(property "Manufacturer" "Bourns"
			(at 0 0 0)
			(layer "B.Fab")
			(hide yes)
			(effects
				(font
					(size 1 1)
					(thickness 0.15)
				)
				(justify mirror)
			)
		)
		(property "Tolerance" "1%"
			(at 0 0 0)
			(layer "B.Fab")
			(hide yes)
			(effects
				(font
					(size 1 1)
					(thickness 0.15)
				)
				(justify mirror)
			)
		)
		(property "Val" "10k"
			(at 0 0 0)
			(layer "B.Fab")
			(hide yes)
			(effects
				(font
					(size 1 1)
					(thickness 0.15)
				)
				(justify mirror)
			)
		)
		(sheetname "/RoT/")
		(sheetfile "rot.kicad_sch")
		(attr smd)
		(fp_rect
			(start -0.925 0.47)
			(end 0.925 -0.47)
			(stroke
				(width 0.05)
				(type default)
			)
			(fill no)
			(layer "B.CrtYd")
		)
		(fp_rect
			(start -0.5 0.25)
			(end 0.5 -0.25)
			(stroke
				(width 0.15)
				(type solid)
			)
			(fill no)
			(layer "B.Fab")
		)
		(pad "1" smd roundrect
			(at -0.48 0)
			(size 0.59 0.64)
			(layers "B.Cu" "B.Mask" "B.Paste")
			(roundrect_rratio 0.25)
			(net 122 "QSPIB1_D2")
			(pintype "passive")
		)
		(pad "2" smd roundrect
			(at 0.48 0)
			(size 0.59 0.64)
			(layers "B.Cu" "B.Mask" "B.Paste")
			(roundrect_rratio 0.25)
			(net 2 "VCC3V3")
			(pintype "passive")
		)
	)
	(footprint "antmicro-footprints:C_0402_1005Metric"
		(layer "B.Cu")
		(at 98.075 146.375 90)
		(descr "Capacitor SMD 0402")
		(tags "capacitor SMD 0402")
		(property "Reference" "C155"
			(at 1.275 -8.675 90)
			(layer "B.SilkS")
			(effects
				(font
					(size 0.7 0.7)
					(thickness 0.15)
				)
				(justify right bottom mirror)
			)
		)
		(property "Value" "C_10u_0402"
			(at 0 -1.4 90)
			(layer "B.Fab")
			(effects
				(font
					(size 0.7 0.7)
					(thickness 0.15)
				)
				(justify right bottom mirror)
			)
		)
		(property "Datasheet" "https://www.yageo.com/en/Chart/Download/pdf/CC0402MRX5R5BB106"
			(at 0 0 90)
			(layer "F.Fab")
			(hide yes)
			(effects
				(font
					(size 1.27 1.27)
					(thickness 0.15)
				)
			)
		)
		(property "Description" "SMD Multilayer Ceramic Capacitor, 10 µF, 6.3 V, 0402 [1005 Metric], ± 20%, X5R, CC Series"
			(at 0 0 90)
			(layer "F.Fab")
			(hide yes)
			(effects
				(font
					(size 1.27 1.27)
					(thickness 0.15)
				)
			)
		)
		(property "Author" "Antmicro"
			(at 244.45 48.3 0)
			(layer "B.Fab")
			(hide yes)
			(effects
				(font
					(size 1 1)
					(thickness 0.15)
				)
				(justify mirror)
			)
		)
		(property "Dielectric" ""
			(at 244.45 48.3 0)
			(layer "B.Fab")
			(hide yes)
			(effects
				(font
					(size 1 1)
					(thickness 0.15)
				)
				(justify mirror)
			)
		)
		(property "License" "Apache-2.0"
			(at 244.45 48.3 0)
			(layer "B.Fab")
			(hide yes)
			(effects
				(font
					(size 1 1)
					(thickness 0.15)
				)
				(justify mirror)
			)
		)
		(property "MPN" "CC0402MRX5R5BB106"
			(at 244.45 48.3 0)
			(layer "B.Fab")
			(hide yes)
			(effects
				(font
					(size 1 1)
					(thickness 0.15)
				)
				(justify mirror)
			)
		)
		(property "Manufacturer" "YAGEO"
			(at 244.45 48.3 0)
			(layer "B.Fab")
			(hide yes)
			(effects
				(font
					(size 1 1)
					(thickness 0.15)
				)
				(justify mirror)
			)
		)
		(property "Val" "10u"
			(at 244.45 48.3 0)
			(layer "B.Fab")
			(hide yes)
			(effects
				(font
					(size 1 1)
					(thickness 0.15)
				)
				(justify mirror)
			)
		)
		(property "Voltage" ""
			(at 244.45 48.3 0)
			(layer "B.Fab")
			(hide yes)
			(effects
				(font
					(size 1 1)
					(thickness 0.15)
				)
				(justify mirror)
			)
		)
		(sheetname "/DDR3/")
		(sheetfile "ddr3.kicad_sch")
		(attr smd)
		(fp_rect
			(start -0.925 0.47)
			(end 0.925 -0.47)
			(stroke
				(width 0.05)
				(type default)
			)
			(fill no)
			(layer "B.CrtYd")
		)
		(fp_line
			(start 0.504 -0.248)
			(end -0.494 -0.248)
			(stroke
				(width 0.15)
				(type solid)
			)
			(layer "B.Fab")
		)
		(fp_line
			(start -0.494 -0.248)
			(end -0.494 0.25)
			(stroke
				(width 0.15)
				(type solid)
			)
			(layer "B.Fab")
		)
		(fp_line
			(start 0.504 0.25)
			(end 0.504 -0.248)
			(stroke
				(width 0.15)
				(type solid)
			)
			(layer "B.Fab")
		)
		(fp_line
			(start -0.494 0.25)
			(end 0.504 0.25)
			(stroke
				(width 0.15)
				(type solid)
			)
			(layer "B.Fab")
		)
		(pad "1" smd roundrect
			(at -0.48 0 90)
			(size 0.59 0.64)
			(layers "B.Cu" "B.Mask" "B.Paste")
			(roundrect_rratio 0.25)
			(net 1 "GND")
			(pintype "passive")
		)
		(pad "2" smd roundrect
			(at 0.48 0 90)
			(size 0.59 0.64)
			(layers "B.Cu" "B.Mask" "B.Paste")
			(roundrect_rratio 0.25)
			(net 143 "/DDR3/DDR3_VTT")
			(pintype "passive")
		)
	)
	(footprint "antmicro-footprints:C_0402_1005Metric"
		(layer "B.Cu")
		(at 98.57 87.005 90)
		(descr "Capacitor SMD 0402")
		(tags "capacitor SMD 0402")
		(property "Reference" "C228"
			(at 1.005 -1.07 90)
			(layer "B.SilkS")
			(effects
				(font
					(size 0.7 0.7)
					(thickness 0.15)
				)
				(justify right bottom mirror)
			)
		)
		(property "Value" "C_100n_0402"
			(at 0 -1.4 90)
			(layer "B.Fab")
			(effects
				(font
					(size 0.7 0.7)
					(thickness 0.15)
				)
				(justify right bottom mirror)
			)
		)
		(property "Datasheet" "https://www.murata.com/products/productdetail?partno=GRM155R61H104KE14%23"
			(at 0 0 90)
			(layer "F.Fab")
			(hide yes)
			(effects
				(font
					(size 1.27 1.27)
					(thickness 0.15)
				)
			)
		)
		(property "Description" "SMD Multilayer Ceramic Capacitor, 0.1 µF, 50 V, 0402 [1005 Metric], ± 10%, X5R, GRM Series"
			(at 0 0 90)
			(layer "F.Fab")
			(hide yes)
			(effects
				(font
					(size 1.27 1.27)
					(thickness 0.15)
				)
			)
		)
		(property "Author" "Antmicro"
			(at 185.575 -11.565 0)
			(layer "B.Fab")
			(hide yes)
			(effects
				(font
					(size 1 1)
					(thickness 0.15)
				)
				(justify mirror)
			)
		)
		(property "Dielectric" "X5R"
			(at 185.575 -11.565 0)
			(layer "B.Fab")
			(hide yes)
			(effects
				(font
					(size 1 1)
					(thickness 0.15)
				)
				(justify mirror)
			)
		)
		(property "License" "Apache-2.0"
			(at 185.575 -11.565 0)
			(layer "B.Fab")
			(hide yes)
			(effects
				(font
					(size 1 1)
					(thickness 0.15)
				)
				(justify mirror)
			)
		)
		(property "MPN" "GRM155R61H104KE14D"
			(at 185.575 -11.565 0)
			(layer "B.Fab")
			(hide yes)
			(effects
				(font
					(size 1 1)
					(thickness 0.15)
				)
				(justify mirror)
			)
		)
		(property "Manufacturer" "Murata"
			(at 185.575 -11.565 0)
			(layer "B.Fab")
			(hide yes)
			(effects
				(font
					(size 1 1)
					(thickness 0.15)
				)
				(justify mirror)
			)
		)
		(property "Val" "100n"
			(at 185.575 -11.565 0)
			(layer "B.Fab")
			(hide yes)
			(effects
				(font
					(size 1 1)
					(thickness 0.15)
				)
				(justify mirror)
			)
		)
		(property "Voltage" "50V"
			(at 185.575 -11.565 0)
			(layer "B.Fab")
			(hide yes)
			(effects
				(font
					(size 1 1)
					(thickness 0.15)
				)
				(justify mirror)
			)
		)
		(sheetname "/Ethernet/")
		(sheetfile "ethernet.kicad_sch")
		(attr smd)
		(fp_rect
			(start -0.925 0.47)
			(end 0.925 -0.47)
			(stroke
				(width 0.05)
				(type default)
			)
			(fill no)
			(layer "B.CrtYd")
		)
		(fp_line
			(start 0.504 -0.248)
			(end -0.494 -0.248)
			(stroke
				(width 0.15)
				(type solid)
			)
			(layer "B.Fab")
		)
		(fp_line
			(start -0.494 -0.248)
			(end -0.494 0.25)
			(stroke
				(width 0.15)
				(type solid)
			)
			(layer "B.Fab")
		)
		(fp_line
			(start 0.504 0.25)
			(end 0.504 -0.248)
			(stroke
				(width 0.15)
				(type solid)
			)
			(layer "B.Fab")
		)
		(fp_line
			(start -0.494 0.25)
			(end 0.504 0.25)
			(stroke
				(width 0.15)
				(type solid)
			)
			(layer "B.Fab")
		)
		(pad "1" smd roundrect
			(at -0.48 0 90)
			(size 0.59 0.64)
			(layers "B.Cu" "B.Mask" "B.Paste")
			(roundrect_rratio 0.25)
			(net 1 "GND")
			(pintype "passive")
		)
		(pad "2" smd roundrect
			(at 0.48 0 90)
			(size 0.59 0.64)
			(layers "B.Cu" "B.Mask" "B.Paste")
			(roundrect_rratio 0.25)
			(net 206 "Net-(J1-TRCT4)")
			(pintype "passive")
		)
	)
	(footprint "antmicro-footprints:R_0402_1005Metric"
		(layer "B.Cu")
		(at 70.967 91.556 -90)
		(descr "Resistor SMD 0402")
		(tags "resistor SMD 0402")
		(property "Reference" "R63"
			(at 1.884 -0.483 90)
			(layer "B.SilkS")
			(effects
				(font
					(size 0.7 0.7)
					(thickness 0.15)
				)
				(justify left bottom mirror)
			)
		)
		(property "Value" "R_100k_0402"
			(at 0 -1.4 90)
			(layer "B.Fab")
			(effects
				(font
					(size 0.7 0.7)
					(thickness 0.15)
				)
				(justify left bottom mirror)
			)
		)
		(property "Datasheet" "https://www.bourns.com/docs/product-datasheets/cr.pdf"
			(at 0 0 270)
			(layer "F.Fab")
			(hide yes)
			(effects
				(font
					(size 1.27 1.27)
					(thickness 0.15)
				)
			)
		)
		(property "Description" "SMD Chip Resistor, 100 kohm, ± 1%, 62.5 mW, 0402 [1005 Metric], Thick Film, General Purpose"
			(at 0 0 270)
			(layer "F.Fab")
			(hide yes)
			(effects
				(font
					(size 1.27 1.27)
					(thickness 0.15)
				)
			)
		)
		(property "Author" "Antmicro"
			(at -20.589 162.523 0)
			(layer "B.Fab")
			(hide yes)
			(effects
				(font
					(size 1 1)
					(thickness 0.15)
				)
				(justify mirror)
			)
		)
		(property "License" "Apache-2.0"
			(at -20.589 162.523 0)
			(layer "B.Fab")
			(hide yes)
			(effects
				(font
					(size 1 1)
					(thickness 0.15)
				)
				(justify mirror)
			)
		)
		(property "MPN" "CR0402-FX-1003GLF"
			(at -20.589 162.523 0)
			(layer "B.Fab")
			(hide yes)
			(effects
				(font
					(size 1 1)
					(thickness 0.15)
				)
				(justify mirror)
			)
		)
		(property "Manufacturer" "Bourns"
			(at -20.589 162.523 0)
			(layer "B.Fab")
			(hide yes)
			(effects
				(font
					(size 1 1)
					(thickness 0.15)
				)
				(justify mirror)
			)
		)
		(property "Tolerance" "1%"
			(at -20.589 162.523 0)
			(layer "B.Fab")
			(hide yes)
			(effects
				(font
					(size 1 1)
					(thickness 0.15)
				)
				(justify mirror)
			)
		)
		(property "Val" "100k"
			(at -20.589 162.523 0)
			(layer "B.Fab")
			(hide yes)
			(effects
				(font
					(size 1 1)
					(thickness 0.15)
				)
				(justify mirror)
			)
		)
		(sheetname "/Power supply/")
		(sheetfile "power-supply.kicad_sch")
		(attr smd)
		(fp_rect
			(start -0.925 0.47)
			(end 0.925 -0.47)
			(stroke
				(width 0.05)
				(type default)
			)
			(fill no)
			(layer "B.CrtYd")
		)
		(fp_rect
			(start -0.5 0.25)
			(end 0.5 -0.25)
			(stroke
				(width 0.15)
				(type solid)
			)
			(fill no)
			(layer "B.Fab")
		)
		(pad "1" smd roundrect
			(at -0.48 0 270)
			(size 0.59 0.64)
			(layers "B.Cu" "B.Mask" "B.Paste")
			(roundrect_rratio 0.25)
			(net 4 "VCC5V0")
			(pintype "passive")
		)
		(pad "2" smd roundrect
			(at 0.48 0 270)
			(size 0.59 0.64)
			(layers "B.Cu" "B.Mask" "B.Paste")
			(roundrect_rratio 0.25)
			(net 295 "/Power supply/VCCINT_EN")
			(pintype "passive")
		)
	)
	(footprint "antmicro-footprints:R_0402_1005Metric"
		(layer "B.Cu")
		(at 69.967 91.556 -90)
		(descr "Resistor SMD 0402")
		(tags "resistor SMD 0402")
		(property "Reference" "R64"
			(at 1.884 -0.393 90)
			(layer "B.SilkS")
			(effects
				(font
					(size 0.7 0.7)
					(thickness 0.15)
				)
				(justify left bottom mirror)
			)
		)
		(property "Value" "R_100k_0402"
			(at 0 -1.4 90)
			(layer "B.Fab")
			(effects
				(font
					(size 0.7 0.7)
					(thickness 0.15)
				)
				(justify left bottom mirror)
			)
		)
		(property "Datasheet" "https://www.bourns.com/docs/product-datasheets/cr.pdf"
			(at 0 0 270)
			(layer "F.Fab")
			(hide yes)
			(effects
				(font
					(size 1.27 1.27)
					(thickness 0.15)
				)
			)
		)
		(property "Description" "SMD Chip Resistor, 100 kohm, ± 1%, 62.5 mW, 0402 [1005 Metric], Thick Film, General Purpose"
			(at 0 0 270)
			(layer "F.Fab")
			(hide yes)
			(effects
				(font
					(size 1.27 1.27)
					(thickness 0.15)
				)
			)
		)
		(property "Author" "Antmicro"
			(at -21.589 161.523 0)
			(layer "B.Fab")
			(hide yes)
			(effects
				(font
					(size 1 1)
					(thickness 0.15)
				)
				(justify mirror)
			)
		)
		(property "License" "Apache-2.0"
			(at -21.589 161.523 0)
			(layer "B.Fab")
			(hide yes)
			(effects
				(font
					(size 1 1)
					(thickness 0.15)
				)
				(justify mirror)
			)
		)
		(property "MPN" "CR0402-FX-1003GLF"
			(at -21.589 161.523 0)
			(layer "B.Fab")
			(hide yes)
			(effects
				(font
					(size 1 1)
					(thickness 0.15)
				)
				(justify mirror)
			)
		)
		(property "Manufacturer" "Bourns"
			(at -21.589 161.523 0)
			(layer "B.Fab")
			(hide yes)
			(effects
				(font
					(size 1 1)
					(thickness 0.15)
				)
				(justify mirror)
			)
		)
		(property "Tolerance" "1%"
			(at -21.589 161.523 0)
			(layer "B.Fab")
			(hide yes)
			(effects
				(font
					(size 1 1)
					(thickness 0.15)
				)
				(justify mirror)
			)
		)
		(property "Val" "100k"
			(at -21.589 161.523 0)
			(layer "B.Fab")
			(hide yes)
			(effects
				(font
					(size 1 1)
					(thickness 0.15)
				)
				(justify mirror)
			)
		)
		(sheetname "/Power supply/")
		(sheetfile "power-supply.kicad_sch")
		(attr smd)
		(fp_rect
			(start -0.925 0.47)
			(end 0.925 -0.47)
			(stroke
				(width 0.05)
				(type default)
			)
			(fill no)
			(layer "B.CrtYd")
		)
		(fp_rect
			(start -0.5 0.25)
			(end 0.5 -0.25)
			(stroke
				(width 0.15)
				(type solid)
			)
			(fill no)
			(layer "B.Fab")
		)
		(pad "1" smd roundrect
			(at -0.48 0 270)
			(size 0.59 0.64)
			(layers "B.Cu" "B.Mask" "B.Paste")
			(roundrect_rratio 0.25)
			(net 4 "VCC5V0")
			(pintype "passive")
		)
		(pad "2" smd roundrect
			(at 0.48 0 270)
			(size 0.59 0.64)
			(layers "B.Cu" "B.Mask" "B.Paste")
			(roundrect_rratio 0.25)
			(net 296 "/Power supply/VCCAUX_EN")
			(pintype "passive")
		)
	)
	(footprint "antmicro-footprints:R_0402_1005Metric"
		(layer "B.Cu")
		(at 68.967 91.556 -90)
		(descr "Resistor SMD 0402")
		(tags "resistor SMD 0402")
		(property "Reference" "R65"
			(at 1.884 -0.353 90)
			(layer "B.SilkS")
			(effects
				(font
					(size 0.7 0.7)
					(thickness 0.15)
				)
				(justify left bottom mirror)
			)
		)
		(property "Value" "R_100k_0402"
			(at 0 -1.4 90)
			(layer "B.Fab")
			(effects
				(font
					(size 0.7 0.7)
					(thickness 0.15)
				)
				(justify left bottom mirror)
			)
		)
		(property "Datasheet" "https://www.bourns.com/docs/product-datasheets/cr.pdf"
			(at 0 0 270)
			(layer "F.Fab")
			(hide yes)
			(effects
				(font
					(size 1.27 1.27)
					(thickness 0.15)
				)
			)
		)
		(property "Description" "SMD Chip Resistor, 100 kohm, ± 1%, 62.5 mW, 0402 [1005 Metric], Thick Film, General Purpose"
			(at 0 0 270)
			(layer "F.Fab")
			(hide yes)
			(effects
				(font
					(size 1.27 1.27)
					(thickness 0.15)
				)
			)
		)
		(property "Author" "Antmicro"
			(at -22.589 160.523 0)
			(layer "B.Fab")
			(hide yes)
			(effects
				(font
					(size 1 1)
					(thickness 0.15)
				)
				(justify mirror)
			)
		)
		(property "License" "Apache-2.0"
			(at -22.589 160.523 0)
			(layer "B.Fab")
			(hide yes)
			(effects
				(font
					(size 1 1)
					(thickness 0.15)
				)
				(justify mirror)
			)
		)
		(property "MPN" "CR0402-FX-1003GLF"
			(at -22.589 160.523 0)
			(layer "B.Fab")
			(hide yes)
			(effects
				(font
					(size 1 1)
					(thickness 0.15)
				)
				(justify mirror)
			)
		)
		(property "Manufacturer" "Bourns"
			(at -22.589 160.523 0)
			(layer "B.Fab")
			(hide yes)
			(effects
				(font
					(size 1 1)
					(thickness 0.15)
				)
				(justify mirror)
			)
		)
		(property "Tolerance" "1%"
			(at -22.589 160.523 0)
			(layer "B.Fab")
			(hide yes)
			(effects
				(font
					(size 1 1)
					(thickness 0.15)
				)
				(justify mirror)
			)
		)
		(property "Val" "100k"
			(at -22.589 160.523 0)
			(layer "B.Fab")
			(hide yes)
			(effects
				(font
					(size 1 1)
					(thickness 0.15)
				)
				(justify mirror)
			)
		)
		(sheetname "/Power supply/")
		(sheetfile "power-supply.kicad_sch")
		(attr smd)
		(fp_rect
			(start -0.925 0.47)
			(end 0.925 -0.47)
			(stroke
				(width 0.05)
				(type default)
			)
			(fill no)
			(layer "B.CrtYd")
		)
		(fp_rect
			(start -0.5 0.25)
			(end 0.5 -0.25)
			(stroke
				(width 0.15)
				(type solid)
			)
			(fill no)
			(layer "B.Fab")
		)
		(pad "1" smd roundrect
			(at -0.48 0 270)
			(size 0.59 0.64)
			(layers "B.Cu" "B.Mask" "B.Paste")
			(roundrect_rratio 0.25)
			(net 4 "VCC5V0")
			(pintype "passive")
		)
		(pad "2" smd roundrect
			(at 0.48 0 270)
			(size 0.59 0.64)
			(layers "B.Cu" "B.Mask" "B.Paste")
			(roundrect_rratio 0.25)
			(net 297 "/Power supply/VCCIO_EN")
			(pintype "passive")
		)
	)
	(footprint "antmicro-footprints:C_0402_1005Metric"
		(layer "B.Cu")
		(at 64.565 146.325 90)
		(descr "Capacitor SMD 0402")
		(tags "capacitor SMD 0402")
		(property "Reference" "C38"
			(at -1.095 -0.575 90)
			(layer "B.SilkS")
			(effects
				(font
					(size 0.7 0.7)
					(thickness 0.15)
				)
				(justify right bottom mirror)
			)
		)
		(property "Value" "C_470n_0402"
			(at 0 -1.4 90)
			(layer "B.Fab")
			(effects
				(font
					(size 0.7 0.7)
					(thickness 0.15)
				)
				(justify right bottom mirror)
			)
		)
		(property "Datasheet" "https://product.tdk.com/en/search/capacitor/ceramic/mlcc/info?part_no=C1005X5R1E474M050BB"
			(at 0 0 90)
			(layer "F.Fab")
			(hide yes)
			(effects
				(font
					(size 1.27 1.27)
					(thickness 0.15)
				)
			)
		)
		(property "Description" "SMD Multilayer Ceramic Capacitor, 0.47 µF, 25 V, 0402 [1005 Metric], ± 20%, X5R, C"
			(at 0 0 90)
			(layer "F.Fab")
			(hide yes)
			(effects
				(font
					(size 1.27 1.27)
					(thickness 0.15)
				)
			)
		)
		(property "Author" "Antmicro"
			(at 210.89 81.76 0)
			(layer "B.Fab")
			(hide yes)
			(effects
				(font
					(size 1 1)
					(thickness 0.15)
				)
				(justify mirror)
			)
		)
		(property "Dielectric" ""
			(at 210.89 81.76 0)
			(layer "B.Fab")
			(hide yes)
			(effects
				(font
					(size 1 1)
					(thickness 0.15)
				)
				(justify mirror)
			)
		)
		(property "License" "Apache-2.0"
			(at 210.89 81.76 0)
			(layer "B.Fab")
			(hide yes)
			(effects
				(font
					(size 1 1)
					(thickness 0.15)
				)
				(justify mirror)
			)
		)
		(property "MPN" "C1005X5R1E474M050BB"
			(at 210.89 81.76 0)
			(layer "B.Fab")
			(hide yes)
			(effects
				(font
					(size 1 1)
					(thickness 0.15)
				)
				(justify mirror)
			)
		)
		(property "Manufacturer" "TDK"
			(at 210.89 81.76 0)
			(layer "B.Fab")
			(hide yes)
			(effects
				(font
					(size 1 1)
					(thickness 0.15)
				)
				(justify mirror)
			)
		)
		(property "Val" "470n"
			(at 210.89 81.76 0)
			(layer "B.Fab")
			(hide yes)
			(effects
				(font
					(size 1 1)
					(thickness 0.15)
				)
				(justify mirror)
			)
		)
		(property "Voltage" ""
			(at 210.89 81.76 0)
			(layer "B.Fab")
			(hide yes)
			(effects
				(font
					(size 1 1)
					(thickness 0.15)
				)
				(justify mirror)
			)
		)
		(sheetname "/RoT/")
		(sheetfile "rot.kicad_sch")
		(attr smd)
		(fp_rect
			(start -0.925 0.47)
			(end 0.925 -0.47)
			(stroke
				(width 0.05)
				(type default)
			)
			(fill no)
			(layer "B.CrtYd")
		)
		(fp_line
			(start 0.504 -0.248)
			(end -0.494 -0.248)
			(stroke
				(width 0.15)
				(type solid)
			)
			(layer "B.Fab")
		)
		(fp_line
			(start -0.494 -0.248)
			(end -0.494 0.25)
			(stroke
				(width 0.15)
				(type solid)
			)
			(layer "B.Fab")
		)
		(fp_line
			(start 0.504 0.25)
			(end 0.504 -0.248)
			(stroke
				(width 0.15)
				(type solid)
			)
			(layer "B.Fab")
		)
		(fp_line
			(start -0.494 0.25)
			(end 0.504 0.25)
			(stroke
				(width 0.15)
				(type solid)
			)
			(layer "B.Fab")
		)
		(pad "1" smd roundrect
			(at -0.48 0 90)
			(size 0.59 0.64)
			(layers "B.Cu" "B.Mask" "B.Paste")
			(roundrect_rratio 0.25)
			(net 1 "GND")
			(pintype "passive")
		)
		(pad "2" smd roundrect
			(at 0.48 0 90)
			(size 0.59 0.64)
			(layers "B.Cu" "B.Mask" "B.Paste")
			(roundrect_rratio 0.25)
			(net 2 "VCC3V3")
			(pintype "passive")
		)
	)
	(footprint "antmicro-footprints:C_0402_1005Metric"
		(layer "B.Cu")
		(at 94.845 162.485 90)
		(descr "Capacitor SMD 0402")
		(tags "capacitor SMD 0402")
		(property "Reference" "C195"
			(at -3.715 0.375 90)
			(layer "B.SilkS")
			(effects
				(font
					(size 0.7 0.7)
					(thickness 0.15)
				)
				(justify right bottom mirror)
			)
		)
		(property "Value" "C_100n_6V3_0402"
			(at 0 -1.4 90)
			(layer "B.Fab")
			(effects
				(font
					(size 0.7 0.7)
					(thickness 0.15)
				)
				(justify right bottom mirror)
			)
		)
		(property "Datasheet" "https://www.passivecomponent.com/wp-content/uploads/datasheet/WTC_MLCC_General_Purpose.pdf"
			(at 0 0 90)
			(layer "F.Fab")
			(hide yes)
			(effects
				(font
					(size 1.27 1.27)
					(thickness 0.15)
				)
			)
		)
		(property "Description" "SMT Multilayer Ceramic Capacitor, 0.1 µF, 6.3 V, 0402 [1005 Metric], ± 10%, X5R, Walsin MLCC"
			(at 0 0 90)
			(layer "F.Fab")
			(hide yes)
			(effects
				(font
					(size 1.27 1.27)
					(thickness 0.15)
				)
			)
		)
		(property "Author" "Antmicro"
			(at 257.33 67.64 0)
			(layer "B.Fab")
			(hide yes)
			(effects
				(font
					(size 1 1)
					(thickness 0.15)
				)
				(justify mirror)
			)
		)
		(property "Dielectric" ""
			(at 257.33 67.64 0)
			(layer "B.Fab")
			(hide yes)
			(effects
				(font
					(size 1 1)
					(thickness 0.15)
				)
				(justify mirror)
			)
		)
		(property "License" "Apache-2.0"
			(at 257.33 67.64 0)
			(layer "B.Fab")
			(hide yes)
			(effects
				(font
					(size 1 1)
					(thickness 0.15)
				)
				(justify mirror)
			)
		)
		(property "MPN" "0402X104K6R3CT"
			(at 257.33 67.64 0)
			(layer "B.Fab")
			(hide yes)
			(effects
				(font
					(size 1 1)
					(thickness 0.15)
				)
				(justify mirror)
			)
		)
		(property "Manufacturer" "Walsin"
			(at 257.33 67.64 0)
			(layer "B.Fab")
			(hide yes)
			(effects
				(font
					(size 1 1)
					(thickness 0.15)
				)
				(justify mirror)
			)
		)
		(property "Public" "False"
			(at 257.33 67.64 0)
			(layer "B.Fab")
			(hide yes)
			(effects
				(font
					(size 1 1)
					(thickness 0.15)
				)
				(justify mirror)
			)
		)
		(property "Val" "100n"
			(at 257.33 67.64 0)
			(layer "B.Fab")
			(hide yes)
			(effects
				(font
					(size 1 1)
					(thickness 0.15)
				)
				(justify mirror)
			)
		)
		(property "Voltage" ""
			(at 257.33 67.64 0)
			(layer "B.Fab")
			(hide yes)
			(effects
				(font
					(size 1 1)
					(thickness 0.15)
				)
				(justify mirror)
			)
		)
		(sheetname "/Interfaces/")
		(sheetfile "interfaces.kicad_sch")
		(attr smd)
		(fp_rect
			(start -0.925 0.47)
			(end 0.925 -0.47)
			(stroke
				(width 0.05)
				(type default)
			)
			(fill no)
			(layer "B.CrtYd")
		)
		(fp_line
			(start 0.504 -0.248)
			(end -0.494 -0.248)
			(stroke
				(width 0.15)
				(type solid)
			)
			(layer "B.Fab")
		)
		(fp_line
			(start -0.494 -0.248)
			(end -0.494 0.25)
			(stroke
				(width 0.15)
				(type solid)
			)
			(layer "B.Fab")
		)
		(fp_line
			(start 0.504 0.25)
			(end 0.504 -0.248)
			(stroke
				(width 0.15)
				(type solid)
			)
			(layer "B.Fab")
		)
		(fp_line
			(start -0.494 0.25)
			(end 0.504 0.25)
			(stroke
				(width 0.15)
				(type solid)
			)
			(layer "B.Fab")
		)
		(pad "1" smd roundrect
			(at -0.48 0 90)
			(size 0.59 0.64)
			(layers "B.Cu" "B.Mask" "B.Paste")
			(roundrect_rratio 0.25)
			(net 378 "PCIE_BMC_TX_P")
			(pintype "passive")
		)
		(pad "2" smd roundrect
			(at 0.48 0 90)
			(size 0.59 0.64)
			(layers "B.Cu" "B.Mask" "B.Paste")
			(roundrect_rratio 0.25)
			(net 490 "/Interfaces/PCIE_BMC_TX_C_P")
			(pintype "passive")
		)
	)
	(footprint "antmicro-footprints:C_1210_3225Metric"
		(layer "B.Cu")
		(at 96.4 103.127 180)
		(descr "Capacitor SMD 1210")
		(tags "capacitor SMD 1210")
		(property "Reference" "C147"
			(at 1.9 -0.373 0)
			(layer "B.SilkS")
			(effects
				(font
					(size 0.7 0.7)
					(thickness 0.15)
				)
				(justify left bottom mirror)
			)
		)
		(property "Value" "C_47u_1210"
			(at 0 -2.749 0)
			(layer "B.Fab")
			(effects
				(font
					(size 0.7 0.7)
					(thickness 0.15)
				)
				(justify left bottom mirror)
			)
		)
		(property "Datasheet" "https://www.kemet.com/en/us/capacitors/product/C1210C476K8RACTU.html"
			(at 0 0 180)
			(layer "F.Fab")
			(hide yes)
			(effects
				(font
					(size 1.27 1.27)
					(thickness 0.15)
				)
			)
		)
		(property "Description" "SMD Multilayer Ceramic Capacitor, 47 µF, 10 V, 1210 [3225 Metric], ± 10%, X7R, C Series KEMET"
			(at 0 0 180)
			(layer "F.Fab")
			(hide yes)
			(effects
				(font
					(size 1.27 1.27)
					(thickness 0.15)
				)
			)
		)
		(property "Author" "Antmicro"
			(at 192.8 206.254 0)
			(layer "B.Fab")
			(hide yes)
			(effects
				(font
					(size 1 1)
					(thickness 0.15)
				)
				(justify mirror)
			)
		)
		(property "Dielectric" ""
			(at 192.8 206.254 0)
			(layer "B.Fab")
			(hide yes)
			(effects
				(font
					(size 1 1)
					(thickness 0.15)
				)
				(justify mirror)
			)
		)
		(property "License" "Apache-2.0"
			(at 192.8 206.254 0)
			(layer "B.Fab")
			(hide yes)
			(effects
				(font
					(size 1 1)
					(thickness 0.15)
				)
				(justify mirror)
			)
		)
		(property "MPN" "C1210C476K8RACTU"
			(at 192.8 206.254 0)
			(layer "B.Fab")
			(hide yes)
			(effects
				(font
					(size 1 1)
					(thickness 0.15)
				)
				(justify mirror)
			)
		)
		(property "Manufacturer" "KEMET"
			(at 192.8 206.254 0)
			(layer "B.Fab")
			(hide yes)
			(effects
				(font
					(size 1 1)
					(thickness 0.15)
				)
				(justify mirror)
			)
		)
		(property "Public" "False"
			(at 192.8 206.254 0)
			(layer "B.Fab")
			(hide yes)
			(effects
				(font
					(size 1 1)
					(thickness 0.15)
				)
				(justify mirror)
			)
		)
		(property "Val" "47u"
			(at 192.8 206.254 0)
			(layer "B.Fab")
			(hide yes)
			(effects
				(font
					(size 1 1)
					(thickness 0.15)
				)
				(justify mirror)
			)
		)
		(property "Voltage" ""
			(at 192.8 206.254 0)
			(layer "B.Fab")
			(hide yes)
			(effects
				(font
					(size 1 1)
					(thickness 0.15)
				)
				(justify mirror)
			)
		)
		(property "DNP" ""
			(at 0 0 180)
			(unlocked yes)
			(layer "B.Fab")
			(hide yes)
			(effects
				(font
					(size 1 1)
					(thickness 0.15)
				)
				(justify mirror)
			)
		)
		(sheetname "/FPGA power supply/")
		(sheetfile "fpga-power-supply.kicad_sch")
		(attr smd)
		(fp_line
			(start -0.3 1.39)
			(end 0.3 1.39)
			(stroke
				(width 0.15)
				(type solid)
			)
			(layer "B.SilkS")
		)
		(fp_line
			(start -0.3 -1.39)
			(end 0.3 -1.39)
			(stroke
				(width 0.15)
				(type solid)
			)
			(layer "B.SilkS")
		)
		(fp_rect
			(start -2.1 1.75)
			(end 2.1 -1.75)
			(stroke
				(width 0.05)
				(type solid)
			)
			(fill no)
			(layer "B.CrtYd")
		)
		(fp_rect
			(start -1.6 1.25)
			(end 1.6 -1.25)
			(stroke
				(width 0.15)
				(type solid)
			)
			(fill no)
			(layer "B.Fab")
		)
		(pad "1" smd rect
			(at -1.145 0 180)
			(size 1.52 3.05)
			(layers "B.Cu" "B.Mask" "B.Paste")
			(net 1 "GND")
			(pintype "passive")
		)
		(pad "2" smd rect
			(at 1.145 0 180)
			(size 1.52 3.05)
			(layers "B.Cu" "B.Mask" "B.Paste")
			(net 6 "VCC1V0")
			(pintype "passive")
		)
	)
	(footprint "antmicro-footprints:C_0402_1005Metric"
		(layer "B.Cu")
		(at 64.575 136.705 90)
		(descr "Capacitor SMD 0402")
		(tags "capacitor SMD 0402")
		(property "Reference" "C37"
			(at -1.095 -0.575 90)
			(layer "B.SilkS")
			(effects
				(font
					(size 0.7 0.7)
					(thickness 0.15)
				)
				(justify right bottom mirror)
			)
		)
		(property "Value" "C_470n_0402"
			(at 0 -1.4 90)
			(layer "B.Fab")
			(effects
				(font
					(size 0.7 0.7)
					(thickness 0.15)
				)
				(justify right bottom mirror)
			)
		)
		(property "Datasheet" "https://product.tdk.com/en/search/capacitor/ceramic/mlcc/info?part_no=C1005X5R1E474M050BB"
			(at 0 0 90)
			(layer "F.Fab")
			(hide yes)
			(effects
				(font
					(size 1.27 1.27)
					(thickness 0.15)
				)
			)
		)
		(property "Description" "SMD Multilayer Ceramic Capacitor, 0.47 µF, 25 V, 0402 [1005 Metric], ± 20%, X5R, C"
			(at 0 0 90)
			(layer "F.Fab")
			(hide yes)
			(effects
				(font
					(size 1.27 1.27)
					(thickness 0.15)
				)
			)
		)
		(property "Author" "Antmicro"
			(at 201.28 72.13 0)
			(layer "B.Fab")
			(hide yes)
			(effects
				(font
					(size 1 1)
					(thickness 0.15)
				)
				(justify mirror)
			)
		)
		(property "Dielectric" ""
			(at 201.28 72.13 0)
			(layer "B.Fab")
			(hide yes)
			(effects
				(font
					(size 1 1)
					(thickness 0.15)
				)
				(justify mirror)
			)
		)
		(property "License" "Apache-2.0"
			(at 201.28 72.13 0)
			(layer "B.Fab")
			(hide yes)
			(effects
				(font
					(size 1 1)
					(thickness 0.15)
				)
				(justify mirror)
			)
		)
		(property "MPN" "C1005X5R1E474M050BB"
			(at 201.28 72.13 0)
			(layer "B.Fab")
			(hide yes)
			(effects
				(font
					(size 1 1)
					(thickness 0.15)
				)
				(justify mirror)
			)
		)
		(property "Manufacturer" "TDK"
			(at 201.28 72.13 0)
			(layer "B.Fab")
			(hide yes)
			(effects
				(font
					(size 1 1)
					(thickness 0.15)
				)
				(justify mirror)
			)
		)
		(property "Val" "470n"
			(at 201.28 72.13 0)
			(layer "B.Fab")
			(hide yes)
			(effects
				(font
					(size 1 1)
					(thickness 0.15)
				)
				(justify mirror)
			)
		)
		(property "Voltage" ""
			(at 201.28 72.13 0)
			(layer "B.Fab")
			(hide yes)
			(effects
				(font
					(size 1 1)
					(thickness 0.15)
				)
				(justify mirror)
			)
		)
		(sheetname "/RoT/")
		(sheetfile "rot.kicad_sch")
		(attr smd)
		(fp_rect
			(start -0.925 0.47)
			(end 0.925 -0.47)
			(stroke
				(width 0.05)
				(type default)
			)
			(fill no)
			(layer "B.CrtYd")
		)
		(fp_line
			(start 0.504 -0.248)
			(end -0.494 -0.248)
			(stroke
				(width 0.15)
				(type solid)
			)
			(layer "B.Fab")
		)
		(fp_line
			(start -0.494 -0.248)
			(end -0.494 0.25)
			(stroke
				(width 0.15)
				(type solid)
			)
			(layer "B.Fab")
		)
		(fp_line
			(start 0.504 0.25)
			(end 0.504 -0.248)
			(stroke
				(width 0.15)
				(type solid)
			)
			(layer "B.Fab")
		)
		(fp_line
			(start -0.494 0.25)
			(end 0.504 0.25)
			(stroke
				(width 0.15)
				(type solid)
			)
			(layer "B.Fab")
		)
		(pad "1" smd roundrect
			(at -0.48 0 90)
			(size 0.59 0.64)
			(layers "B.Cu" "B.Mask" "B.Paste")
			(roundrect_rratio 0.25)
			(net 1 "GND")
			(pintype "passive")
		)
		(pad "2" smd roundrect
			(at 0.48 0 90)
			(size 0.59 0.64)
			(layers "B.Cu" "B.Mask" "B.Paste")
			(roundrect_rratio 0.25)
			(net 2 "VCC3V3")
			(pintype "passive")
		)
	)
	(footprint "antmicro-footprints:C_0603_1608Metric"
		(layer "B.Cu")
		(at 118.6 126.4 -90)
		(descr "Capacitor SMD 0603")
		(tags "capacitor 0603")
		(property "Reference" "C45"
			(at -1.1 0.6 90)
			(layer "B.SilkS")
			(effects
				(font
					(size 0.7 0.7)
					(thickness 0.15)
				)
				(justify left bottom mirror)
			)
		)
		(property "Value" "C_4u7_0603"
			(at 0 -1.6 90)
			(layer "B.Fab")
			(effects
				(font
					(size 0.7 0.7)
					(thickness 0.15)
				)
				(justify left bottom mirror)
			)
		)
		(property "Datasheet" "https://product.tdk.com/en/search/capacitor/ceramic/mlcc/info?part_no=C1608X5R1V475M080AC"
			(at 0 0 270)
			(layer "F.Fab")
			(hide yes)
			(effects
				(font
					(size 1.27 1.27)
					(thickness 0.15)
				)
			)
		)
		(property "Description" "SMD Multilayer Ceramic Capacitor, 4.7 µF, 35 V, 0603 [1608 Metric], ± 20%, X5R, C"
			(at 0 0 270)
			(layer "F.Fab")
			(hide yes)
			(effects
				(font
					(size 1.27 1.27)
					(thickness 0.15)
				)
			)
		)
		(property "Author" "Antmicro"
			(at -7.8 245 0)
			(layer "B.Fab")
			(hide yes)
			(effects
				(font
					(size 1 1)
					(thickness 0.15)
				)
				(justify mirror)
			)
		)
		(property "Dielectric" ""
			(at -7.8 245 0)
			(layer "B.Fab")
			(hide yes)
			(effects
				(font
					(size 1 1)
					(thickness 0.15)
				)
				(justify mirror)
			)
		)
		(property "License" "Apache-2.0"
			(at -7.8 245 0)
			(layer "B.Fab")
			(hide yes)
			(effects
				(font
					(size 1 1)
					(thickness 0.15)
				)
				(justify mirror)
			)
		)
		(property "MPN" "C1608X5R1V475M080AC"
			(at -7.8 245 0)
			(layer "B.Fab")
			(hide yes)
			(effects
				(font
					(size 1 1)
					(thickness 0.15)
				)
				(justify mirror)
			)
		)
		(property "Manufacturer" "TDK"
			(at -7.8 245 0)
			(layer "B.Fab")
			(hide yes)
			(effects
				(font
					(size 1 1)
					(thickness 0.15)
				)
				(justify mirror)
			)
		)
		(property "Val" "4u7"
			(at -7.8 245 0)
			(layer "B.Fab")
			(hide yes)
			(effects
				(font
					(size 1 1)
					(thickness 0.15)
				)
				(justify mirror)
			)
		)
		(property "Voltage" ""
			(at -7.8 245 0)
			(layer "B.Fab")
			(hide yes)
			(effects
				(font
					(size 1 1)
					(thickness 0.15)
				)
				(justify mirror)
			)
		)
		(sheetname "/Interfaces/")
		(sheetfile "interfaces.kicad_sch")
		(attr smd)
		(fp_line
			(start -0.15 0.4)
			(end 0.15 0.4)
			(stroke
				(width 0.15)
				(type solid)
			)
			(layer "B.SilkS")
		)
		(fp_line
			(start -0.15 -0.4)
			(end 0.15 -0.4)
			(stroke
				(width 0.15)
				(type solid)
			)
			(layer "B.SilkS")
		)
		(fp_rect
			(start -1.25 0.65)
			(end 1.25 -0.65)
			(stroke
				(width 0.05)
				(type solid)
			)
			(fill no)
			(layer "B.CrtYd")
		)
		(fp_rect
			(start -0.8 0.4)
			(end 0.8 -0.4)
			(stroke
				(width 0.15)
				(type solid)
			)
			(fill no)
			(layer "B.Fab")
		)
		(pad "1" smd roundrect
			(at -0.7 0 270)
			(size 0.8 1)
			(layers "B.Cu" "B.Mask" "B.Paste")
			(roundrect_rratio 0.2)
			(net 1 "GND")
			(pintype "passive")
		)
		(pad "2" smd roundrect
			(at 0.7 0 270)
			(size 0.8 1)
			(layers "B.Cu" "B.Mask" "B.Paste")
			(roundrect_rratio 0.2)
			(net 339 "VCC1V2")
			(pintype "passive")
		)
	)
	(footprint "antmicro-footprints:R_0402_1005Metric"
		(layer "B.Cu")
		(at 107.719 92.077 180)
		(descr "Resistor SMD 0402")
		(tags "resistor SMD 0402")
		(property "Reference" "R159"
			(at -5.881 2.277 0)
			(layer "B.SilkS")
			(effects
				(font
					(size 0.7 0.7)
					(thickness 0.15)
				)
				(justify left bottom mirror)
			)
		)
		(property "Value" "R_12k1_0402"
			(at 0 -1.4 0)
			(layer "B.Fab")
			(effects
				(font
					(size 0.7 0.7)
					(thickness 0.15)
				)
				(justify left bottom mirror)
			)
		)
		(property "Datasheet" "https://www.bourns.com/docs/product-datasheets/cr.pdf"
			(at 0 0 180)
			(layer "F.Fab")
			(hide yes)
			(effects
				(font
					(size 1.27 1.27)
					(thickness 0.15)
				)
			)
		)
		(property "Description" "SMD Chip Resistor, 12.1 kohm, ± 1%, 62.5 mW, 0402 [1005 Metric], Thick Film, General Purpose"
			(at 0 0 180)
			(layer "F.Fab")
			(hide yes)
			(effects
				(font
					(size 1.27 1.27)
					(thickness 0.15)
				)
			)
		)
		(property "Author" "Antmicro"
			(at 215.438 184.154 0)
			(layer "B.Fab")
			(hide yes)
			(effects
				(font
					(size 1 1)
					(thickness 0.15)
				)
				(justify mirror)
			)
		)
		(property "License" "Apache-2.0"
			(at 215.438 184.154 0)
			(layer "B.Fab")
			(hide yes)
			(effects
				(font
					(size 1 1)
					(thickness 0.15)
				)
				(justify mirror)
			)
		)
		(property "MPN" "CR0402-FX-1212GLF"
			(at 215.438 184.154 0)
			(layer "B.Fab")
			(hide yes)
			(effects
				(font
					(size 1 1)
					(thickness 0.15)
				)
				(justify mirror)
			)
		)
		(property "Manufacturer" "Bourns"
			(at 215.438 184.154 0)
			(layer "B.Fab")
			(hide yes)
			(effects
				(font
					(size 1 1)
					(thickness 0.15)
				)
				(justify mirror)
			)
		)
		(property "Tolerance" "1%"
			(at 215.438 184.154 0)
			(layer "B.Fab")
			(hide yes)
			(effects
				(font
					(size 1 1)
					(thickness 0.15)
				)
				(justify mirror)
			)
		)
		(property "Val" "12k1"
			(at 215.438 184.154 0)
			(layer "B.Fab")
			(hide yes)
			(effects
				(font
					(size 1 1)
					(thickness 0.15)
				)
				(justify mirror)
			)
		)
		(sheetname "/Ethernet/")
		(sheetfile "ethernet.kicad_sch")
		(attr smd)
		(fp_rect
			(start -0.925 0.47)
			(end 0.925 -0.47)
			(stroke
				(width 0.05)
				(type default)
			)
			(fill no)
			(layer "B.CrtYd")
		)
		(fp_rect
			(start -0.5 0.25)
			(end 0.5 -0.25)
			(stroke
				(width 0.15)
				(type solid)
			)
			(fill no)
			(layer "B.Fab")
		)
		(pad "1" smd roundrect
			(at -0.48 0 180)
			(size 0.59 0.64)
			(layers "B.Cu" "B.Mask" "B.Paste")
			(roundrect_rratio 0.25)
			(net 1 "GND")
			(pintype "passive")
		)
		(pad "2" smd roundrect
			(at 0.48 0 180)
			(size 0.59 0.64)
			(layers "B.Cu" "B.Mask" "B.Paste")
			(roundrect_rratio 0.25)
			(net 345 "Net-(U20-ISET)")
			(pintype "passive")
		)
	)
	(footprint "antmicro-footprints:C_0402_1005Metric"
		(layer "B.Cu")
		(at 140.274 130.314 180)
		(descr "Capacitor SMD 0402")
		(tags "capacitor SMD 0402")
		(property "Reference" "C188"
			(at -3.626 -0.386 0)
			(layer "B.SilkS")
			(effects
				(font
					(size 0.7 0.7)
					(thickness 0.15)
				)
				(justify left bottom mirror)
			)
		)
		(property "Value" "C_4u7_0402"
			(at 0 -1.4 0)
			(layer "B.Fab")
			(effects
				(font
					(size 0.7 0.7)
					(thickness 0.15)
				)
				(justify left bottom mirror)
			)
		)
		(property "Datasheet" "https://www.murata.com/products/productdetail?partno=GRM155R61A475MEAA%23"
			(at 0 0 180)
			(layer "F.Fab")
			(hide yes)
			(effects
				(font
					(size 1.27 1.27)
					(thickness 0.15)
				)
			)
		)
		(property "Description" "SMD Multilayer Ceramic Capacitor, 4.7 µF, 10 V, 0402 [1005 Metric], ± 20%, X5R, GRM Series"
			(at 0 0 180)
			(layer "F.Fab")
			(hide yes)
			(effects
				(font
					(size 1.27 1.27)
					(thickness 0.15)
				)
			)
		)
		(property "Author" "Antmicro"
			(at 280.548 260.628 0)
			(layer "B.Fab")
			(hide yes)
			(effects
				(font
					(size 1 1)
					(thickness 0.15)
				)
				(justify mirror)
			)
		)
		(property "Dielectric" ""
			(at 280.548 260.628 0)
			(layer "B.Fab")
			(hide yes)
			(effects
				(font
					(size 1 1)
					(thickness 0.15)
				)
				(justify mirror)
			)
		)
		(property "License" "Apache-2.0"
			(at 280.548 260.628 0)
			(layer "B.Fab")
			(hide yes)
			(effects
				(font
					(size 1 1)
					(thickness 0.15)
				)
				(justify mirror)
			)
		)
		(property "MPN" "GRM155R61A475MEAAD"
			(at 280.548 260.628 0)
			(layer "B.Fab")
			(hide yes)
			(effects
				(font
					(size 1 1)
					(thickness 0.15)
				)
				(justify mirror)
			)
		)
		(property "Manufacturer" "Murata"
			(at 280.548 260.628 0)
			(layer "B.Fab")
			(hide yes)
			(effects
				(font
					(size 1 1)
					(thickness 0.15)
				)
				(justify mirror)
			)
		)
		(property "Val" "4u7"
			(at 280.548 260.628 0)
			(layer "B.Fab")
			(hide yes)
			(effects
				(font
					(size 1 1)
					(thickness 0.15)
				)
				(justify mirror)
			)
		)
		(property "Voltage" ""
			(at 280.548 260.628 0)
			(layer "B.Fab")
			(hide yes)
			(effects
				(font
					(size 1 1)
					(thickness 0.15)
				)
				(justify mirror)
			)
		)
		(sheetname "/Interfaces/")
		(sheetfile "interfaces.kicad_sch")
		(attr smd)
		(fp_rect
			(start -0.925 0.47)
			(end 0.925 -0.47)
			(stroke
				(width 0.05)
				(type default)
			)
			(fill no)
			(layer "B.CrtYd")
		)
		(fp_line
			(start 0.504 0.25)
			(end 0.504 -0.248)
			(stroke
				(width 0.15)
				(type solid)
			)
			(layer "B.Fab")
		)
		(fp_line
			(start 0.504 -0.248)
			(end -0.494 -0.248)
			(stroke
				(width 0.15)
				(type solid)
			)
			(layer "B.Fab")
		)
		(fp_line
			(start -0.494 0.25)
			(end 0.504 0.25)
			(stroke
				(width 0.15)
				(type solid)
			)
			(layer "B.Fab")
		)
		(fp_line
			(start -0.494 -0.248)
			(end -0.494 0.25)
			(stroke
				(width 0.15)
				(type solid)
			)
			(layer "B.Fab")
		)
		(pad "1" smd roundrect
			(at -0.48 0 180)
			(size 0.59 0.64)
			(layers "B.Cu" "B.Mask" "B.Paste")
			(roundrect_rratio 0.25)
			(net 1 "GND")
			(pintype "passive")
		)
		(pad "2" smd roundrect
			(at 0.48 0 180)
			(size 0.59 0.64)
			(layers "B.Cu" "B.Mask" "B.Paste")
			(roundrect_rratio 0.25)
			(net 200 "Net-(U1-VDDIM)")
			(pintype "passive")
		)
	)
	(footprint "antmicro-footprints:R_0402_1005Metric"
		(layer "B.Cu")
		(at 138.774 122.004)
		(descr "Resistor SMD 0402")
		(tags "resistor SMD 0402")
		(property "Reference" "R117"
			(at -3.574 0.296 0)
			(layer "B.SilkS")
			(effects
				(font
					(size 0.7 0.7)
					(thickness 0.15)
				)
				(justify right bottom mirror)
			)
		)
		(property "Value" "R_47k_0402"
			(at 0 -1.4 0)
			(layer "B.Fab")
			(effects
				(font
					(size 0.7 0.7)
					(thickness 0.15)
				)
				(justify right bottom mirror)
			)
		)
		(property "Datasheet" "https://www.bourns.com/docs/product-datasheets/cr.pdf"
			(at 0 0 0)
			(layer "F.Fab")
			(hide yes)
			(effects
				(font
					(size 1.27 1.27)
					(thickness 0.15)
				)
			)
		)
		(property "Description" "SMD Chip Resistor, 47 kohm, ± 1%, 62.5 mW, 0402 [1005 Metric], Thick Film, General Purpose"
			(at 0 0 0)
			(layer "F.Fab")
			(hide yes)
			(effects
				(font
					(size 1.27 1.27)
					(thickness 0.15)
				)
			)
		)
		(property "Author" "Antmicro"
			(at 0 0 0)
			(layer "B.Fab")
			(hide yes)
			(effects
				(font
					(size 1 1)
					(thickness 0.15)
				)
				(justify mirror)
			)
		)
		(property "License" "Apache-2.0"
			(at 0 0 0)
			(layer "B.Fab")
			(hide yes)
			(effects
				(font
					(size 1 1)
					(thickness 0.15)
				)
				(justify mirror)
			)
		)
		(property "MPN" "CR0402-FX-4702GLF"
			(at 0 0 0)
			(layer "B.Fab")
			(hide yes)
			(effects
				(font
					(size 1 1)
					(thickness 0.15)
				)
				(justify mirror)
			)
		)
		(property "Manufacturer" "Bourns"
			(at 0 0 0)
			(layer "B.Fab")
			(hide yes)
			(effects
				(font
					(size 1 1)
					(thickness 0.15)
				)
				(justify mirror)
			)
		)
		(property "Tolerance" "1%"
			(at 0 0 0)
			(layer "B.Fab")
			(hide yes)
			(effects
				(font
					(size 1 1)
					(thickness 0.15)
				)
				(justify mirror)
			)
		)
		(property "Val" "47k"
			(at 0 0 0)
			(layer "B.Fab")
			(hide yes)
			(effects
				(font
					(size 1 1)
					(thickness 0.15)
				)
				(justify mirror)
			)
		)
		(sheetname "/Interfaces/")
		(sheetfile "interfaces.kicad_sch")
		(attr smd)
		(fp_rect
			(start -0.925 0.47)
			(end 0.925 -0.47)
			(stroke
				(width 0.05)
				(type default)
			)
			(fill no)
			(layer "B.CrtYd")
		)
		(fp_rect
			(start -0.5 0.25)
			(end 0.5 -0.25)
			(stroke
				(width 0.15)
				(type solid)
			)
			(fill no)
			(layer "B.Fab")
		)
		(pad "1" smd roundrect
			(at -0.48 0)
			(size 0.59 0.64)
			(layers "B.Cu" "B.Mask" "B.Paste")
			(roundrect_rratio 0.25)
			(net 2 "VCC3V3")
			(pintype "passive")
		)
		(pad "2" smd roundrect
			(at 0.48 0)
			(size 0.59 0.64)
			(layers "B.Cu" "B.Mask" "B.Paste")
			(roundrect_rratio 0.25)
			(net 331 "MMC_RSTN")
			(pintype "passive")
		)
	)
	(footprint "antmicro-footprints:R_0402_1005Metric"
		(layer "B.Cu")
		(at 139.764 120.004 180)
		(descr "Resistor SMD 0402")
		(tags "resistor SMD 0402")
		(property "Reference" "R118"
			(at -1.736 0.604 0)
			(layer "B.SilkS")
			(effects
				(font
					(size 0.7 0.7)
					(thickness 0.15)
				)
				(justify left bottom mirror)
			)
		)
		(property "Value" "R_47k_0402"
			(at 0 -1.4 0)
			(layer "B.Fab")
			(effects
				(font
					(size 0.7 0.7)
					(thickness 0.15)
				)
				(justify left bottom mirror)
			)
		)
		(property "Datasheet" "https://www.bourns.com/docs/product-datasheets/cr.pdf"
			(at 0 0 180)
			(layer "F.Fab")
			(hide yes)
			(effects
				(font
					(size 1.27 1.27)
					(thickness 0.15)
				)
			)
		)
		(property "Description" "SMD Chip Resistor, 47 kohm, ± 1%, 62.5 mW, 0402 [1005 Metric], Thick Film, General Purpose"
			(at 0 0 180)
			(layer "F.Fab")
			(hide yes)
			(effects
				(font
					(size 1.27 1.27)
					(thickness 0.15)
				)
			)
		)
		(property "Author" "Antmicro"
			(at 279.528 240.008 0)
			(layer "B.Fab")
			(hide yes)
			(effects
				(font
					(size 1 1)
					(thickness 0.15)
				)
				(justify mirror)
			)
		)
		(property "License" "Apache-2.0"
			(at 279.528 240.008 0)
			(layer "B.Fab")
			(hide yes)
			(effects
				(font
					(size 1 1)
					(thickness 0.15)
				)
				(justify mirror)
			)
		)
		(property "MPN" "CR0402-FX-4702GLF"
			(at 279.528 240.008 0)
			(layer "B.Fab")
			(hide yes)
			(effects
				(font
					(size 1 1)
					(thickness 0.15)
				)
				(justify mirror)
			)
		)
		(property "Manufacturer" "Bourns"
			(at 279.528 240.008 0)
			(layer "B.Fab")
			(hide yes)
			(effects
				(font
					(size 1 1)
					(thickness 0.15)
				)
				(justify mirror)
			)
		)
		(property "Tolerance" "1%"
			(at 279.528 240.008 0)
			(layer "B.Fab")
			(hide yes)
			(effects
				(font
					(size 1 1)
					(thickness 0.15)
				)
				(justify mirror)
			)
		)
		(property "Val" "47k"
			(at 279.528 240.008 0)
			(layer "B.Fab")
			(hide yes)
			(effects
				(font
					(size 1 1)
					(thickness 0.15)
				)
				(justify mirror)
			)
		)
		(sheetname "/Interfaces/")
		(sheetfile "interfaces.kicad_sch")
		(attr smd)
		(fp_rect
			(start -0.925 0.47)
			(end 0.925 -0.47)
			(stroke
				(width 0.05)
				(type default)
			)
			(fill no)
			(layer "B.CrtYd")
		)
		(fp_rect
			(start -0.5 0.25)
			(end 0.5 -0.25)
			(stroke
				(width 0.15)
				(type solid)
			)
			(fill no)
			(layer "B.Fab")
		)
		(pad "1" smd roundrect
			(at -0.48 0 180)
			(size 0.59 0.64)
			(layers "B.Cu" "B.Mask" "B.Paste")
			(roundrect_rratio 0.25)
			(net 2 "VCC3V3")
			(pintype "passive")
		)
		(pad "2" smd roundrect
			(at 0.48 0 180)
			(size 0.59 0.64)
			(layers "B.Cu" "B.Mask" "B.Paste")
			(roundrect_rratio 0.25)
			(net 329 "MMC_CMD")
			(pintype "passive")
		)
	)
	(footprint "antmicro-footprints:R_0402_1005Metric"
		(layer "B.Cu")
		(at 142.274 124.214 180)
		(descr "Resistor SMD 0402")
		(tags "resistor SMD 0402")
		(property "Reference" "R119"
			(at -3.626 -0.386 0)
			(layer "B.SilkS")
			(effects
				(font
					(size 0.7 0.7)
					(thickness 0.15)
				)
				(justify left bottom mirror)
			)
		)
		(property "Value" "R_47k_0402"
			(at 0 -1.4 0)
			(layer "B.Fab")
			(effects
				(font
					(size 0.7 0.7)
					(thickness 0.15)
				)
				(justify left bottom mirror)
			)
		)
		(property "Datasheet" "https://www.bourns.com/docs/product-datasheets/cr.pdf"
			(at 0 0 180)
			(layer "F.Fab")
			(hide yes)
			(effects
				(font
					(size 1.27 1.27)
					(thickness 0.15)
				)
			)
		)
		(property "Description" "SMD Chip Resistor, 47 kohm, ± 1%, 62.5 mW, 0402 [1005 Metric], Thick Film, General Purpose"
			(at 0 0 180)
			(layer "F.Fab")
			(hide yes)
			(effects
				(font
					(size 1.27 1.27)
					(thickness 0.15)
				)
			)
		)
		(property "Author" "Antmicro"
			(at 284.548 248.428 0)
			(layer "B.Fab")
			(hide yes)
			(effects
				(font
					(size 1 1)
					(thickness 0.15)
				)
				(justify mirror)
			)
		)
		(property "License" "Apache-2.0"
			(at 284.548 248.428 0)
			(layer "B.Fab")
			(hide yes)
			(effects
				(font
					(size 1 1)
					(thickness 0.15)
				)
				(justify mirror)
			)
		)
		(property "MPN" "CR0402-FX-4702GLF"
			(at 284.548 248.428 0)
			(layer "B.Fab")
			(hide yes)
			(effects
				(font
					(size 1 1)
					(thickness 0.15)
				)
				(justify mirror)
			)
		)
		(property "Manufacturer" "Bourns"
			(at 284.548 248.428 0)
			(layer "B.Fab")
			(hide yes)
			(effects
				(font
					(size 1 1)
					(thickness 0.15)
				)
				(justify mirror)
			)
		)
		(property "Tolerance" "1%"
			(at 284.548 248.428 0)
			(layer "B.Fab")
			(hide yes)
			(effects
				(font
					(size 1 1)
					(thickness 0.15)
				)
				(justify mirror)
			)
		)
		(property "Val" "47k"
			(at 284.548 248.428 0)
			(layer "B.Fab")
			(hide yes)
			(effects
				(font
					(size 1 1)
					(thickness 0.15)
				)
				(justify mirror)
			)
		)
		(sheetname "/Interfaces/")
		(sheetfile "interfaces.kicad_sch")
		(attr smd)
		(fp_rect
			(start -0.925 0.47)
			(end 0.925 -0.47)
			(stroke
				(width 0.05)
				(type default)
			)
			(fill no)
			(layer "B.CrtYd")
		)
		(fp_rect
			(start -0.5 0.25)
			(end 0.5 -0.25)
			(stroke
				(width 0.15)
				(type solid)
			)
			(fill no)
			(layer "B.Fab")
		)
		(pad "1" smd roundrect
			(at -0.48 0 180)
			(size 0.59 0.64)
			(layers "B.Cu" "B.Mask" "B.Paste")
			(roundrect_rratio 0.25)
			(net 2 "VCC3V3")
			(pintype "passive")
		)
		(pad "2" smd roundrect
			(at 0.48 0 180)
			(size 0.59 0.64)
			(layers "B.Cu" "B.Mask" "B.Paste")
			(roundrect_rratio 0.25)
			(net 321 "MMC_DAT0")
			(pintype "passive")
		)
	)
	(footprint "antmicro-footprints:R_0402_1005Metric"
		(layer "B.Cu")
		(at 143.069 120.927 180)
		(descr "Resistor SMD 0402")
		(tags "resistor SMD 0402")
		(property "Reference" "R120"
			(at -3.731 -0.373 0)
			(layer "B.SilkS")
			(effects
				(font
					(size 0.7 0.7)
					(thickness 0.15)
				)
				(justify left bottom mirror)
			)
		)
		(property "Value" "R_47k_0402"
			(at 0 -1.4 0)
			(layer "B.Fab")
			(effects
				(font
					(size 0.7 0.7)
					(thickness 0.15)
				)
				(justify left bottom mirror)
			)
		)
		(property "Datasheet" "https://www.bourns.com/docs/product-datasheets/cr.pdf"
			(at 0 0 180)
			(layer "F.Fab")
			(hide yes)
			(effects
				(font
					(size 1.27 1.27)
					(thickness 0.15)
				)
			)
		)
		(property "Description" "SMD Chip Resistor, 47 kohm, ± 1%, 62.5 mW, 0402 [1005 Metric], Thick Film, General Purpose"
			(at 0 0 180)
			(layer "F.Fab")
			(hide yes)
			(effects
				(font
					(size 1.27 1.27)
					(thickness 0.15)
				)
			)
		)
		(property "Author" "Antmicro"
			(at 286.138 241.854 0)
			(layer "B.Fab")
			(hide yes)
			(effects
				(font
					(size 1 1)
					(thickness 0.15)
				)
				(justify mirror)
			)
		)
		(property "License" "Apache-2.0"
			(at 286.138 241.854 0)
			(layer "B.Fab")
			(hide yes)
			(effects
				(font
					(size 1 1)
					(thickness 0.15)
				)
				(justify mirror)
			)
		)
		(property "MPN" "CR0402-FX-4702GLF"
			(at 286.138 241.854 0)
			(layer "B.Fab")
			(hide yes)
			(effects
				(font
					(size 1 1)
					(thickness 0.15)
				)
				(justify mirror)
			)
		)
		(property "Manufacturer" "Bourns"
			(at 286.138 241.854 0)
			(layer "B.Fab")
			(hide yes)
			(effects
				(font
					(size 1 1)
					(thickness 0.15)
				)
				(justify mirror)
			)
		)
		(property "Tolerance" "1%"
			(at 286.138 241.854 0)
			(layer "B.Fab")
			(hide yes)
			(effects
				(font
					(size 1 1)
					(thickness 0.15)
				)
				(justify mirror)
			)
		)
		(property "Val" "47k"
			(at 286.138 241.854 0)
			(layer "B.Fab")
			(hide yes)
			(effects
				(font
					(size 1 1)
					(thickness 0.15)
				)
				(justify mirror)
			)
		)
		(sheetname "/Interfaces/")
		(sheetfile "interfaces.kicad_sch")
		(attr smd)
		(fp_rect
			(start -0.925 0.47)
			(end 0.925 -0.47)
			(stroke
				(width 0.05)
				(type default)
			)
			(fill no)
			(layer "B.CrtYd")
		)
		(fp_rect
			(start -0.5 0.25)
			(end 0.5 -0.25)
			(stroke
				(width 0.15)
				(type solid)
			)
			(fill no)
			(layer "B.Fab")
		)
		(pad "1" smd roundrect
			(at -0.48 0 180)
			(size 0.59 0.64)
			(layers "B.Cu" "B.Mask" "B.Paste")
			(roundrect_rratio 0.25)
			(net 2 "VCC3V3")
			(pintype "passive")
		)
		(pad "2" smd roundrect
			(at 0.48 0 180)
			(size 0.59 0.64)
			(layers "B.Cu" "B.Mask" "B.Paste")
			(roundrect_rratio 0.25)
			(net 322 "MMC_DAT1")
			(pintype "passive")
		)
	)
	(footprint "antmicro-footprints:R_0402_1005Metric"
		(layer "B.Cu")
		(at 140.274 124.214)
		(descr "Resistor SMD 0402")
		(tags "resistor SMD 0402")
		(property "Reference" "R121"
			(at -0.674 -0.614 0)
			(layer "B.SilkS")
			(effects
				(font
					(size 0.7 0.7)
					(thickness 0.15)
				)
				(justify right bottom mirror)
			)
		)
		(property "Value" "R_47k_0402"
			(at 0 -1.4 0)
			(layer "B.Fab")
			(effects
				(font
					(size 0.7 0.7)
					(thickness 0.15)
				)
				(justify right bottom mirror)
			)
		)
		(property "Datasheet" "https://www.bourns.com/docs/product-datasheets/cr.pdf"
			(at 0 0 0)
			(layer "F.Fab")
			(hide yes)
			(effects
				(font
					(size 1.27 1.27)
					(thickness 0.15)
				)
			)
		)
		(property "Description" "SMD Chip Resistor, 47 kohm, ± 1%, 62.5 mW, 0402 [1005 Metric], Thick Film, General Purpose"
			(at 0 0 0)
			(layer "F.Fab")
			(hide yes)
			(effects
				(font
					(size 1.27 1.27)
					(thickness 0.15)
				)
			)
		)
		(property "Author" "Antmicro"
			(at 0 0 0)
			(layer "B.Fab")
			(hide yes)
			(effects
				(font
					(size 1 1)
					(thickness 0.15)
				)
				(justify mirror)
			)
		)
		(property "License" "Apache-2.0"
			(at 0 0 0)
			(layer "B.Fab")
			(hide yes)
			(effects
				(font
					(size 1 1)
					(thickness 0.15)
				)
				(justify mirror)
			)
		)
		(property "MPN" "CR0402-FX-4702GLF"
			(at 0 0 0)
			(layer "B.Fab")
			(hide yes)
			(effects
				(font
					(size 1 1)
					(thickness 0.15)
				)
				(justify mirror)
			)
		)
		(property "Manufacturer" "Bourns"
			(at 0 0 0)
			(layer "B.Fab")
			(hide yes)
			(effects
				(font
					(size 1 1)
					(thickness 0.15)
				)
				(justify mirror)
			)
		)
		(property "Tolerance" "1%"
			(at 0 0 0)
			(layer "B.Fab")
			(hide yes)
			(effects
				(font
					(size 1 1)
					(thickness 0.15)
				)
				(justify mirror)
			)
		)
		(property "Val" "47k"
			(at 0 0 0)
			(layer "B.Fab")
			(hide yes)
			(effects
				(font
					(size 1 1)
					(thickness 0.15)
				)
				(justify mirror)
			)
		)
		(sheetname "/Interfaces/")
		(sheetfile "interfaces.kicad_sch")
		(attr smd)
		(fp_rect
			(start -0.925 0.47)
			(end 0.925 -0.47)
			(stroke
				(width 0.05)
				(type default)
			)
			(fill no)
			(layer "B.CrtYd")
		)
		(fp_rect
			(start -0.5 0.25)
			(end 0.5 -0.25)
			(stroke
				(width 0.15)
				(type solid)
			)
			(fill no)
			(layer "B.Fab")
		)
		(pad "1" smd roundrect
			(at -0.48 0)
			(size 0.59 0.64)
			(layers "B.Cu" "B.Mask" "B.Paste")
			(roundrect_rratio 0.25)
			(net 2 "VCC3V3")
			(pintype "passive")
		)
		(pad "2" smd roundrect
			(at 0.48 0)
			(size 0.59 0.64)
			(layers "B.Cu" "B.Mask" "B.Paste")
			(roundrect_rratio 0.25)
			(net 323 "MMC_DAT2")
			(pintype "passive")
		)
	)
	(footprint "antmicro-footprints:R_0402_1005Metric"
		(layer "B.Cu")
		(at 140.919 121.027)
		(descr "Resistor SMD 0402")
		(tags "resistor SMD 0402")
		(property "Reference" "R122"
			(at -0.019 -0.627 0)
			(layer "B.SilkS")
			(effects
				(font
					(size 0.7 0.7)
					(thickness 0.15)
				)
				(justify right bottom mirror)
			)
		)
		(property "Value" "R_47k_0402"
			(at 0 -1.4 0)
			(layer "B.Fab")
			(effects
				(font
					(size 0.7 0.7)
					(thickness 0.15)
				)
				(justify right bottom mirror)
			)
		)
		(property "Datasheet" "https://www.bourns.com/docs/product-datasheets/cr.pdf"
			(at 0 0 0)
			(layer "F.Fab")
			(hide yes)
			(effects
				(font
					(size 1.27 1.27)
					(thickness 0.15)
				)
			)
		)
		(property "Description" "SMD Chip Resistor, 47 kohm, ± 1%, 62.5 mW, 0402 [1005 Metric], Thick Film, General Purpose"
			(at 0 0 0)
			(layer "F.Fab")
			(hide yes)
			(effects
				(font
					(size 1.27 1.27)
					(thickness 0.15)
				)
			)
		)
		(property "Author" "Antmicro"
			(at 0 0 0)
			(layer "B.Fab")
			(hide yes)
			(effects
				(font
					(size 1 1)
					(thickness 0.15)
				)
				(justify mirror)
			)
		)
		(property "License" "Apache-2.0"
			(at 0 0 0)
			(layer "B.Fab")
			(hide yes)
			(effects
				(font
					(size 1 1)
					(thickness 0.15)
				)
				(justify mirror)
			)
		)
		(property "MPN" "CR0402-FX-4702GLF"
			(at 0 0 0)
			(layer "B.Fab")
			(hide yes)
			(effects
				(font
					(size 1 1)
					(thickness 0.15)
				)
				(justify mirror)
			)
		)
		(property "Manufacturer" "Bourns"
			(at 0 0 0)
			(layer "B.Fab")
			(hide yes)
			(effects
				(font
					(size 1 1)
					(thickness 0.15)
				)
				(justify mirror)
			)
		)
		(property "Tolerance" "1%"
			(at 0 0 0)
			(layer "B.Fab")
			(hide yes)
			(effects
				(font
					(size 1 1)
					(thickness 0.15)
				)
				(justify mirror)
			)
		)
		(property "Val" "47k"
			(at 0 0 0)
			(layer "B.Fab")
			(hide yes)
			(effects
				(font
					(size 1 1)
					(thickness 0.15)
				)
				(justify mirror)
			)
		)
		(sheetname "/Interfaces/")
		(sheetfile "interfaces.kicad_sch")
		(attr smd)
		(fp_rect
			(start -0.925 0.47)
			(end 0.925 -0.47)
			(stroke
				(width 0.05)
				(type default)
			)
			(fill no)
			(layer "B.CrtYd")
		)
		(fp_rect
			(start -0.5 0.25)
			(end 0.5 -0.25)
			(stroke
				(width 0.15)
				(type solid)
			)
			(fill no)
			(layer "B.Fab")
		)
		(pad "1" smd roundrect
			(at -0.48 0)
			(size 0.59 0.64)
			(layers "B.Cu" "B.Mask" "B.Paste")
			(roundrect_rratio 0.25)
			(net 2 "VCC3V3")
			(pintype "passive")
		)
		(pad "2" smd roundrect
			(at 0.48 0)
			(size 0.59 0.64)
			(layers "B.Cu" "B.Mask" "B.Paste")
			(roundrect_rratio 0.25)
			(net 324 "MMC_DAT3")
			(pintype "passive")
		)
	)
	(footprint "antmicro-footprints:R_0402_1005Metric"
		(layer "B.Cu")
		(at 136.774 121.024 180)
		(descr "Resistor SMD 0402")
		(tags "resistor SMD 0402")
		(property "Reference" "R123"
			(at -1.126 0.524 0)
			(layer "B.SilkS")
			(effects
				(font
					(size 0.7 0.7)
					(thickness 0.15)
				)
				(justify left bottom mirror)
			)
		)
		(property "Value" "R_47k_0402"
			(at 0 -1.4 0)
			(layer "B.Fab")
			(effects
				(font
					(size 0.7 0.7)
					(thickness 0.15)
				)
				(justify left bottom mirror)
			)
		)
		(property "Datasheet" "https://www.bourns.com/docs/product-datasheets/cr.pdf"
			(at 0 0 180)
			(layer "F.Fab")
			(hide yes)
			(effects
				(font
					(size 1.27 1.27)
					(thickness 0.15)
				)
			)
		)
		(property "Description" "SMD Chip Resistor, 47 kohm, ± 1%, 62.5 mW, 0402 [1005 Metric], Thick Film, General Purpose"
			(at 0 0 180)
			(layer "F.Fab")
			(hide yes)
			(effects
				(font
					(size 1.27 1.27)
					(thickness 0.15)
				)
			)
		)
		(property "Author" "Antmicro"
			(at 273.548 242.048 0)
			(layer "B.Fab")
			(hide yes)
			(effects
				(font
					(size 1 1)
					(thickness 0.15)
				)
				(justify mirror)
			)
		)
		(property "License" "Apache-2.0"
			(at 273.548 242.048 0)
			(layer "B.Fab")
			(hide yes)
			(effects
				(font
					(size 1 1)
					(thickness 0.15)
				)
				(justify mirror)
			)
		)
		(property "MPN" "CR0402-FX-4702GLF"
			(at 273.548 242.048 0)
			(layer "B.Fab")
			(hide yes)
			(effects
				(font
					(size 1 1)
					(thickness 0.15)
				)
				(justify mirror)
			)
		)
		(property "Manufacturer" "Bourns"
			(at 273.548 242.048 0)
			(layer "B.Fab")
			(hide yes)
			(effects
				(font
					(size 1 1)
					(thickness 0.15)
				)
				(justify mirror)
			)
		)
		(property "Tolerance" "1%"
			(at 273.548 242.048 0)
			(layer "B.Fab")
			(hide yes)
			(effects
				(font
					(size 1 1)
					(thickness 0.15)
				)
				(justify mirror)
			)
		)
		(property "Val" "47k"
			(at 273.548 242.048 0)
			(layer "B.Fab")
			(hide yes)
			(effects
				(font
					(size 1 1)
					(thickness 0.15)
				)
				(justify mirror)
			)
		)
		(sheetname "/Interfaces/")
		(sheetfile "interfaces.kicad_sch")
		(attr smd)
		(fp_rect
			(start -0.925 0.47)
			(end 0.925 -0.47)
			(stroke
				(width 0.05)
				(type default)
			)
			(fill no)
			(layer "B.CrtYd")
		)
		(fp_rect
			(start -0.5 0.25)
			(end 0.5 -0.25)
			(stroke
				(width 0.15)
				(type solid)
			)
			(fill no)
			(layer "B.Fab")
		)
		(pad "1" smd roundrect
			(at -0.48 0 180)
			(size 0.59 0.64)
			(layers "B.Cu" "B.Mask" "B.Paste")
			(roundrect_rratio 0.25)
			(net 2 "VCC3V3")
			(pintype "passive")
		)
		(pad "2" smd roundrect
			(at 0.48 0 180)
			(size 0.59 0.64)
			(layers "B.Cu" "B.Mask" "B.Paste")
			(roundrect_rratio 0.25)
			(net 325 "MMC_DAT4")
			(pintype "passive")
		)
	)
	(footprint "antmicro-footprints:R_0402_1005Metric"
		(layer "B.Cu")
		(at 136.274 124.214 180)
		(descr "Resistor SMD 0402")
		(tags "resistor SMD 0402")
		(property "Reference" "R124"
			(at -1.926 -1.286 0)
			(layer "B.SilkS")
			(effects
				(font
					(size 0.7 0.7)
					(thickness 0.15)
				)
				(justify left bottom mirror)
			)
		)
		(property "Value" "R_47k_0402"
			(at 0 -1.4 0)
			(layer "B.Fab")
			(effects
				(font
					(size 0.7 0.7)
					(thickness 0.15)
				)
				(justify left bottom mirror)
			)
		)
		(property "Datasheet" "https://www.bourns.com/docs/product-datasheets/cr.pdf"
			(at 0 0 180)
			(layer "F.Fab")
			(hide yes)
			(effects
				(font
					(size 1.27 1.27)
					(thickness 0.15)
				)
			)
		)
		(property "Description" "SMD Chip Resistor, 47 kohm, ± 1%, 62.5 mW, 0402 [1005 Metric], Thick Film, General Purpose"
			(at 0 0 180)
			(layer "F.Fab")
			(hide yes)
			(effects
				(font
					(size 1.27 1.27)
					(thickness 0.15)
				)
			)
		)
		(property "Author" "Antmicro"
			(at 272.548 248.428 0)
			(layer "B.Fab")
			(hide yes)
			(effects
				(font
					(size 1 1)
					(thickness 0.15)
				)
				(justify mirror)
			)
		)
		(property "License" "Apache-2.0"
			(at 272.548 248.428 0)
			(layer "B.Fab")
			(hide yes)
			(effects
				(font
					(size 1 1)
					(thickness 0.15)
				)
				(justify mirror)
			)
		)
		(property "MPN" "CR0402-FX-4702GLF"
			(at 272.548 248.428 0)
			(layer "B.Fab")
			(hide yes)
			(effects
				(font
					(size 1 1)
					(thickness 0.15)
				)
				(justify mirror)
			)
		)
		(property "Manufacturer" "Bourns"
			(at 272.548 248.428 0)
			(layer "B.Fab")
			(hide yes)
			(effects
				(font
					(size 1 1)
					(thickness 0.15)
				)
				(justify mirror)
			)
		)
		(property "Tolerance" "1%"
			(at 272.548 248.428 0)
			(layer "B.Fab")
			(hide yes)
			(effects
				(font
					(size 1 1)
					(thickness 0.15)
				)
				(justify mirror)
			)
		)
		(property "Val" "47k"
			(at 272.548 248.428 0)
			(layer "B.Fab")
			(hide yes)
			(effects
				(font
					(size 1 1)
					(thickness 0.15)
				)
				(justify mirror)
			)
		)
		(sheetname "/Interfaces/")
		(sheetfile "interfaces.kicad_sch")
		(attr smd)
		(fp_rect
			(start -0.925 0.47)
			(end 0.925 -0.47)
			(stroke
				(width 0.05)
				(type default)
			)
			(fill no)
			(layer "B.CrtYd")
		)
		(fp_rect
			(start -0.5 0.25)
			(end 0.5 -0.25)
			(stroke
				(width 0.15)
				(type solid)
			)
			(fill no)
			(layer "B.Fab")
		)
		(pad "1" smd roundrect
			(at -0.48 0 180)
			(size 0.59 0.64)
			(layers "B.Cu" "B.Mask" "B.Paste")
			(roundrect_rratio 0.25)
			(net 2 "VCC3V3")
			(pintype "passive")
		)
		(pad "2" smd roundrect
			(at 0.48 0 180)
			(size 0.59 0.64)
			(layers "B.Cu" "B.Mask" "B.Paste")
			(roundrect_rratio 0.25)
			(net 326 "MMC_DAT5")
			(pintype "passive")
		)
	)
	(footprint "antmicro-footprints:R_0402_1005Metric"
		(layer "B.Cu")
		(at 134.319 120.927)
		(descr "Resistor SMD 0402")
		(tags "resistor SMD 0402")
		(property "Reference" "R125"
			(at -3.619 0.373 0)
			(layer "B.SilkS")
			(effects
				(font
					(size 0.7 0.7)
					(thickness 0.15)
				)
				(justify right bottom mirror)
			)
		)
		(property "Value" "R_47k_0402"
			(at 0 -1.4 0)
			(layer "B.Fab")
			(effects
				(font
					(size 0.7 0.7)
					(thickness 0.15)
				)
				(justify right bottom mirror)
			)
		)
		(property "Datasheet" "https://www.bourns.com/docs/product-datasheets/cr.pdf"
			(at 0 0 0)
			(layer "F.Fab")
			(hide yes)
			(effects
				(font
					(size 1.27 1.27)
					(thickness 0.15)
				)
			)
		)
		(property "Description" "SMD Chip Resistor, 47 kohm, ± 1%, 62.5 mW, 0402 [1005 Metric], Thick Film, General Purpose"
			(at 0 0 0)
			(layer "F.Fab")
			(hide yes)
			(effects
				(font
					(size 1.27 1.27)
					(thickness 0.15)
				)
			)
		)
		(property "Author" "Antmicro"
			(at 0 0 0)
			(layer "B.Fab")
			(hide yes)
			(effects
				(font
					(size 1 1)
					(thickness 0.15)
				)
				(justify mirror)
			)
		)
		(property "License" "Apache-2.0"
			(at 0 0 0)
			(layer "B.Fab")
			(hide yes)
			(effects
				(font
					(size 1 1)
					(thickness 0.15)
				)
				(justify mirror)
			)
		)
		(property "MPN" "CR0402-FX-4702GLF"
			(at 0 0 0)
			(layer "B.Fab")
			(hide yes)
			(effects
				(font
					(size 1 1)
					(thickness 0.15)
				)
				(justify mirror)
			)
		)
		(property "Manufacturer" "Bourns"
			(at 0 0 0)
			(layer "B.Fab")
			(hide yes)
			(effects
				(font
					(size 1 1)
					(thickness 0.15)
				)
				(justify mirror)
			)
		)
		(property "Tolerance" "1%"
			(at 0 0 0)
			(layer "B.Fab")
			(hide yes)
			(effects
				(font
					(size 1 1)
					(thickness 0.15)
				)
				(justify mirror)
			)
		)
		(property "Val" "47k"
			(at 0 0 0)
			(layer "B.Fab")
			(hide yes)
			(effects
				(font
					(size 1 1)
					(thickness 0.15)
				)
				(justify mirror)
			)
		)
		(sheetname "/Interfaces/")
		(sheetfile "interfaces.kicad_sch")
		(attr smd)
		(fp_rect
			(start -0.925 0.47)
			(end 0.925 -0.47)
			(stroke
				(width 0.05)
				(type default)
			)
			(fill no)
			(layer "B.CrtYd")
		)
		(fp_rect
			(start -0.5 0.25)
			(end 0.5 -0.25)
			(stroke
				(width 0.15)
				(type solid)
			)
			(fill no)
			(layer "B.Fab")
		)
		(pad "1" smd roundrect
			(at -0.48 0)
			(size 0.59 0.64)
			(layers "B.Cu" "B.Mask" "B.Paste")
			(roundrect_rratio 0.25)
			(net 2 "VCC3V3")
			(pintype "passive")
		)
		(pad "2" smd roundrect
			(at 0.48 0)
			(size 0.59 0.64)
			(layers "B.Cu" "B.Mask" "B.Paste")
			(roundrect_rratio 0.25)
			(net 327 "MMC_DAT6")
			(pintype "passive")
		)
	)
	(footprint "antmicro-footprints:R_0402_1005Metric"
		(layer "B.Cu")
		(at 134.274 124.214)
		(descr "Resistor SMD 0402")
		(tags "resistor SMD 0402")
		(property "Reference" "R126"
			(at -1.874 1.286 0)
			(layer "B.SilkS")
			(effects
				(font
					(size 0.7 0.7)
					(thickness 0.15)
				)
				(justify right bottom mirror)
			)
		)
		(property "Value" "R_47k_0402"
			(at 0 -1.4 0)
			(layer "B.Fab")
			(effects
				(font
					(size 0.7 0.7)
					(thickness 0.15)
				)
				(justify right bottom mirror)
			)
		)
		(property "Datasheet" "https://www.bourns.com/docs/product-datasheets/cr.pdf"
			(at 0 0 0)
			(layer "F.Fab")
			(hide yes)
			(effects
				(font
					(size 1.27 1.27)
					(thickness 0.15)
				)
			)
		)
		(property "Description" "SMD Chip Resistor, 47 kohm, ± 1%, 62.5 mW, 0402 [1005 Metric], Thick Film, General Purpose"
			(at 0 0 0)
			(layer "F.Fab")
			(hide yes)
			(effects
				(font
					(size 1.27 1.27)
					(thickness 0.15)
				)
			)
		)
		(property "Author" "Antmicro"
			(at 0 0 0)
			(layer "B.Fab")
			(hide yes)
			(effects
				(font
					(size 1 1)
					(thickness 0.15)
				)
				(justify mirror)
			)
		)
		(property "License" "Apache-2.0"
			(at 0 0 0)
			(layer "B.Fab")
			(hide yes)
			(effects
				(font
					(size 1 1)
					(thickness 0.15)
				)
				(justify mirror)
			)
		)
		(property "MPN" "CR0402-FX-4702GLF"
			(at 0 0 0)
			(layer "B.Fab")
			(hide yes)
			(effects
				(font
					(size 1 1)
					(thickness 0.15)
				)
				(justify mirror)
			)
		)
		(property "Manufacturer" "Bourns"
			(at 0 0 0)
			(layer "B.Fab")
			(hide yes)
			(effects
				(font
					(size 1 1)
					(thickness 0.15)
				)
				(justify mirror)
			)
		)
		(property "Tolerance" "1%"
			(at 0 0 0)
			(layer "B.Fab")
			(hide yes)
			(effects
				(font
					(size 1 1)
					(thickness 0.15)
				)
				(justify mirror)
			)
		)
		(property "Val" "47k"
			(at 0 0 0)
			(layer "B.Fab")
			(hide yes)
			(effects
				(font
					(size 1 1)
					(thickness 0.15)
				)
				(justify mirror)
			)
		)
		(sheetname "/Interfaces/")
		(sheetfile "interfaces.kicad_sch")
		(attr smd)
		(fp_rect
			(start -0.925 0.47)
			(end 0.925 -0.47)
			(stroke
				(width 0.05)
				(type default)
			)
			(fill no)
			(layer "B.CrtYd")
		)
		(fp_rect
			(start -0.5 0.25)
			(end 0.5 -0.25)
			(stroke
				(width 0.15)
				(type solid)
			)
			(fill no)
			(layer "B.Fab")
		)
		(pad "1" smd roundrect
			(at -0.48 0)
			(size 0.59 0.64)
			(layers "B.Cu" "B.Mask" "B.Paste")
			(roundrect_rratio 0.25)
			(net 2 "VCC3V3")
			(pintype "passive")
		)
		(pad "2" smd roundrect
			(at 0.48 0)
			(size 0.59 0.64)
			(layers "B.Cu" "B.Mask" "B.Paste")
			(roundrect_rratio 0.25)
			(net 328 "MMC_DAT7")
			(pintype "passive")
		)
	)
	(footprint "antmicro-footprints:C_0402_1005Metric"
		(layer "B.Cu")
		(at 134.774 127.514 -90)
		(descr "Capacitor SMD 0402")
		(tags "capacitor SMD 0402")
		(property "Reference" "C183"
			(at 1.086 2.974 90)
			(layer "B.SilkS")
			(effects
				(font
					(size 0.7 0.7)
					(thickness 0.15)
				)
				(justify left bottom mirror)
			)
		)
		(property "Value" "C_2u2_0402"
			(at 0 -1.4 90)
			(layer "B.Fab")
			(effects
				(font
					(size 0.7 0.7)
					(thickness 0.15)
				)
				(justify left bottom mirror)
			)
		)
		(property "Datasheet" "https://product.tdk.com/en/search/capacitor/ceramic/mlcc/info?part_no=C1005X5R1A225K050BC"
			(at 0 0 270)
			(layer "F.Fab")
			(hide yes)
			(effects
				(font
					(size 1.27 1.27)
					(thickness 0.15)
				)
			)
		)
		(property "Description" "SMD Multilayer Ceramic Capacitor, 2.2 µF, 10 V, 0402 [1005 Metric], ± 10%, X5R, C"
			(at 0 0 270)
			(layer "F.Fab")
			(hide yes)
			(effects
				(font
					(size 1.27 1.27)
					(thickness 0.15)
				)
			)
		)
		(property "Author" "Antmicro"
			(at 7.26 262.288 0)
			(layer "B.Fab")
			(hide yes)
			(effects
				(font
					(size 1 1)
					(thickness 0.15)
				)
				(justify mirror)
			)
		)
		(property "Dielectric" ""
			(at 7.26 262.288 0)
			(layer "B.Fab")
			(hide yes)
			(effects
				(font
					(size 1 1)
					(thickness 0.15)
				)
				(justify mirror)
			)
		)
		(property "License" "Apache-2.0"
			(at 7.26 262.288 0)
			(layer "B.Fab")
			(hide yes)
			(effects
				(font
					(size 1 1)
					(thickness 0.15)
				)
				(justify mirror)
			)
		)
		(property "MPN" "C1005X5R1A225K050BC"
			(at 7.26 262.288 0)
			(layer "B.Fab")
			(hide yes)
			(effects
				(font
					(size 1 1)
					(thickness 0.15)
				)
				(justify mirror)
			)
		)
		(property "Manufacturer" "TDK"
			(at 7.26 262.288 0)
			(layer "B.Fab")
			(hide yes)
			(effects
				(font
					(size 1 1)
					(thickness 0.15)
				)
				(justify mirror)
			)
		)
		(property "Val" "2u2"
			(at 7.26 262.288 0)
			(layer "B.Fab")
			(hide yes)
			(effects
				(font
					(size 1 1)
					(thickness 0.15)
				)
				(justify mirror)
			)
		)
		(property "Voltage" ""
			(at 7.26 262.288 0)
			(layer "B.Fab")
			(hide yes)
			(effects
				(font
					(size 1 1)
					(thickness 0.15)
				)
				(justify mirror)
			)
		)
		(sheetname "/Interfaces/")
		(sheetfile "interfaces.kicad_sch")
		(attr smd)
		(fp_rect
			(start -0.925 0.47)
			(end 0.925 -0.47)
			(stroke
				(width 0.05)
				(type default)
			)
			(fill no)
			(layer "B.CrtYd")
		)
		(fp_line
			(start -0.494 0.25)
			(end 0.504 0.25)
			(stroke
				(width 0.15)
				(type solid)
			)
			(layer "B.Fab")
		)
		(fp_line
			(start 0.504 0.25)
			(end 0.504 -0.248)
			(stroke
				(width 0.15)
				(type solid)
			)
			(layer "B.Fab")
		)
		(fp_line
			(start -0.494 -0.248)
			(end -0.494 0.25)
			(stroke
				(width 0.15)
				(type solid)
			)
			(layer "B.Fab")
		)
		(fp_line
			(start 0.504 -0.248)
			(end -0.494 -0.248)
			(stroke
				(width 0.15)
				(type solid)
			)
			(layer "B.Fab")
		)
		(pad "1" smd roundrect
			(at -0.48 0 270)
			(size 0.59 0.64)
			(layers "B.Cu" "B.Mask" "B.Paste")
			(roundrect_rratio 0.25)
			(net 1 "GND")
			(pintype "passive")
		)
		(pad "2" smd roundrect
			(at 0.48 0 270)
			(size 0.59 0.64)
			(layers "B.Cu" "B.Mask" "B.Paste")
			(roundrect_rratio 0.25)
			(net 2 "VCC3V3")
			(pintype "passive")
		)
	)
	(footprint "antmicro-footprints:C_0402_1005Metric"
		(layer "B.Cu")
		(at 136.774 127.514 -90)
		(descr "Capacitor SMD 0402")
		(tags "capacitor SMD 0402")
		(property "Reference" "C184"
			(at 1.086 2.974 90)
			(layer "B.SilkS")
			(effects
				(font
					(size 0.7 0.7)
					(thickness 0.15)
				)
				(justify left bottom mirror)
			)
		)
		(property "Value" "C_2u2_0402"
			(at 0 -1.4 90)
			(layer "B.Fab")
			(effects
				(font
					(size 0.7 0.7)
					(thickness 0.15)
				)
				(justify left bottom mirror)
			)
		)
		(property "Datasheet" "https://product.tdk.com/en/search/capacitor/ceramic/mlcc/info?part_no=C1005X5R1A225K050BC"
			(at 0 0 270)
			(layer "F.Fab")
			(hide yes)
			(effects
				(font
					(size 1.27 1.27)
					(thickness 0.15)
				)
			)
		)
		(property "Description" "SMD Multilayer Ceramic Capacitor, 2.2 µF, 10 V, 0402 [1005 Metric], ± 10%, X5R, C"
			(at 0 0 270)
			(layer "F.Fab")
			(hide yes)
			(effects
				(font
					(size 1.27 1.27)
					(thickness 0.15)
				)
			)
		)
		(property "Author" "Antmicro"
			(at 9.26 264.288 0)
			(layer "B.Fab")
			(hide yes)
			(effects
				(font
					(size 1 1)
					(thickness 0.15)
				)
				(justify mirror)
			)
		)
		(property "Dielectric" ""
			(at 9.26 264.288 0)
			(layer "B.Fab")
			(hide yes)
			(effects
				(font
					(size 1 1)
					(thickness 0.15)
				)
				(justify mirror)
			)
		)
		(property "License" "Apache-2.0"
			(at 9.26 264.288 0)
			(layer "B.Fab")
			(hide yes)
			(effects
				(font
					(size 1 1)
					(thickness 0.15)
				)
				(justify mirror)
			)
		)
		(property "MPN" "C1005X5R1A225K050BC"
			(at 9.26 264.288 0)
			(layer "B.Fab")
			(hide yes)
			(effects
				(font
					(size 1 1)
					(thickness 0.15)
				)
				(justify mirror)
			)
		)
		(property "Manufacturer" "TDK"
			(at 9.26 264.288 0)
			(layer "B.Fab")
			(hide yes)
			(effects
				(font
					(size 1 1)
					(thickness 0.15)
				)
				(justify mirror)
			)
		)
		(property "Val" "2u2"
			(at 9.26 264.288 0)
			(layer "B.Fab")
			(hide yes)
			(effects
				(font
					(size 1 1)
					(thickness 0.15)
				)
				(justify mirror)
			)
		)
		(property "Voltage" ""
			(at 9.26 264.288 0)
			(layer "B.Fab")
			(hide yes)
			(effects
				(font
					(size 1 1)
					(thickness 0.15)
				)
				(justify mirror)
			)
		)
		(sheetname "/Interfaces/")
		(sheetfile "interfaces.kicad_sch")
		(attr smd)
		(fp_rect
			(start -0.925 0.47)
			(end 0.925 -0.47)
			(stroke
				(width 0.05)
				(type default)
			)
			(fill no)
			(layer "B.CrtYd")
		)
		(fp_line
			(start -0.494 0.25)
			(end 0.504 0.25)
			(stroke
				(width 0.15)
				(type solid)
			)
			(layer "B.Fab")
		)
		(fp_line
			(start 0.504 0.25)
			(end 0.504 -0.248)
			(stroke
				(width 0.15)
				(type solid)
			)
			(layer "B.Fab")
		)
		(fp_line
			(start -0.494 -0.248)
			(end -0.494 0.25)
			(stroke
				(width 0.15)
				(type solid)
			)
			(layer "B.Fab")
		)
		(fp_line
			(start 0.504 -0.248)
			(end -0.494 -0.248)
			(stroke
				(width 0.15)
				(type solid)
			)
			(layer "B.Fab")
		)
		(pad "1" smd roundrect
			(at -0.48 0 270)
			(size 0.59 0.64)
			(layers "B.Cu" "B.Mask" "B.Paste")
			(roundrect_rratio 0.25)
			(net 1 "GND")
			(pintype "passive")
		)
		(pad "2" smd roundrect
			(at 0.48 0 270)
			(size 0.59 0.64)
			(layers "B.Cu" "B.Mask" "B.Paste")
			(roundrect_rratio 0.25)
			(net 2 "VCC3V3")
			(pintype "passive")
		)
	)
	(footprint "antmicro-footprints:C_0402_1005Metric"
		(layer "B.Cu")
		(at 138.774 123.014 180)
		(descr "Capacitor SMD 0402")
		(tags "capacitor SMD 0402")
		(property "Reference" "C185"
			(at 0.774 -0.386 0)
			(layer "B.SilkS")
			(effects
				(font
					(size 0.7 0.7)
					(thickness 0.15)
				)
				(justify left bottom mirror)
			)
		)
		(property "Value" "C_2u2_0402"
			(at 0 -1.4 0)
			(layer "B.Fab")
			(effects
				(font
					(size 0.7 0.7)
					(thickness 0.15)
				)
				(justify left bottom mirror)
			)
		)
		(property "Datasheet" "https://product.tdk.com/en/search/capacitor/ceramic/mlcc/info?part_no=C1005X5R1A225K050BC"
			(at 0 0 180)
			(layer "F.Fab")
			(hide yes)
			(effects
				(font
					(size 1.27 1.27)
					(thickness 0.15)
				)
			)
		)
		(property "Description" "SMD Multilayer Ceramic Capacitor, 2.2 µF, 10 V, 0402 [1005 Metric], ± 10%, X5R, C"
			(at 0 0 180)
			(layer "F.Fab")
			(hide yes)
			(effects
				(font
					(size 1.27 1.27)
					(thickness 0.15)
				)
			)
		)
		(property "Author" "Antmicro"
			(at 277.548 246.028 0)
			(layer "B.Fab")
			(hide yes)
			(effects
				(font
					(size 1 1)
					(thickness 0.15)
				)
				(justify mirror)
			)
		)
		(property "Dielectric" ""
			(at 277.548 246.028 0)
			(layer "B.Fab")
			(hide yes)
			(effects
				(font
					(size 1 1)
					(thickness 0.15)
				)
				(justify mirror)
			)
		)
		(property "License" "Apache-2.0"
			(at 277.548 246.028 0)
			(layer "B.Fab")
			(hide yes)
			(effects
				(font
					(size 1 1)
					(thickness 0.15)
				)
				(justify mirror)
			)
		)
		(property "MPN" "C1005X5R1A225K050BC"
			(at 277.548 246.028 0)
			(layer "B.Fab")
			(hide yes)
			(effects
				(font
					(size 1 1)
					(thickness 0.15)
				)
				(justify mirror)
			)
		)
		(property "Manufacturer" "TDK"
			(at 277.548 246.028 0)
			(layer "B.Fab")
			(hide yes)
			(effects
				(font
					(size 1 1)
					(thickness 0.15)
				)
				(justify mirror)
			)
		)
		(property "Val" "2u2"
			(at 277.548 246.028 0)
			(layer "B.Fab")
			(hide yes)
			(effects
				(font
					(size 1 1)
					(thickness 0.15)
				)
				(justify mirror)
			)
		)
		(property "Voltage" ""
			(at 277.548 246.028 0)
			(layer "B.Fab")
			(hide yes)
			(effects
				(font
					(size 1 1)
					(thickness 0.15)
				)
				(justify mirror)
			)
		)
		(sheetname "/Interfaces/")
		(sheetfile "interfaces.kicad_sch")
		(attr smd)
		(fp_rect
			(start -0.925 0.47)
			(end 0.925 -0.47)
			(stroke
				(width 0.05)
				(type default)
			)
			(fill no)
			(layer "B.CrtYd")
		)
		(fp_line
			(start 0.504 0.25)
			(end 0.504 -0.248)
			(stroke
				(width 0.15)
				(type solid)
			)
			(layer "B.Fab")
		)
		(fp_line
			(start 0.504 -0.248)
			(end -0.494 -0.248)
			(stroke
				(width 0.15)
				(type solid)
			)
			(layer "B.Fab")
		)
		(fp_line
			(start -0.494 0.25)
			(end 0.504 0.25)
			(stroke
				(width 0.15)
				(type solid)
			)
			(layer "B.Fab")
		)
		(fp_line
			(start -0.494 -0.248)
			(end -0.494 0.25)
			(stroke
				(width 0.15)
				(type solid)
			)
			(layer "B.Fab")
		)
		(pad "1" smd roundrect
			(at -0.48 0 180)
			(size 0.59 0.64)
			(layers "B.Cu" "B.Mask" "B.Paste")
			(roundrect_rratio 0.25)
			(net 1 "GND")
			(pintype "passive")
		)
		(pad "2" smd roundrect
			(at 0.48 0 180)
			(size 0.59 0.64)
			(layers "B.Cu" "B.Mask" "B.Paste")
			(roundrect_rratio 0.25)
			(net 2 "VCC3V3")
			(pintype "passive")
		)
	)
	(footprint "antmicro-footprints:C_0402_1005Metric"
		(layer "B.Cu")
		(at 135.774 127.514 -90)
		(descr "Capacitor SMD 0402")
		(tags "capacitor SMD 0402")
		(property "Reference" "C186"
			(at 1.086 2.974 90)
			(layer "B.SilkS")
			(effects
				(font
					(size 0.7 0.7)
					(thickness 0.15)
				)
				(justify left bottom mirror)
			)
		)
		(property "Value" "C_100n_6V3_0402"
			(at 0 -1.4 90)
			(layer "B.Fab")
			(effects
				(font
					(size 0.7 0.7)
					(thickness 0.15)
				)
				(justify left bottom mirror)
			)
		)
		(property "Datasheet" "https://www.passivecomponent.com/wp-content/uploads/datasheet/WTC_MLCC_General_Purpose.pdf"
			(at 0 0 270)
			(layer "F.Fab")
			(hide yes)
			(effects
				(font
					(size 1.27 1.27)
					(thickness 0.15)
				)
			)
		)
		(property "Description" "SMT Multilayer Ceramic Capacitor, 0.1 µF, 6.3 V, 0402 [1005 Metric], ± 10%, X5R, Walsin MLCC"
			(at 0 0 270)
			(layer "F.Fab")
			(hide yes)
			(effects
				(font
					(size 1.27 1.27)
					(thickness 0.15)
				)
			)
		)
		(property "Author" "Antmicro"
			(at 8.26 263.288 0)
			(layer "B.Fab")
			(hide yes)
			(effects
				(font
					(size 1 1)
					(thickness 0.15)
				)
				(justify mirror)
			)
		)
		(property "Dielectric" ""
			(at 8.26 263.288 0)
			(layer "B.Fab")
			(hide yes)
			(effects
				(font
					(size 1 1)
					(thickness 0.15)
				)
				(justify mirror)
			)
		)
		(property "License" "Apache-2.0"
			(at 8.26 263.288 0)
			(layer "B.Fab")
			(hide yes)
			(effects
				(font
					(size 1 1)
					(thickness 0.15)
				)
				(justify mirror)
			)
		)
		(property "MPN" "0402X104K6R3CT"
			(at 8.26 263.288 0)
			(layer "B.Fab")
			(hide yes)
			(effects
				(font
					(size 1 1)
					(thickness 0.15)
				)
				(justify mirror)
			)
		)
		(property "Manufacturer" "Walsin"
			(at 8.26 263.288 0)
			(layer "B.Fab")
			(hide yes)
			(effects
				(font
					(size 1 1)
					(thickness 0.15)
				)
				(justify mirror)
			)
		)
		(property "Public" "False"
			(at 8.26 263.288 0)
			(layer "B.Fab")
			(hide yes)
			(effects
				(font
					(size 1 1)
					(thickness 0.15)
				)
				(justify mirror)
			)
		)
		(property "Val" "100n"
			(at 8.26 263.288 0)
			(layer "B.Fab")
			(hide yes)
			(effects
				(font
					(size 1 1)
					(thickness 0.15)
				)
				(justify mirror)
			)
		)
		(property "Voltage" ""
			(at 8.26 263.288 0)
			(layer "B.Fab")
			(hide yes)
			(effects
				(font
					(size 1 1)
					(thickness 0.15)
				)
				(justify mirror)
			)
		)
		(sheetname "/Interfaces/")
		(sheetfile "interfaces.kicad_sch")
		(attr smd)
		(fp_rect
			(start -0.925 0.47)
			(end 0.925 -0.47)
			(stroke
				(width 0.05)
				(type default)
			)
			(fill no)
			(layer "B.CrtYd")
		)
		(fp_line
			(start -0.494 0.25)
			(end 0.504 0.25)
			(stroke
				(width 0.15)
				(type solid)
			)
			(layer "B.Fab")
		)
		(fp_line
			(start 0.504 0.25)
			(end 0.504 -0.248)
			(stroke
				(width 0.15)
				(type solid)
			)
			(layer "B.Fab")
		)
		(fp_line
			(start -0.494 -0.248)
			(end -0.494 0.25)
			(stroke
				(width 0.15)
				(type solid)
			)
			(layer "B.Fab")
		)
		(fp_line
			(start 0.504 -0.248)
			(end -0.494 -0.248)
			(stroke
				(width 0.15)
				(type solid)
			)
			(layer "B.Fab")
		)
		(pad "1" smd roundrect
			(at -0.48 0 270)
			(size 0.59 0.64)
			(layers "B.Cu" "B.Mask" "B.Paste")
			(roundrect_rratio 0.25)
			(net 1 "GND")
			(pintype "passive")
		)
		(pad "2" smd roundrect
			(at 0.48 0 270)
			(size 0.59 0.64)
			(layers "B.Cu" "B.Mask" "B.Paste")
			(roundrect_rratio 0.25)
			(net 2 "VCC3V3")
			(pintype "passive")
		)
	)
	(footprint "antmicro-footprints:C_0402_1005Metric"
		(layer "B.Cu")
		(at 133.574 122.514)
		(descr "Capacitor SMD 0402")
		(tags "capacitor SMD 0402")
		(property "Reference" "C187"
			(at -3.674 0.386 0)
			(layer "B.SilkS")
			(effects
				(font
					(size 0.7 0.7)
					(thickness 0.15)
				)
				(justify right bottom mirror)
			)
		)
		(property "Value" "C_100n_6V3_0402"
			(at 0 -1.4 0)
			(layer "B.Fab")
			(effects
				(font
					(size 0.7 0.7)
					(thickness 0.15)
				)
				(justify right bottom mirror)
			)
		)
		(property "Datasheet" "https://www.passivecomponent.com/wp-content/uploads/datasheet/WTC_MLCC_General_Purpose.pdf"
			(at 0 0 0)
			(layer "F.Fab")
			(hide yes)
			(effects
				(font
					(size 1.27 1.27)
					(thickness 0.15)
				)
			)
		)
		(property "Description" "SMT Multilayer Ceramic Capacitor, 0.1 µF, 6.3 V, 0402 [1005 Metric], ± 10%, X5R, Walsin MLCC"
			(at 0 0 0)
			(layer "F.Fab")
			(hide yes)
			(effects
				(font
					(size 1.27 1.27)
					(thickness 0.15)
				)
			)
		)
		(property "Author" "Antmicro"
			(at 0 0 0)
			(layer "B.Fab")
			(hide yes)
			(effects
				(font
					(size 1 1)
					(thickness 0.15)
				)
				(justify mirror)
			)
		)
		(property "Dielectric" ""
			(at 0 0 0)
			(layer "B.Fab")
			(hide yes)
			(effects
				(font
					(size 1 1)
					(thickness 0.15)
				)
				(justify mirror)
			)
		)
		(property "License" "Apache-2.0"
			(at 0 0 0)
			(layer "B.Fab")
			(hide yes)
			(effects
				(font
					(size 1 1)
					(thickness 0.15)
				)
				(justify mirror)
			)
		)
		(property "MPN" "0402X104K6R3CT"
			(at 0 0 0)
			(layer "B.Fab")
			(hide yes)
			(effects
				(font
					(size 1 1)
					(thickness 0.15)
				)
				(justify mirror)
			)
		)
		(property "Manufacturer" "Walsin"
			(at 0 0 0)
			(layer "B.Fab")
			(hide yes)
			(effects
				(font
					(size 1 1)
					(thickness 0.15)
				)
				(justify mirror)
			)
		)
		(property "Public" "False"
			(at 0 0 0)
			(layer "B.Fab")
			(hide yes)
			(effects
				(font
					(size 1 1)
					(thickness 0.15)
				)
				(justify mirror)
			)
		)
		(property "Val" "100n"
			(at 0 0 0)
			(layer "B.Fab")
			(hide yes)
			(effects
				(font
					(size 1 1)
					(thickness 0.15)
				)
				(justify mirror)
			)
		)
		(property "Voltage" ""
			(at 0 0 0)
			(layer "B.Fab")
			(hide yes)
			(effects
				(font
					(size 1 1)
					(thickness 0.15)
				)
				(justify mirror)
			)
		)
		(sheetname "/Interfaces/")
		(sheetfile "interfaces.kicad_sch")
		(attr smd)
		(fp_rect
			(start -0.925 0.47)
			(end 0.925 -0.47)
			(stroke
				(width 0.05)
				(type default)
			)
			(fill no)
			(layer "B.CrtYd")
		)
		(fp_line
			(start -0.494 -0.248)
			(end -0.494 0.25)
			(stroke
				(width 0.15)
				(type solid)
			)
			(layer "B.Fab")
		)
		(fp_line
			(start -0.494 0.25)
			(end 0.504 0.25)
			(stroke
				(width 0.15)
				(type solid)
			)
			(layer "B.Fab")
		)
		(fp_line
			(start 0.504 -0.248)
			(end -0.494 -0.248)
			(stroke
				(width 0.15)
				(type solid)
			)
			(layer "B.Fab")
		)
		(fp_line
			(start 0.504 0.25)
			(end 0.504 -0.248)
			(stroke
				(width 0.15)
				(type solid)
			)
			(layer "B.Fab")
		)
		(pad "1" smd roundrect
			(at -0.48 0)
			(size 0.59 0.64)
			(layers "B.Cu" "B.Mask" "B.Paste")
			(roundrect_rratio 0.25)
			(net 1 "GND")
			(pintype "passive")
		)
		(pad "2" smd roundrect
			(at 0.48 0)
			(size 0.59 0.64)
			(layers "B.Cu" "B.Mask" "B.Paste")
			(roundrect_rratio 0.25)
			(net 2 "VCC3V3")
			(pintype "passive")
		)
	)
	(footprint "antmicro-footprints:C_0402_1005Metric"
		(layer "B.Cu")
		(at 140.274 131.414 180)
		(descr "Capacitor SMD 0402")
		(tags "capacitor SMD 0402")
		(property "Reference" "C189"
			(at -3.726 -0.386 0)
			(layer "B.SilkS")
			(effects
				(font
					(size 0.7 0.7)
					(thickness 0.15)
				)
				(justify left bottom mirror)
			)
		)
		(property "Value" "C_100n_6V3_0402"
			(at 0 -1.4 0)
			(layer "B.Fab")
			(effects
				(font
					(size 0.7 0.7)
					(thickness 0.15)
				)
				(justify left bottom mirror)
			)
		)
		(property "Datasheet" "https://www.passivecomponent.com/wp-content/uploads/datasheet/WTC_MLCC_General_Purpose.pdf"
			(at 0 0 180)
			(layer "F.Fab")
			(hide yes)
			(effects
				(font
					(size 1.27 1.27)
					(thickness 0.15)
				)
			)
		)
		(property "Description" "SMT Multilayer Ceramic Capacitor, 0.1 µF, 6.3 V, 0402 [1005 Metric], ± 10%, X5R, Walsin MLCC"
			(at 0 0 180)
			(layer "F.Fab")
			(hide yes)
			(effects
				(font
					(size 1.27 1.27)
					(thickness 0.15)
				)
			)
		)
		(property "Author" "Antmicro"
			(at 280.548 262.828 0)
			(layer "B.Fab")
			(hide yes)
			(effects
				(font
					(size 1 1)
					(thickness 0.15)
				)
				(justify mirror)
			)
		)
		(property "Dielectric" ""
			(at 280.548 262.828 0)
			(layer "B.Fab")
			(hide yes)
			(effects
				(font
					(size 1 1)
					(thickness 0.15)
				)
				(justify mirror)
			)
		)
		(property "License" "Apache-2.0"
			(at 280.548 262.828 0)
			(layer "B.Fab")
			(hide yes)
			(effects
				(font
					(size 1 1)
					(thickness 0.15)
				)
				(justify mirror)
			)
		)
		(property "MPN" "0402X104K6R3CT"
			(at 280.548 262.828 0)
			(layer "B.Fab")
			(hide yes)
			(effects
				(font
					(size 1 1)
					(thickness 0.15)
				)
				(justify mirror)
			)
		)
		(property "Manufacturer" "Walsin"
			(at 280.548 262.828 0)
			(layer "B.Fab")
			(hide yes)
			(effects
				(font
					(size 1 1)
					(thickness 0.15)
				)
				(justify mirror)
			)
		)
		(property "Public" "False"
			(at 280.548 262.828 0)
			(layer "B.Fab")
			(hide yes)
			(effects
				(font
					(size 1 1)
					(thickness 0.15)
				)
				(justify mirror)
			)
		)
		(property "Val" "100n"
			(at 280.548 262.828 0)
			(layer "B.Fab")
			(hide yes)
			(effects
				(font
					(size 1 1)
					(thickness 0.15)
				)
				(justify mirror)
			)
		)
		(property "Voltage" ""
			(at 280.548 262.828 0)
			(layer "B.Fab")
			(hide yes)
			(effects
				(font
					(size 1 1)
					(thickness 0.15)
				)
				(justify mirror)
			)
		)
		(sheetname "/Interfaces/")
		(sheetfile "interfaces.kicad_sch")
		(attr smd)
		(fp_rect
			(start -0.925 0.47)
			(end 0.925 -0.47)
			(stroke
				(width 0.05)
				(type default)
			)
			(fill no)
			(layer "B.CrtYd")
		)
		(fp_line
			(start 0.504 0.25)
			(end 0.504 -0.248)
			(stroke
				(width 0.15)
				(type solid)
			)
			(layer "B.Fab")
		)
		(fp_line
			(start 0.504 -0.248)
			(end -0.494 -0.248)
			(stroke
				(width 0.15)
				(type solid)
			)
			(layer "B.Fab")
		)
		(fp_line
			(start -0.494 0.25)
			(end 0.504 0.25)
			(stroke
				(width 0.15)
				(type solid)
			)
			(layer "B.Fab")
		)
		(fp_line
			(start -0.494 -0.248)
			(end -0.494 0.25)
			(stroke
				(width 0.15)
				(type solid)
			)
			(layer "B.Fab")
		)
		(pad "1" smd roundrect
			(at -0.48 0 180)
			(size 0.59 0.64)
			(layers "B.Cu" "B.Mask" "B.Paste")
			(roundrect_rratio 0.25)
			(net 1 "GND")
			(pintype "passive")
		)
		(pad "2" smd roundrect
			(at 0.48 0 180)
			(size 0.59 0.64)
			(layers "B.Cu" "B.Mask" "B.Paste")
			(roundrect_rratio 0.25)
			(net 200 "Net-(U1-VDDIM)")
			(pintype "passive")
		)
	)
	(footprint "antmicro-footprints:C_0402_1005Metric"
		(layer "B.Cu")
		(at 138.774 127.514 -90)
		(descr "Capacitor SMD 0402")
		(tags "capacitor SMD 0402")
		(property "Reference" "C223"
			(at 1.086 2.974 90)
			(layer "B.SilkS")
			(effects
				(font
					(size 0.7 0.7)
					(thickness 0.15)
				)
				(justify left bottom mirror)
			)
		)
		(property "Value" "C_100n_6V3_0402"
			(at 0 -1.4 90)
			(layer "B.Fab")
			(effects
				(font
					(size 0.7 0.7)
					(thickness 0.15)
				)
				(justify left bottom mirror)
			)
		)
		(property "Datasheet" "https://www.passivecomponent.com/wp-content/uploads/datasheet/WTC_MLCC_General_Purpose.pdf"
			(at 0 0 270)
			(layer "F.Fab")
			(hide yes)
			(effects
				(font
					(size 1.27 1.27)
					(thickness 0.15)
				)
			)
		)
		(property "Description" "SMT Multilayer Ceramic Capacitor, 0.1 µF, 6.3 V, 0402 [1005 Metric], ± 10%, X5R, Walsin MLCC"
			(at 0 0 270)
			(layer "F.Fab")
			(hide yes)
			(effects
				(font
					(size 1.27 1.27)
					(thickness 0.15)
				)
			)
		)
		(property "Author" "Antmicro"
			(at 11.26 266.288 0)
			(layer "B.Fab")
			(hide yes)
			(effects
				(font
					(size 1 1)
					(thickness 0.15)
				)
				(justify mirror)
			)
		)
		(property "Dielectric" ""
			(at 11.26 266.288 0)
			(layer "B.Fab")
			(hide yes)
			(effects
				(font
					(size 1 1)
					(thickness 0.15)
				)
				(justify mirror)
			)
		)
		(property "License" "Apache-2.0"
			(at 11.26 266.288 0)
			(layer "B.Fab")
			(hide yes)
			(effects
				(font
					(size 1 1)
					(thickness 0.15)
				)
				(justify mirror)
			)
		)
		(property "MPN" "0402X104K6R3CT"
			(at 11.26 266.288 0)
			(layer "B.Fab")
			(hide yes)
			(effects
				(font
					(size 1 1)
					(thickness 0.15)
				)
				(justify mirror)
			)
		)
		(property "Manufacturer" "Walsin"
			(at 11.26 266.288 0)
			(layer "B.Fab")
			(hide yes)
			(effects
				(font
					(size 1 1)
					(thickness 0.15)
				)
				(justify mirror)
			)
		)
		(property "Public" "False"
			(at 11.26 266.288 0)
			(layer "B.Fab")
			(hide yes)
			(effects
				(font
					(size 1 1)
					(thickness 0.15)
				)
				(justify mirror)
			)
		)
		(property "Val" "100n"
			(at 11.26 266.288 0)
			(layer "B.Fab")
			(hide yes)
			(effects
				(font
					(size 1 1)
					(thickness 0.15)
				)
				(justify mirror)
			)
		)
		(property "Voltage" ""
			(at 11.26 266.288 0)
			(layer "B.Fab")
			(hide yes)
			(effects
				(font
					(size 1 1)
					(thickness 0.15)
				)
				(justify mirror)
			)
		)
		(sheetname "/Interfaces/")
		(sheetfile "interfaces.kicad_sch")
		(attr smd)
		(fp_rect
			(start -0.925 0.47)
			(end 0.925 -0.47)
			(stroke
				(width 0.05)
				(type default)
			)
			(fill no)
			(layer "B.CrtYd")
		)
		(fp_line
			(start -0.494 0.25)
			(end 0.504 0.25)
			(stroke
				(width 0.15)
				(type solid)
			)
			(layer "B.Fab")
		)
		(fp_line
			(start 0.504 0.25)
			(end 0.504 -0.248)
			(stroke
				(width 0.15)
				(type solid)
			)
			(layer "B.Fab")
		)
		(fp_line
			(start -0.494 -0.248)
			(end -0.494 0.25)
			(stroke
				(width 0.15)
				(type solid)
			)
			(layer "B.Fab")
		)
		(fp_line
			(start 0.504 -0.248)
			(end -0.494 -0.248)
			(stroke
				(width 0.15)
				(type solid)
			)
			(layer "B.Fab")
		)
		(pad "1" smd roundrect
			(at -0.48 0 270)
			(size 0.59 0.64)
			(layers "B.Cu" "B.Mask" "B.Paste")
			(roundrect_rratio 0.25)
			(net 1 "GND")
			(pintype "passive")
		)
		(pad "2" smd roundrect
			(at 0.48 0 270)
			(size 0.59 0.64)
			(layers "B.Cu" "B.Mask" "B.Paste")
			(roundrect_rratio 0.25)
			(net 2 "VCC3V3")
			(pintype "passive")
		)
	)
	(footprint "antmicro-footprints:C_0402_1005Metric"
		(layer "B.Cu")
		(at 133.775 127.515 -90)
		(descr "Capacitor SMD 0402")
		(tags "capacitor SMD 0402")
		(property "Reference" "C224"
			(at 1.086 2.974 90)
			(layer "B.SilkS")
			(effects
				(font
					(size 0.7 0.7)
					(thickness 0.15)
				)
				(justify left bottom mirror)
			)
		)
		(property "Value" "C_100n_6V3_0402"
			(at 0 -1.4 90)
			(layer "B.Fab")
			(effects
				(font
					(size 0.7 0.7)
					(thickness 0.15)
				)
				(justify left bottom mirror)
			)
		)
		(property "Datasheet" "https://www.passivecomponent.com/wp-content/uploads/datasheet/WTC_MLCC_General_Purpose.pdf"
			(at 0 0 270)
			(layer "F.Fab")
			(hide yes)
			(effects
				(font
					(size 1.27 1.27)
					(thickness 0.15)
				)
			)
		)
		(property "Description" "SMT Multilayer Ceramic Capacitor, 0.1 µF, 6.3 V, 0402 [1005 Metric], ± 10%, X5R, Walsin MLCC"
			(at 0 0 270)
			(layer "F.Fab")
			(hide yes)
			(effects
				(font
					(size 1.27 1.27)
					(thickness 0.15)
				)
			)
		)
		(property "Author" "Antmicro"
			(at 6.26 261.29 0)
			(layer "B.Fab")
			(hide yes)
			(effects
				(font
					(size 1 1)
					(thickness 0.15)
				)
				(justify mirror)
			)
		)
		(property "Dielectric" ""
			(at 6.26 261.29 0)
			(layer "B.Fab")
			(hide yes)
			(effects
				(font
					(size 1 1)
					(thickness 0.15)
				)
				(justify mirror)
			)
		)
		(property "License" "Apache-2.0"
			(at 6.26 261.29 0)
			(layer "B.Fab")
			(hide yes)
			(effects
				(font
					(size 1 1)
					(thickness 0.15)
				)
				(justify mirror)
			)
		)
		(property "MPN" "0402X104K6R3CT"
			(at 6.26 261.29 0)
			(layer "B.Fab")
			(hide yes)
			(effects
				(font
					(size 1 1)
					(thickness 0.15)
				)
				(justify mirror)
			)
		)
		(property "Manufacturer" "Walsin"
			(at 6.26 261.29 0)
			(layer "B.Fab")
			(hide yes)
			(effects
				(font
					(size 1 1)
					(thickness 0.15)
				)
				(justify mirror)
			)
		)
		(property "Public" "False"
			(at 6.26 261.29 0)
			(layer "B.Fab")
			(hide yes)
			(effects
				(font
					(size 1 1)
					(thickness 0.15)
				)
				(justify mirror)
			)
		)
		(property "Val" "100n"
			(at 6.26 261.29 0)
			(layer "B.Fab")
			(hide yes)
			(effects
				(font
					(size 1 1)
					(thickness 0.15)
				)
				(justify mirror)
			)
		)
		(property "Voltage" ""
			(at 6.26 261.29 0)
			(layer "B.Fab")
			(hide yes)
			(effects
				(font
					(size 1 1)
					(thickness 0.15)
				)
				(justify mirror)
			)
		)
		(sheetname "/Interfaces/")
		(sheetfile "interfaces.kicad_sch")
		(attr smd)
		(fp_rect
			(start -0.925 0.47)
			(end 0.925 -0.47)
			(stroke
				(width 0.05)
				(type default)
			)
			(fill no)
			(layer "B.CrtYd")
		)
		(fp_line
			(start -0.494 0.25)
			(end 0.504 0.25)
			(stroke
				(width 0.15)
				(type solid)
			)
			(layer "B.Fab")
		)
		(fp_line
			(start 0.504 0.25)
			(end 0.504 -0.248)
			(stroke
				(width 0.15)
				(type solid)
			)
			(layer "B.Fab")
		)
		(fp_line
			(start -0.494 -0.248)
			(end -0.494 0.25)
			(stroke
				(width 0.15)
				(type solid)
			)
			(layer "B.Fab")
		)
		(fp_line
			(start 0.504 -0.248)
			(end -0.494 -0.248)
			(stroke
				(width 0.15)
				(type solid)
			)
			(layer "B.Fab")
		)
		(pad "1" smd roundrect
			(at -0.48 0 270)
			(size 0.59 0.64)
			(layers "B.Cu" "B.Mask" "B.Paste")
			(roundrect_rratio 0.25)
			(net 1 "GND")
			(pintype "passive")
		)
		(pad "2" smd roundrect
			(at 0.48 0 270)
			(size 0.59 0.64)
			(layers "B.Cu" "B.Mask" "B.Paste")
			(roundrect_rratio 0.25)
			(net 2 "VCC3V3")
			(pintype "passive")
		)
	)
	(footprint "antmicro-footprints:C_0402_1005Metric"
		(layer "B.Cu")
		(at 139.774 127.514 -90)
		(descr "Capacitor SMD 0402")
		(tags "capacitor SMD 0402")
		(property "Reference" "C229"
			(at 1.086 2.974 90)
			(layer "B.SilkS")
			(effects
				(font
					(size 0.7 0.7)
					(thickness 0.15)
				)
				(justify left bottom mirror)
			)
		)
		(property "Value" "C_100n_6V3_0402"
			(at 0 -1.4 90)
			(layer "B.Fab")
			(effects
				(font
					(size 0.7 0.7)
					(thickness 0.15)
				)
				(justify left bottom mirror)
			)
		)
		(property "Datasheet" "https://www.passivecomponent.com/wp-content/uploads/datasheet/WTC_MLCC_General_Purpose.pdf"
			(at 0 0 270)
			(layer "F.Fab")
			(hide yes)
			(effects
				(font
					(size 1.27 1.27)
					(thickness 0.15)
				)
			)
		)
		(property "Description" "SMT Multilayer Ceramic Capacitor, 0.1 µF, 6.3 V, 0402 [1005 Metric], ± 10%, X5R, Walsin MLCC"
			(at 0 0 270)
			(layer "F.Fab")
			(hide yes)
			(effects
				(font
					(size 1.27 1.27)
					(thickness 0.15)
				)
			)
		)
		(property "Author" "Antmicro"
			(at 12.26 267.288 0)
			(layer "B.Fab")
			(hide yes)
			(effects
				(font
					(size 1 1)
					(thickness 0.15)
				)
				(justify mirror)
			)
		)
		(property "Dielectric" ""
			(at 12.26 267.288 0)
			(layer "B.Fab")
			(hide yes)
			(effects
				(font
					(size 1 1)
					(thickness 0.15)
				)
				(justify mirror)
			)
		)
		(property "License" "Apache-2.0"
			(at 12.26 267.288 0)
			(layer "B.Fab")
			(hide yes)
			(effects
				(font
					(size 1 1)
					(thickness 0.15)
				)
				(justify mirror)
			)
		)
		(property "MPN" "0402X104K6R3CT"
			(at 12.26 267.288 0)
			(layer "B.Fab")
			(hide yes)
			(effects
				(font
					(size 1 1)
					(thickness 0.15)
				)
				(justify mirror)
			)
		)
		(property "Manufacturer" "Walsin"
			(at 12.26 267.288 0)
			(layer "B.Fab")
			(hide yes)
			(effects
				(font
					(size 1 1)
					(thickness 0.15)
				)
				(justify mirror)
			)
		)
		(property "Public" "False"
			(at 12.26 267.288 0)
			(layer "B.Fab")
			(hide yes)
			(effects
				(font
					(size 1 1)
					(thickness 0.15)
				)
				(justify mirror)
			)
		)
		(property "Val" "100n"
			(at 12.26 267.288 0)
			(layer "B.Fab")
			(hide yes)
			(effects
				(font
					(size 1 1)
					(thickness 0.15)
				)
				(justify mirror)
			)
		)
		(property "Voltage" ""
			(at 12.26 267.288 0)
			(layer "B.Fab")
			(hide yes)
			(effects
				(font
					(size 1 1)
					(thickness 0.15)
				)
				(justify mirror)
			)
		)
		(sheetname "/Interfaces/")
		(sheetfile "interfaces.kicad_sch")
		(attr smd)
		(fp_rect
			(start -0.925 0.47)
			(end 0.925 -0.47)
			(stroke
				(width 0.05)
				(type default)
			)
			(fill no)
			(layer "B.CrtYd")
		)
		(fp_line
			(start -0.494 0.25)
			(end 0.504 0.25)
			(stroke
				(width 0.15)
				(type solid)
			)
			(layer "B.Fab")
		)
		(fp_line
			(start 0.504 0.25)
			(end 0.504 -0.248)
			(stroke
				(width 0.15)
				(type solid)
			)
			(layer "B.Fab")
		)
		(fp_line
			(start -0.494 -0.248)
			(end -0.494 0.25)
			(stroke
				(width 0.15)
				(type solid)
			)
			(layer "B.Fab")
		)
		(fp_line
			(start 0.504 -0.248)
			(end -0.494 -0.248)
			(stroke
				(width 0.15)
				(type solid)
			)
			(layer "B.Fab")
		)
		(pad "1" smd roundrect
			(at -0.48 0 270)
			(size 0.59 0.64)
			(layers "B.Cu" "B.Mask" "B.Paste")
			(roundrect_rratio 0.25)
			(net 1 "GND")
			(pintype "passive")
		)
		(pad "2" smd roundrect
			(at 0.48 0 270)
			(size 0.59 0.64)
			(layers "B.Cu" "B.Mask" "B.Paste")
			(roundrect_rratio 0.25)
			(net 2 "VCC3V3")
			(pintype "passive")
		)
	)
	(footprint "antmicro-footprints:C_0402_1005Metric"
		(layer "B.Cu")
		(at 137.774 127.514 -90)
		(descr "Capacitor SMD 0402")
		(tags "capacitor SMD 0402")
		(property "Reference" "C230"
			(at 1.086 2.974 90)
			(layer "B.SilkS")
			(effects
				(font
					(size 0.7 0.7)
					(thickness 0.15)
				)
				(justify left bottom mirror)
			)
		)
		(property "Value" "C_100n_6V3_0402"
			(at 0 -1.4 90)
			(layer "B.Fab")
			(effects
				(font
					(size 0.7 0.7)
					(thickness 0.15)
				)
				(justify left bottom mirror)
			)
		)
		(property "Datasheet" "https://www.passivecomponent.com/wp-content/uploads/datasheet/WTC_MLCC_General_Purpose.pdf"
			(at 0 0 270)
			(layer "F.Fab")
			(hide yes)
			(effects
				(font
					(size 1.27 1.27)
					(thickness 0.15)
				)
			)
		)
		(property "Description" "SMT Multilayer Ceramic Capacitor, 0.1 µF, 6.3 V, 0402 [1005 Metric], ± 10%, X5R, Walsin MLCC"
			(at 0 0 270)
			(layer "F.Fab")
			(hide yes)
			(effects
				(font
					(size 1.27 1.27)
					(thickness 0.15)
				)
			)
		)
		(property "Author" "Antmicro"
			(at 10.26 265.288 0)
			(layer "B.Fab")
			(hide yes)
			(effects
				(font
					(size 1 1)
					(thickness 0.15)
				)
				(justify mirror)
			)
		)
		(property "Dielectric" ""
			(at 10.26 265.288 0)
			(layer "B.Fab")
			(hide yes)
			(effects
				(font
					(size 1 1)
					(thickness 0.15)
				)
				(justify mirror)
			)
		)
		(property "License" "Apache-2.0"
			(at 10.26 265.288 0)
			(layer "B.Fab")
			(hide yes)
			(effects
				(font
					(size 1 1)
					(thickness 0.15)
				)
				(justify mirror)
			)
		)
		(property "MPN" "0402X104K6R3CT"
			(at 10.26 265.288 0)
			(layer "B.Fab")
			(hide yes)
			(effects
				(font
					(size 1 1)
					(thickness 0.15)
				)
				(justify mirror)
			)
		)
		(property "Manufacturer" "Walsin"
			(at 10.26 265.288 0)
			(layer "B.Fab")
			(hide yes)
			(effects
				(font
					(size 1 1)
					(thickness 0.15)
				)
				(justify mirror)
			)
		)
		(property "Public" "False"
			(at 10.26 265.288 0)
			(layer "B.Fab")
			(hide yes)
			(effects
				(font
					(size 1 1)
					(thickness 0.15)
				)
				(justify mirror)
			)
		)
		(property "Val" "100n"
			(at 10.26 265.288 0)
			(layer "B.Fab")
			(hide yes)
			(effects
				(font
					(size 1 1)
					(thickness 0.15)
				)
				(justify mirror)
			)
		)
		(property "Voltage" ""
			(at 10.26 265.288 0)
			(layer "B.Fab")
			(hide yes)
			(effects
				(font
					(size 1 1)
					(thickness 0.15)
				)
				(justify mirror)
			)
		)
		(sheetname "/Interfaces/")
		(sheetfile "interfaces.kicad_sch")
		(attr smd)
		(fp_rect
			(start -0.925 0.47)
			(end 0.925 -0.47)
			(stroke
				(width 0.05)
				(type default)
			)
			(fill no)
			(layer "B.CrtYd")
		)
		(fp_line
			(start -0.494 0.25)
			(end 0.504 0.25)
			(stroke
				(width 0.15)
				(type solid)
			)
			(layer "B.Fab")
		)
		(fp_line
			(start 0.504 0.25)
			(end 0.504 -0.248)
			(stroke
				(width 0.15)
				(type solid)
			)
			(layer "B.Fab")
		)
		(fp_line
			(start -0.494 -0.248)
			(end -0.494 0.25)
			(stroke
				(width 0.15)
				(type solid)
			)
			(layer "B.Fab")
		)
		(fp_line
			(start 0.504 -0.248)
			(end -0.494 -0.248)
			(stroke
				(width 0.15)
				(type solid)
			)
			(layer "B.Fab")
		)
		(pad "1" smd roundrect
			(at -0.48 0 270)
			(size 0.59 0.64)
			(layers "B.Cu" "B.Mask" "B.Paste")
			(roundrect_rratio 0.25)
			(net 1 "GND")
			(pintype "passive")
		)
		(pad "2" smd roundrect
			(at 0.48 0 270)
			(size 0.59 0.64)
			(layers "B.Cu" "B.Mask" "B.Paste")
			(roundrect_rratio 0.25)
			(net 2 "VCC3V3")
			(pintype "passive")
		)
	)
	(footprint "antmicro-footprints:C_0402_1005Metric"
		(layer "B.Cu")
		(at 141.774 127.514 -90)
		(descr "Capacitor SMD 0402")
		(tags "capacitor SMD 0402")
		(property "Reference" "C231"
			(at 1.086 2.974 90)
			(layer "B.SilkS")
			(effects
				(font
					(size 0.7 0.7)
					(thickness 0.15)
				)
				(justify left bottom mirror)
			)
		)
		(property "Value" "C_100n_6V3_0402"
			(at 0 -1.4 90)
			(layer "B.Fab")
			(effects
				(font
					(size 0.7 0.7)
					(thickness 0.15)
				)
				(justify left bottom mirror)
			)
		)
		(property "Datasheet" "https://www.passivecomponent.com/wp-content/uploads/datasheet/WTC_MLCC_General_Purpose.pdf"
			(at 0 0 270)
			(layer "F.Fab")
			(hide yes)
			(effects
				(font
					(size 1.27 1.27)
					(thickness 0.15)
				)
			)
		)
		(property "Description" "SMT Multilayer Ceramic Capacitor, 0.1 µF, 6.3 V, 0402 [1005 Metric], ± 10%, X5R, Walsin MLCC"
			(at 0 0 270)
			(layer "F.Fab")
			(hide yes)
			(effects
				(font
					(size 1.27 1.27)
					(thickness 0.15)
				)
			)
		)
		(property "Author" "Antmicro"
			(at 14.26 269.288 0)
			(layer "B.Fab")
			(hide yes)
			(effects
				(font
					(size 1 1)
					(thickness 0.15)
				)
				(justify mirror)
			)
		)
		(property "Dielectric" ""
			(at 14.26 269.288 0)
			(layer "B.Fab")
			(hide yes)
			(effects
				(font
					(size 1 1)
					(thickness 0.15)
				)
				(justify mirror)
			)
		)
		(property "License" "Apache-2.0"
			(at 14.26 269.288 0)
			(layer "B.Fab")
			(hide yes)
			(effects
				(font
					(size 1 1)
					(thickness 0.15)
				)
				(justify mirror)
			)
		)
		(property "MPN" "0402X104K6R3CT"
			(at 14.26 269.288 0)
			(layer "B.Fab")
			(hide yes)
			(effects
				(font
					(size 1 1)
					(thickness 0.15)
				)
				(justify mirror)
			)
		)
		(property "Manufacturer" "Walsin"
			(at 14.26 269.288 0)
			(layer "B.Fab")
			(hide yes)
			(effects
				(font
					(size 1 1)
					(thickness 0.15)
				)
				(justify mirror)
			)
		)
		(property "Public" "False"
			(at 14.26 269.288 0)
			(layer "B.Fab")
			(hide yes)
			(effects
				(font
					(size 1 1)
					(thickness 0.15)
				)
				(justify mirror)
			)
		)
		(property "Val" "100n"
			(at 14.26 269.288 0)
			(layer "B.Fab")
			(hide yes)
			(effects
				(font
					(size 1 1)
					(thickness 0.15)
				)
				(justify mirror)
			)
		)
		(property "Voltage" ""
			(at 14.26 269.288 0)
			(layer "B.Fab")
			(hide yes)
			(effects
				(font
					(size 1 1)
					(thickness 0.15)
				)
				(justify mirror)
			)
		)
		(sheetname "/Interfaces/")
		(sheetfile "interfaces.kicad_sch")
		(attr smd)
		(fp_rect
			(start -0.925 0.47)
			(end 0.925 -0.47)
			(stroke
				(width 0.05)
				(type default)
			)
			(fill no)
			(layer "B.CrtYd")
		)
		(fp_line
			(start -0.494 0.25)
			(end 0.504 0.25)
			(stroke
				(width 0.15)
				(type solid)
			)
			(layer "B.Fab")
		)
		(fp_line
			(start 0.504 0.25)
			(end 0.504 -0.248)
			(stroke
				(width 0.15)
				(type solid)
			)
			(layer "B.Fab")
		)
		(fp_line
			(start -0.494 -0.248)
			(end -0.494 0.25)
			(stroke
				(width 0.15)
				(type solid)
			)
			(layer "B.Fab")
		)
		(fp_line
			(start 0.504 -0.248)
			(end -0.494 -0.248)
			(stroke
				(width 0.15)
				(type solid)
			)
			(layer "B.Fab")
		)
		(pad "1" smd roundrect
			(at -0.48 0 270)
			(size 0.59 0.64)
			(layers "B.Cu" "B.Mask" "B.Paste")
			(roundrect_rratio 0.25)
			(net 1 "GND")
			(pintype "passive")
		)
		(pad "2" smd roundrect
			(at 0.48 0 270)
			(size 0.59 0.64)
			(layers "B.Cu" "B.Mask" "B.Paste")
			(roundrect_rratio 0.25)
			(net 2 "VCC3V3")
			(pintype "passive")
		)
	)
	(footprint "antmicro-footprints:C_0402_1005Metric"
		(layer "B.Cu")
		(at 140.774 127.514 -90)
		(descr "Capacitor SMD 0402")
		(tags "capacitor SMD 0402")
		(property "Reference" "C232"
			(at 1.086 2.974 90)
			(layer "B.SilkS")
			(effects
				(font
					(size 0.7 0.7)
					(thickness 0.15)
				)
				(justify left bottom mirror)
			)
		)
		(property "Value" "C_100n_6V3_0402"
			(at 0 -1.4 90)
			(layer "B.Fab")
			(effects
				(font
					(size 0.7 0.7)
					(thickness 0.15)
				)
				(justify left bottom mirror)
			)
		)
		(property "Datasheet" "https://www.passivecomponent.com/wp-content/uploads/datasheet/WTC_MLCC_General_Purpose.pdf"
			(at 0 0 270)
			(layer "F.Fab")
			(hide yes)
			(effects
				(font
					(size 1.27 1.27)
					(thickness 0.15)
				)
			)
		)
		(property "Description" "SMT Multilayer Ceramic Capacitor, 0.1 µF, 6.3 V, 0402 [1005 Metric], ± 10%, X5R, Walsin MLCC"
			(at 0 0 270)
			(layer "F.Fab")
			(hide yes)
			(effects
				(font
					(size 1.27 1.27)
					(thickness 0.15)
				)
			)
		)
		(property "Author" "Antmicro"
			(at 13.26 268.288 0)
			(layer "B.Fab")
			(hide yes)
			(effects
				(font
					(size 1 1)
					(thickness 0.15)
				)
				(justify mirror)
			)
		)
		(property "Dielectric" ""
			(at 13.26 268.288 0)
			(layer "B.Fab")
			(hide yes)
			(effects
				(font
					(size 1 1)
					(thickness 0.15)
				)
				(justify mirror)
			)
		)
		(property "License" "Apache-2.0"
			(at 13.26 268.288 0)
			(layer "B.Fab")
			(hide yes)
			(effects
				(font
					(size 1 1)
					(thickness 0.15)
				)
				(justify mirror)
			)
		)
		(property "MPN" "0402X104K6R3CT"
			(at 13.26 268.288 0)
			(layer "B.Fab")
			(hide yes)
			(effects
				(font
					(size 1 1)
					(thickness 0.15)
				)
				(justify mirror)
			)
		)
		(property "Manufacturer" "Walsin"
			(at 13.26 268.288 0)
			(layer "B.Fab")
			(hide yes)
			(effects
				(font
					(size 1 1)
					(thickness 0.15)
				)
				(justify mirror)
			)
		)
		(property "Public" "False"
			(at 13.26 268.288 0)
			(layer "B.Fab")
			(hide yes)
			(effects
				(font
					(size 1 1)
					(thickness 0.15)
				)
				(justify mirror)
			)
		)
		(property "Val" "100n"
			(at 13.26 268.288 0)
			(layer "B.Fab")
			(hide yes)
			(effects
				(font
					(size 1 1)
					(thickness 0.15)
				)
				(justify mirror)
			)
		)
		(property "Voltage" ""
			(at 13.26 268.288 0)
			(layer "B.Fab")
			(hide yes)
			(effects
				(font
					(size 1 1)
					(thickness 0.15)
				)
				(justify mirror)
			)
		)
		(sheetname "/Interfaces/")
		(sheetfile "interfaces.kicad_sch")
		(attr smd)
		(fp_rect
			(start -0.925 0.47)
			(end 0.925 -0.47)
			(stroke
				(width 0.05)
				(type default)
			)
			(fill no)
			(layer "B.CrtYd")
		)
		(fp_line
			(start -0.494 0.25)
			(end 0.504 0.25)
			(stroke
				(width 0.15)
				(type solid)
			)
			(layer "B.Fab")
		)
		(fp_line
			(start 0.504 0.25)
			(end 0.504 -0.248)
			(stroke
				(width 0.15)
				(type solid)
			)
			(layer "B.Fab")
		)
		(fp_line
			(start -0.494 -0.248)
			(end -0.494 0.25)
			(stroke
				(width 0.15)
				(type solid)
			)
			(layer "B.Fab")
		)
		(fp_line
			(start 0.504 -0.248)
			(end -0.494 -0.248)
			(stroke
				(width 0.15)
				(type solid)
			)
			(layer "B.Fab")
		)
		(pad "1" smd roundrect
			(at -0.48 0 270)
			(size 0.59 0.64)
			(layers "B.Cu" "B.Mask" "B.Paste")
			(roundrect_rratio 0.25)
			(net 1 "GND")
			(pintype "passive")
		)
		(pad "2" smd roundrect
			(at 0.48 0 270)
			(size 0.59 0.64)
			(layers "B.Cu" "B.Mask" "B.Paste")
			(roundrect_rratio 0.25)
			(net 2 "VCC3V3")
			(pintype "passive")
		)
	)
	(footprint "antmicro-footprints:R_0402_1005Metric"
		(layer "B.Cu")
		(at 77.975 148.175 180)
		(descr "Resistor SMD 0402")
		(tags "resistor SMD 0402")
		(property "Reference" "R161"
			(at 0.775 -0.425 0)
			(layer "B.SilkS")
			(effects
				(font
					(size 0.7 0.7)
					(thickness 0.15)
				)
				(justify left bottom mirror)
			)
		)
		(property "Value" "R_0R_0402"
			(at 0 -1.4 0)
			(layer "B.Fab")
			(effects
				(font
					(size 0.7 0.7)
					(thickness 0.15)
				)
				(justify left bottom mirror)
			)
		)
		(property "Datasheet" "https://industrial.panasonic.com/cdbs/www-data/pdf/RDA0000/AOA0000C301.pdf"
			(at 0 0 180)
			(layer "F.Fab")
			(hide yes)
			(effects
				(font
					(size 1.27 1.27)
					(thickness 0.15)
				)
			)
		)
		(property "Description" "SMD Chip Resistor, Jumper, 0 ohm, 100 mW, 0402 [1005 Metric], Thick Film, General Purpose"
			(at 0 0 180)
			(layer "F.Fab")
			(hide yes)
			(effects
				(font
					(size 1.27 1.27)
					(thickness 0.15)
				)
			)
		)
		(property "Author" "Antmicro"
			(at 155.95 296.35 0)
			(layer "B.Fab")
			(hide yes)
			(effects
				(font
					(size 1 1)
					(thickness 0.15)
				)
				(justify mirror)
			)
		)
		(property "Current" "1A"
			(at 155.95 296.35 0)
			(layer "B.Fab")
			(hide yes)
			(effects
				(font
					(size 1 1)
					(thickness 0.15)
				)
				(justify mirror)
			)
		)
		(property "License" "Apache-2.0"
			(at 155.95 296.35 0)
			(layer "B.Fab")
			(hide yes)
			(effects
				(font
					(size 1 1)
					(thickness 0.15)
				)
				(justify mirror)
			)
		)
		(property "MPN" "ERJ2GE0R00X"
			(at 155.95 296.35 0)
			(layer "B.Fab")
			(hide yes)
			(effects
				(font
					(size 1 1)
					(thickness 0.15)
				)
				(justify mirror)
			)
		)
		(property "Manufacturer" "Panasonic"
			(at 155.95 296.35 0)
			(layer "B.Fab")
			(hide yes)
			(effects
				(font
					(size 1 1)
					(thickness 0.15)
				)
				(justify mirror)
			)
		)
		(property "Tolerance" "~"
			(at 155.95 296.35 0)
			(layer "B.Fab")
			(hide yes)
			(effects
				(font
					(size 1 1)
					(thickness 0.15)
				)
				(justify mirror)
			)
		)
		(property "Val" "0R"
			(at 155.95 296.35 0)
			(layer "B.Fab")
			(hide yes)
			(effects
				(font
					(size 1 1)
					(thickness 0.15)
				)
				(justify mirror)
			)
		)
		(property "DNP" ""
			(at 0 0 180)
			(unlocked yes)
			(layer "B.Fab")
			(hide yes)
			(effects
				(font
					(size 1 1)
					(thickness 0.15)
				)
				(justify mirror)
			)
		)
		(sheetname "/FPGA banks 13-16/")
		(sheetfile "fpga-banks-13-16.kicad_sch")
		(attr smd)
		(fp_rect
			(start -0.925 0.47)
			(end 0.925 -0.47)
			(stroke
				(width 0.05)
				(type default)
			)
			(fill no)
			(layer "B.CrtYd")
		)
		(fp_rect
			(start -0.5 0.25)
			(end 0.5 -0.25)
			(stroke
				(width 0.15)
				(type solid)
			)
			(fill no)
			(layer "B.Fab")
		)
		(pad "1" smd roundrect
			(at -0.48 0 180)
			(size 0.59 0.64)
			(layers "B.Cu" "B.Mask" "B.Paste")
			(roundrect_rratio 0.25)
			(net 344 "Net-(U14A-IO_L6P_T0_FCS_B_14)")
			(pintype "passive")
		)
		(pad "2" smd roundrect
			(at 0.48 0 180)
			(size 0.59 0.64)
			(layers "B.Cu" "B.Mask" "B.Paste")
			(roundrect_rratio 0.25)
			(net 350 "ROT_QSPI_CS_B")
			(pintype "passive")
		)
	)
	(footprint "antmicro-footprints:C_0402_1005Metric"
		(layer "B.Cu")
		(at 96.275 109.927 180)
		(descr "Capacitor SMD 0402")
		(tags "capacitor SMD 0402")
		(property "Reference" "C234"
			(at 1.01 0.727 0)
			(layer "B.SilkS")
			(effects
				(font
					(size 0.7 0.7)
					(thickness 0.15)
				)
				(justify left bottom mirror)
			)
		)
		(property "Value" "C_470n_0402"
			(at 0 -1.4 0)
			(layer "B.Fab")
			(effects
				(font
					(size 0.7 0.7)
					(thickness 0.15)
				)
				(justify left bottom mirror)
			)
		)
		(property "Datasheet" "https://product.tdk.com/en/search/capacitor/ceramic/mlcc/info?part_no=C1005X5R1E474M050BB"
			(at 0 0 180)
			(layer "F.Fab")
			(hide yes)
			(effects
				(font
					(size 1.27 1.27)
					(thickness 0.15)
				)
			)
		)
		(property "Description" "SMD Multilayer Ceramic Capacitor, 0.47 µF, 25 V, 0402 [1005 Metric], ± 20%, X5R, C"
			(at 0 0 180)
			(layer "F.Fab")
			(hide yes)
			(effects
				(font
					(size 1.27 1.27)
					(thickness 0.15)
				)
			)
		)
		(property "Author" "Antmicro"
			(at 192.55 219.854 0)
			(layer "B.Fab")
			(hide yes)
			(effects
				(font
					(size 1 1)
					(thickness 0.15)
				)
				(justify mirror)
			)
		)
		(property "Dielectric" ""
			(at 192.55 219.854 0)
			(layer "B.Fab")
			(hide yes)
			(effects
				(font
					(size 1 1)
					(thickness 0.15)
				)
				(justify mirror)
			)
		)
		(property "License" "Apache-2.0"
			(at 192.55 219.854 0)
			(layer "B.Fab")
			(hide yes)
			(effects
				(font
					(size 1 1)
					(thickness 0.15)
				)
				(justify mirror)
			)
		)
		(property "MPN" "C1005X5R1E474M050BB"
			(at 192.55 219.854 0)
			(layer "B.Fab")
			(hide yes)
			(effects
				(font
					(size 1 1)
					(thickness 0.15)
				)
				(justify mirror)
			)
		)
		(property "Manufacturer" "TDK"
			(at 192.55 219.854 0)
			(layer "B.Fab")
			(hide yes)
			(effects
				(font
					(size 1 1)
					(thickness 0.15)
				)
				(justify mirror)
			)
		)
		(property "Val" "470n"
			(at 192.55 219.854 0)
			(layer "B.Fab")
			(hide yes)
			(effects
				(font
					(size 1 1)
					(thickness 0.15)
				)
				(justify mirror)
			)
		)
		(property "Voltage" ""
			(at 192.55 219.854 0)
			(layer "B.Fab")
			(hide yes)
			(effects
				(font
					(size 1 1)
					(thickness 0.15)
				)
				(justify mirror)
			)
		)
		(sheetname "/FPGA banks 13-16/")
		(sheetfile "fpga-banks-13-16.kicad_sch")
		(attr smd)
		(fp_rect
			(start -0.925 0.47)
			(end 0.925 -0.47)
			(stroke
				(width 0.05)
				(type default)
			)
			(fill no)
			(layer "B.CrtYd")
		)
		(fp_line
			(start 0.504 0.25)
			(end 0.504 -0.248)
			(stroke
				(width 0.15)
				(type solid)
			)
			(layer "B.Fab")
		)
		(fp_line
			(start 0.504 -0.248)
			(end -0.494 -0.248)
			(stroke
				(width 0.15)
				(type solid)
			)
			(layer "B.Fab")
		)
		(fp_line
			(start -0.494 0.25)
			(end 0.504 0.25)
			(stroke
				(width 0.15)
				(type solid)
			)
			(layer "B.Fab")
		)
		(fp_line
			(start -0.494 -0.248)
			(end -0.494 0.25)
			(stroke
				(width 0.15)
				(type solid)
			)
			(layer "B.Fab")
		)
		(pad "1" smd roundrect
			(at -0.48 0 180)
			(size 0.59 0.64)
			(layers "B.Cu" "B.Mask" "B.Paste")
			(roundrect_rratio 0.25)
			(net 1 "GND")
			(pintype "passive")
		)
		(pad "2" smd roundrect
			(at 0.48 0 180)
			(size 0.59 0.64)
			(layers "B.Cu" "B.Mask" "B.Paste")
			(roundrect_rratio 0.25)
			(net 2 "VCC3V3")
			(pintype "passive")
		)
	)
	(footprint "antmicro-footprints:C_0402_1005Metric"
		(layer "B.Cu")
		(at 64.555 126.995 90)
		(descr "Capacitor SMD 0402")
		(tags "capacitor SMD 0402")
		(property "Reference" "C36"
			(at -1.095 -0.575 90)
			(layer "B.SilkS")
			(effects
				(font
					(size 0.7 0.7)
					(thickness 0.15)
				)
				(justify right bottom mirror)
			)
		)
		(property "Value" "C_470n_0402"
			(at 0 -1.4 90)
			(layer "B.Fab")
			(effects
				(font
					(size 0.7 0.7)
					(thickness 0.15)
				)
				(justify right bottom mirror)
			)
		)
		(property "Datasheet" "https://product.tdk.com/en/search/capacitor/ceramic/mlcc/info?part_no=C1005X5R1E474M050BB"
			(at 0 0 90)
			(layer "F.Fab")
			(hide yes)
			(effects
				(font
					(size 1.27 1.27)
					(thickness 0.15)
				)
			)
		)
		(property "Description" "SMD Multilayer Ceramic Capacitor, 0.47 µF, 25 V, 0402 [1005 Metric], ± 20%, X5R, C"
			(at 0 0 90)
			(layer "F.Fab")
			(hide yes)
			(effects
				(font
					(size 1.27 1.27)
					(thickness 0.15)
				)
			)
		)
		(property "Author" "Antmicro"
			(at 191.55 62.44 0)
			(layer "B.Fab")
			(hide yes)
			(effects
				(font
					(size 1 1)
					(thickness 0.15)
				)
				(justify mirror)
			)
		)
		(property "Dielectric" ""
			(at 191.55 62.44 0)
			(layer "B.Fab")
			(hide yes)
			(effects
				(font
					(size 1 1)
					(thickness 0.15)
				)
				(justify mirror)
			)
		)
		(property "License" "Apache-2.0"
			(at 191.55 62.44 0)
			(layer "B.Fab")
			(hide yes)
			(effects
				(font
					(size 1 1)
					(thickness 0.15)
				)
				(justify mirror)
			)
		)
		(property "MPN" "C1005X5R1E474M050BB"
			(at 191.55 62.44 0)
			(layer "B.Fab")
			(hide yes)
			(effects
				(font
					(size 1 1)
					(thickness 0.15)
				)
				(justify mirror)
			)
		)
		(property "Manufacturer" "TDK"
			(at 191.55 62.44 0)
			(layer "B.Fab")
			(hide yes)
			(effects
				(font
					(size 1 1)
					(thickness 0.15)
				)
				(justify mirror)
			)
		)
		(property "Val" "470n"
			(at 191.55 62.44 0)
			(layer "B.Fab")
			(hide yes)
			(effects
				(font
					(size 1 1)
					(thickness 0.15)
				)
				(justify mirror)
			)
		)
		(property "Voltage" ""
			(at 191.55 62.44 0)
			(layer "B.Fab")
			(hide yes)
			(effects
				(font
					(size 1 1)
					(thickness 0.15)
				)
				(justify mirror)
			)
		)
		(sheetname "/RoT/")
		(sheetfile "rot.kicad_sch")
		(attr smd)
		(fp_rect
			(start -0.925 0.47)
			(end 0.925 -0.47)
			(stroke
				(width 0.05)
				(type default)
			)
			(fill no)
			(layer "B.CrtYd")
		)
		(fp_line
			(start 0.504 -0.248)
			(end -0.494 -0.248)
			(stroke
				(width 0.15)
				(type solid)
			)
			(layer "B.Fab")
		)
		(fp_line
			(start -0.494 -0.248)
			(end -0.494 0.25)
			(stroke
				(width 0.15)
				(type solid)
			)
			(layer "B.Fab")
		)
		(fp_line
			(start 0.504 0.25)
			(end 0.504 -0.248)
			(stroke
				(width 0.15)
				(type solid)
			)
			(layer "B.Fab")
		)
		(fp_line
			(start -0.494 0.25)
			(end 0.504 0.25)
			(stroke
				(width 0.15)
				(type solid)
			)
			(layer "B.Fab")
		)
		(pad "1" smd roundrect
			(at -0.48 0 90)
			(size 0.59 0.64)
			(layers "B.Cu" "B.Mask" "B.Paste")
			(roundrect_rratio 0.25)
			(net 1 "GND")
			(pintype "passive")
		)
		(pad "2" smd roundrect
			(at 0.48 0 90)
			(size 0.59 0.64)
			(layers "B.Cu" "B.Mask" "B.Paste")
			(roundrect_rratio 0.25)
			(net 2 "VCC3V3")
			(pintype "passive")
		)
	)
	(footprint "antmicro-footprints:SOT-23-3"
		(layer "B.Cu")
		(at 71.04 84.49 90)
		(property "Reference" "Q12"
			(at 0.99 -2.74 180)
			(layer "B.SilkS")
			(effects
				(font
					(size 0.7 0.7)
					(thickness 0.15)
				)
				(justify right bottom mirror)
			)
		)
		(property "Value" "2N7002_SOT-23-3"
			(at -1.9 -2.7 90)
			(layer "B.Fab")
			(effects
				(font
					(size 0.7 0.7)
					(thickness 0.15)
				)
				(justify right bottom mirror)
			)
		)
		(property "Datasheet" "https://www.onsemi.com/pub/Collateral/NDS7002A-D.PDF"
			(at 0 0 90)
			(layer "F.Fab")
			(hide yes)
			(effects
				(font
					(size 1.27 1.27)
					(thickness 0.15)
				)
			)
		)
		(property "Description" "Power MOSFET, N Channel, 60 V, 115 mA, 1.2 ohm, SOT-23, Surface Mount"
			(at 0 0 90)
			(layer "F.Fab")
			(hide yes)
			(effects
				(font
					(size 1.27 1.27)
					(thickness 0.15)
				)
			)
		)
		(property "Author" "Antmicro"
			(at 155.53 13.45 0)
			(layer "B.Fab")
			(hide yes)
			(effects
				(font
					(size 1 1)
					(thickness 0.15)
				)
				(justify mirror)
			)
		)
		(property "License" "Apache-2.0"
			(at 155.53 13.45 0)
			(layer "B.Fab")
			(hide yes)
			(effects
				(font
					(size 1 1)
					(thickness 0.15)
				)
				(justify mirror)
			)
		)
		(property "MPN" "2N7002"
			(at 155.53 13.45 0)
			(layer "B.Fab")
			(hide yes)
			(effects
				(font
					(size 1 1)
					(thickness 0.15)
				)
				(justify mirror)
			)
		)
		(property "Manufacturer" "ON Semiconductor"
			(at 155.53 13.45 0)
			(layer "B.Fab")
			(hide yes)
			(effects
				(font
					(size 1 1)
					(thickness 0.15)
				)
				(justify mirror)
			)
		)
		(sheetname "/FPGA banks 34-35 & CFG/")
		(sheetfile "fpga-banks-34-25-cfg.kicad_sch")
		(attr smd)
		(fp_line
			(start 0.7 -1.5)
			(end -0.7 -1.5)
			(stroke
				(width 0.15)
				(type solid)
			)
			(layer "B.SilkS")
		)
		(fp_line
			(start -0.7 -1.5)
			(end -0.7 -1.35)
			(stroke
				(width 0.15)
				(type solid)
			)
			(layer "B.SilkS")
		)
		(fp_line
			(start 0.7 -0.4)
			(end 0.7 -1.5)
			(stroke
				(width 0.15)
				(type solid)
			)
			(layer "B.SilkS")
		)
		(fp_line
			(start 0.7 0.4)
			(end 0.7 1.5)
			(stroke
				(width 0.15)
				(type solid)
			)
			(layer "B.SilkS")
		)
		(fp_line
			(start -0.85 1.35)
			(end -0.7 1.5)
			(stroke
				(width 0.15)
				(type solid)
			)
			(layer "B.SilkS")
		)
		(fp_line
			(start -1.45 1.35)
			(end -0.85 1.35)
			(stroke
				(width 0.15)
				(type solid)
			)
			(layer "B.SilkS")
		)
		(fp_line
			(start 0.7 1.5)
			(end -0.7 1.5)
			(stroke
				(width 0.15)
				(type solid)
			)
			(layer "B.SilkS")
		)
		(fp_line
			(start 0.85 -1.65)
			(end -0.85 -1.65)
			(stroke
				(width 0.05)
				(type solid)
			)
			(layer "B.CrtYd")
		)
		(fp_line
			(start -0.85 -1.65)
			(end -0.85 -1.4)
			(stroke
				(width 0.05)
				(type solid)
			)
			(layer "B.CrtYd")
		)
		(fp_line
			(start -0.85 -1.4)
			(end -1.75 -1.4)
			(stroke
				(width 0.05)
				(type solid)
			)
			(layer "B.CrtYd")
		)
		(fp_line
			(start -1.75 -1.4)
			(end -1.75 -0.5)
			(stroke
				(width 0.05)
				(type solid)
			)
			(layer "B.CrtYd")
		)
		(fp_line
			(start -0.85 -0.5)
			(end -0.85 0.5)
			(stroke
				(width 0.05)
				(type solid)
			)
			(layer "B.CrtYd")
		)
		(fp_line
			(start -1.75 -0.5)
			(end -0.85 -0.5)
			(stroke
				(width 0.05)
				(type solid)
			)
			(layer "B.CrtYd")
		)
		(fp_line
			(start 1.75 -0.45)
			(end 0.85 -0.45)
			(stroke
				(width 0.05)
				(type solid)
			)
			(layer "B.CrtYd")
		)
		(fp_line
			(start 0.85 -0.45)
			(end 0.85 -1.65)
			(stroke
				(width 0.05)
				(type solid)
			)
			(layer "B.CrtYd")
		)
		(fp_line
			(start 1.75 0.45)
			(end 1.75 -0.45)
			(stroke
				(width 0.05)
				(type solid)
			)
			(layer "B.CrtYd")
		)
		(fp_line
			(start 0.825 0.45)
			(end 1.75 0.45)
			(stroke
				(width 0.05)
				(type solid)
			)
			(layer "B.CrtYd")
		)
		(fp_line
			(start -0.85 0.5)
			(end -1.75 0.5)
			(stroke
				(width 0.05)
				(type solid)
			)
			(layer "B.CrtYd")
		)
		(fp_line
			(start -1.75 0.5)
			(end -1.75 1.4)
			(stroke
				(width 0.05)
				(type solid)
			)
			(layer "B.CrtYd")
		)
		(fp_line
			(start -0.9 1.4)
			(end -1.75 1.4)
			(stroke
				(width 0.05)
				(type solid)
			)
			(layer "B.CrtYd")
		)
		(fp_line
			(start 0.825 1.6)
			(end 0.825 0.45)
			(stroke
				(width 0.05)
				(type solid)
			)
			(layer "B.CrtYd")
		)
		(fp_line
			(start -0.9 1.6)
			(end -0.9 1.4)
			(stroke
				(width 0.05)
				(type solid)
			)
			(layer "B.CrtYd")
		)
		(fp_line
			(start -0.9 1.6)
			(end 0.825 1.6)
			(stroke
				(width 0.05)
				(type solid)
			)
			(layer "B.CrtYd")
		)
		(fp_line
			(start 0.688 -1.519)
			(end 0.688 1.52)
			(stroke
				(width 0.15)
				(type solid)
			)
			(layer "B.Fab")
		)
		(fp_line
			(start -0.712 -1.519)
			(end 0.688 -1.519)
			(stroke
				(width 0.15)
				(type solid)
			)
			(layer "B.Fab")
		)
		(fp_line
			(start -0.712 1.325)
			(end -0.712 -1.523)
			(stroke
				(width 0.15)
				(type solid)
			)
			(layer "B.Fab")
		)
		(fp_line
			(start -0.437 1.526)
			(end -0.712 1.325)
			(stroke
				(width 0.15)
				(type solid)
			)
			(layer "B.Fab")
		)
		(fp_line
			(start -0.437 1.526)
			(end 0.688 1.526)
			(stroke
				(width 0.15)
				(type solid)
			)
			(layer "B.Fab")
		)
		(pad "1" smd roundrect
			(at -1.1 0.951 90)
			(size 1 0.6)
			(layers "B.Cu" "B.Mask" "B.Paste")
			(roundrect_rratio 0.15)
			(net 222 "INIT")
			(pinfunction "G")
			(pintype "input")
		)
		(pad "2" smd roundrect
			(at -1.1 -0.949 90)
			(size 1 0.6)
			(layers "B.Cu" "B.Mask" "B.Paste")
			(roundrect_rratio 0.15)
			(net 1 "GND")
			(pinfunction "S")
			(pintype "passive")
		)
		(pad "3" smd roundrect
			(at 1.1 0.0005 90)
			(size 1 0.6)
			(layers "B.Cu" "B.Mask" "B.Paste")
			(roundrect_rratio 0.15)
			(net 225 "Net-(D9-C)")
			(pinfunction "D")
			(pintype "passive")
		)
	)
	(footprint "antmicro-footprints:C_0402_1005Metric"
		(layer "B.Cu")
		(at 99.775 114.675 180)
		(descr "Capacitor SMD 0402")
		(tags "capacitor SMD 0402")
		(property "Reference" "C129"
			(at -1.251 0.45 0)
			(layer "B.SilkS")
			(effects
				(font
					(size 0.7 0.7)
					(thickness 0.15)
				)
				(justify left bottom mirror)
			)
		)
		(property "Value" "C_470n_0402"
			(at 0 -1.4 0)
			(layer "B.Fab")
			(effects
				(font
					(size 0.7 0.7)
					(thickness 0.15)
				)
				(justify left bottom mirror)
			)
		)
		(property "Datasheet" "https://product.tdk.com/en/search/capacitor/ceramic/mlcc/info?part_no=C1005X5R1E474M050BB"
			(at 0 0 180)
			(layer "F.Fab")
			(hide yes)
			(effects
				(font
					(size 1.27 1.27)
					(thickness 0.15)
				)
			)
		)
		(property "Description" "SMD Multilayer Ceramic Capacitor, 0.47 µF, 25 V, 0402 [1005 Metric], ± 20%, X5R, C"
			(at 0 0 180)
			(layer "F.Fab")
			(hide yes)
			(effects
				(font
					(size 1.27 1.27)
					(thickness 0.15)
				)
			)
		)
		(property "Author" "Antmicro"
			(at 199.55 229.35 0)
			(layer "B.Fab")
			(hide yes)
			(effects
				(font
					(size 1 1)
					(thickness 0.15)
				)
				(justify mirror)
			)
		)
		(property "Dielectric" ""
			(at 199.55 229.35 0)
			(layer "B.Fab")
			(hide yes)
			(effects
				(font
					(size 1 1)
					(thickness 0.15)
				)
				(justify mirror)
			)
		)
		(property "License" "Apache-2.0"
			(at 199.55 229.35 0)
			(layer "B.Fab")
			(hide yes)
			(effects
				(font
					(size 1 1)
					(thickness 0.15)
				)
				(justify mirror)
			)
		)
		(property "MPN" "C1005X5R1E474M050BB"
			(at 199.55 229.35 0)
			(layer "B.Fab")
			(hide yes)
			(effects
				(font
					(size 1 1)
					(thickness 0.15)
				)
				(justify mirror)
			)
		)
		(property "Manufacturer" "TDK"
			(at 199.55 229.35 0)
			(layer "B.Fab")
			(hide yes)
			(effects
				(font
					(size 1 1)
					(thickness 0.15)
				)
				(justify mirror)
			)
		)
		(property "Val" "470n"
			(at 199.55 229.35 0)
			(layer "B.Fab")
			(hide yes)
			(effects
				(font
					(size 1 1)
					(thickness 0.15)
				)
				(justify mirror)
			)
		)
		(property "Voltage" ""
			(at 199.55 229.35 0)
			(layer "B.Fab")
			(hide yes)
			(effects
				(font
					(size 1 1)
					(thickness 0.15)
				)
				(justify mirror)
			)
		)
		(sheetname "/FPGA banks 13-16/")
		(sheetfile "fpga-banks-13-16.kicad_sch")
		(attr smd)
		(fp_rect
			(start -0.925 0.47)
			(end 0.925 -0.47)
			(stroke
				(width 0.05)
				(type default)
			)
			(fill no)
			(layer "B.CrtYd")
		)
		(fp_line
			(start 0.504 0.25)
			(end 0.504 -0.248)
			(stroke
				(width 0.15)
				(type solid)
			)
			(layer "B.Fab")
		)
		(fp_line
			(start 0.504 -0.248)
			(end -0.494 -0.248)
			(stroke
				(width 0.15)
				(type solid)
			)
			(layer "B.Fab")
		)
		(fp_line
			(start -0.494 0.25)
			(end 0.504 0.25)
			(stroke
				(width 0.15)
				(type solid)
			)
			(layer "B.Fab")
		)
		(fp_line
			(start -0.494 -0.248)
			(end -0.494 0.25)
			(stroke
				(width 0.15)
				(type solid)
			)
			(layer "B.Fab")
		)
		(pad "1" smd roundrect
			(at -0.48 0 180)
			(size 0.59 0.64)
			(layers "B.Cu" "B.Mask" "B.Paste")
			(roundrect_rratio 0.25)
			(net 1 "GND")
			(pintype "passive")
		)
		(pad "2" smd roundrect
			(at 0.48 0 180)
			(size 0.59 0.64)
			(layers "B.Cu" "B.Mask" "B.Paste")
			(roundrect_rratio 0.25)
			(net 2 "VCC3V3")
			(pintype "passive")
		)
	)
	(footprint "antmicro-footprints:R_0402_1005Metric"
		(layer "B.Cu")
		(at 94.075 122.675 180)
		(descr "Resistor SMD 0402")
		(tags "resistor SMD 0402")
		(property "Reference" "R143"
			(at -1.325 0.475 0)
			(layer "B.SilkS")
			(effects
				(font
					(size 0.7 0.7)
					(thickness 0.15)
				)
				(justify left bottom mirror)
			)
		)
		(property "Value" "R_100R_0402"
			(at 0 -1.4 0)
			(layer "B.Fab")
			(effects
				(font
					(size 0.7 0.7)
					(thickness 0.15)
				)
				(justify left bottom mirror)
			)
		)
		(property "Datasheet" "https://www.bourns.com/docs/product-datasheets/cr.pdf"
			(at 0 0 180)
			(layer "F.Fab")
			(hide yes)
			(effects
				(font
					(size 1.27 1.27)
					(thickness 0.15)
				)
			)
		)
		(property "Description" "SMD Chip Resistor, 100 ohm, ± 1%, 62.5 mW, 0402 [1005 Metric], Thick Film, General Purpose"
			(at 0 0 180)
			(layer "F.Fab")
			(hide yes)
			(effects
				(font
					(size 1.27 1.27)
					(thickness 0.15)
				)
			)
		)
		(property "Author" "Antmicro"
			(at 188.15 245.35 0)
			(layer "B.Fab")
			(hide yes)
			(effects
				(font
					(size 1 1)
					(thickness 0.15)
				)
				(justify mirror)
			)
		)
		(property "License" "Apache-2.0"
			(at 188.15 245.35 0)
			(layer "B.Fab")
			(hide yes)
			(effects
				(font
					(size 1 1)
					(thickness 0.15)
				)
				(justify mirror)
			)
		)
		(property "MPN" "CR0402-FX-1000GLF"
			(at 188.15 245.35 0)
			(layer "B.Fab")
			(hide yes)
			(effects
				(font
					(size 1 1)
					(thickness 0.15)
				)
				(justify mirror)
			)
		)
		(property "Manufacturer" "Bourns"
			(at 188.15 245.35 0)
			(layer "B.Fab")
			(hide yes)
			(effects
				(font
					(size 1 1)
					(thickness 0.15)
				)
				(justify mirror)
			)
		)
		(property "Tolerance" "1%"
			(at 188.15 245.35 0)
			(layer "B.Fab")
			(hide yes)
			(effects
				(font
					(size 1 1)
					(thickness 0.15)
				)
				(justify mirror)
			)
		)
		(property "Val" "100R"
			(at 188.15 245.35 0)
			(layer "B.Fab")
			(hide yes)
			(effects
				(font
					(size 1 1)
					(thickness 0.15)
				)
				(justify mirror)
			)
		)
		(sheetname "/Interfaces/")
		(sheetfile "interfaces.kicad_sch")
		(attr smd)
		(fp_rect
			(start -0.925 0.47)
			(end 0.925 -0.47)
			(stroke
				(width 0.05)
				(type default)
			)
			(fill no)
			(layer "B.CrtYd")
		)
		(fp_rect
			(start -0.5 0.25)
			(end 0.5 -0.25)
			(stroke
				(width 0.15)
				(type solid)
			)
			(fill no)
			(layer "B.Fab")
		)
		(pad "1" smd roundrect
			(at -0.48 0 180)
			(size 0.59 0.64)
			(layers "B.Cu" "B.Mask" "B.Paste")
			(roundrect_rratio 0.25)
			(net 533 "Net-(U14E-MGTRREF_216)")
			(pintype "passive")
		)
		(pad "2" smd roundrect
			(at 0.48 0 180)
			(size 0.59 0.64)
			(layers "B.Cu" "B.Mask" "B.Paste")
			(roundrect_rratio 0.25)
			(net 339 "VCC1V2")
			(pintype "passive")
		)
	)
	(footprint "antmicro-footprints:C_0402_1005Metric"
		(layer "B.Cu")
		(at 106.975 118.175 -90)
		(descr "Capacitor SMD 0402")
		(tags "capacitor SMD 0402")
		(property "Reference" "C237"
			(at -1.475 0.575 90)
			(layer "B.SilkS")
			(effects
				(font
					(size 0.7 0.7)
					(thickness 0.15)
				)
				(justify left bottom mirror)
			)
		)
		(property "Value" "C_470n_0402"
			(at 0 -1.4 90)
			(layer "B.Fab")
			(effects
				(font
					(size 0.7 0.7)
					(thickness 0.15)
				)
				(justify left bottom mirror)
			)
		)
		(property "Datasheet" "https://product.tdk.com/en/search/capacitor/ceramic/mlcc/info?part_no=C1005X5R1E474M050BB"
			(at 0 0 270)
			(layer "F.Fab")
			(hide yes)
			(effects
				(font
					(size 1.27 1.27)
					(thickness 0.15)
				)
			)
		)
		(property "Description" "SMD Multilayer Ceramic Capacitor, 0.47 µF, 25 V, 0402 [1005 Metric], ± 20%, X5R, C"
			(at 0 0 270)
			(layer "F.Fab")
			(hide yes)
			(effects
				(font
					(size 1.27 1.27)
					(thickness 0.15)
				)
			)
		)
		(property "Author" "Antmicro"
			(at -11.2 225.15 0)
			(layer "B.Fab")
			(hide yes)
			(effects
				(font
					(size 1 1)
					(thickness 0.15)
				)
				(justify mirror)
			)
		)
		(property "Dielectric" ""
			(at -11.2 225.15 0)
			(layer "B.Fab")
			(hide yes)
			(effects
				(font
					(size 1 1)
					(thickness 0.15)
				)
				(justify mirror)
			)
		)
		(property "License" "Apache-2.0"
			(at -11.2 225.15 0)
			(layer "B.Fab")
			(hide yes)
			(effects
				(font
					(size 1 1)
					(thickness 0.15)
				)
				(justify mirror)
			)
		)
		(property "MPN" "C1005X5R1E474M050BB"
			(at -11.2 225.15 0)
			(layer "B.Fab")
			(hide yes)
			(effects
				(font
					(size 1 1)
					(thickness 0.15)
				)
				(justify mirror)
			)
		)
		(property "Manufacturer" "TDK"
			(at -11.2 225.15 0)
			(layer "B.Fab")
			(hide yes)
			(effects
				(font
					(size 1 1)
					(thickness 0.15)
				)
				(justify mirror)
			)
		)
		(property "Val" "470n"
			(at -11.2 225.15 0)
			(layer "B.Fab")
			(hide yes)
			(effects
				(font
					(size 1 1)
					(thickness 0.15)
				)
				(justify mirror)
			)
		)
		(property "Voltage" ""
			(at -11.2 225.15 0)
			(layer "B.Fab")
			(hide yes)
			(effects
				(font
					(size 1 1)
					(thickness 0.15)
				)
				(justify mirror)
			)
		)
		(sheetname "/FPGA banks 34-35 & CFG/")
		(sheetfile "fpga-banks-34-25-cfg.kicad_sch")
		(attr smd)
		(fp_rect
			(start -0.925 0.47)
			(end 0.925 -0.47)
			(stroke
				(width 0.05)
				(type default)
			)
			(fill no)
			(layer "B.CrtYd")
		)
		(fp_line
			(start -0.494 0.25)
			(end 0.504 0.25)
			(stroke
				(width 0.15)
				(type solid)
			)
			(layer "B.Fab")
		)
		(fp_line
			(start 0.504 0.25)
			(end 0.504 -0.248)
			(stroke
				(width 0.15)
				(type solid)
			)
			(layer "B.Fab")
		)
		(fp_line
			(start -0.494 -0.248)
			(end -0.494 0.25)
			(stroke
				(width 0.15)
				(type solid)
			)
			(layer "B.Fab")
		)
		(fp_line
			(start 0.504 -0.248)
			(end -0.494 -0.248)
			(stroke
				(width 0.15)
				(type solid)
			)
			(layer "B.Fab")
		)
		(pad "1" smd roundrect
			(at -0.48 0 270)
			(size 0.59 0.64)
			(layers "B.Cu" "B.Mask" "B.Paste")
			(roundrect_rratio 0.25)
			(net 1 "GND")
			(pintype "passive")
		)
		(pad "2" smd roundrect
			(at 0.48 0 270)
			(size 0.59 0.64)
			(layers "B.Cu" "B.Mask" "B.Paste")
			(roundrect_rratio 0.25)
			(net 2 "VCC3V3")
			(pintype "passive")
		)
	)
	(footprint "antmicro-footprints:C_0201"
		(layer "B.Cu")
		(at 104.275 122.675)
		(descr "Capacitor SMD 0201")
		(tags "capacitor SMD 0201")
		(property "Reference" "C157"
			(at 8.325 0.425 0)
			(layer "B.SilkS")
			(effects
				(font
					(size 0.7 0.7)
					(thickness 0.15)
				)
				(justify right bottom mirror)
			)
		)
		(property "Value" "C_470n_0201"
			(at 0 -1.4 0)
			(layer "B.Fab")
			(effects
				(font
					(size 0.7 0.7)
					(thickness 0.15)
				)
				(justify right bottom mirror)
			)
		)
		(property "Datasheet" "https://product.tdk.com/en/search/capacitor/ceramic/mlcc/info?part_no=C0603X5R1A474M030BC"
			(at 0 0 0)
			(layer "F.Fab")
			(hide yes)
			(effects
				(font
					(size 1.27 1.27)
					(thickness 0.15)
				)
			)
		)
		(property "Description" "SMD Multilayer Ceramic Capacitor, 0.47 µF, 10 V, 0201 [0603 Metric], ± 20%, X5R, C"
			(at 0 0 0)
			(layer "F.Fab")
			(hide yes)
			(effects
				(font
					(size 1.27 1.27)
					(thickness 0.15)
				)
			)
		)
		(property "Author" "Antmicro"
			(at 0 0 0)
			(layer "B.Fab")
			(hide yes)
			(effects
				(font
					(size 1 1)
					(thickness 0.15)
				)
				(justify mirror)
			)
		)
		(property "Dielectric" ""
			(at 0 0 0)
			(layer "B.Fab")
			(hide yes)
			(effects
				(font
					(size 1 1)
					(thickness 0.15)
				)
				(justify mirror)
			)
		)
		(property "License" "Apache-2.0"
			(at 0 0 0)
			(layer "B.Fab")
			(hide yes)
			(effects
				(font
					(size 1 1)
					(thickness 0.15)
				)
				(justify mirror)
			)
		)
		(property "MPN" "C0603X5R1A474M030BC"
			(at 0 0 0)
			(layer "B.Fab")
			(hide yes)
			(effects
				(font
					(size 1 1)
					(thickness 0.15)
				)
				(justify mirror)
			)
		)
		(property "Manufacturer" "TDK"
			(at 0 0 0)
			(layer "B.Fab")
			(hide yes)
			(effects
				(font
					(size 1 1)
					(thickness 0.15)
				)
				(justify mirror)
			)
		)
		(property "Public" "False"
			(at 0 0 0)
			(layer "B.Fab")
			(hide yes)
			(effects
				(font
					(size 1 1)
					(thickness 0.15)
				)
				(justify mirror)
			)
		)
		(property "Val" "470n"
			(at 0 0 0)
			(layer "B.Fab")
			(hide yes)
			(effects
				(font
					(size 1 1)
					(thickness 0.15)
				)
				(justify mirror)
			)
		)
		(property "Voltage" ""
			(at 0 0 0)
			(layer "B.Fab")
			(hide yes)
			(effects
				(font
					(size 1 1)
					(thickness 0.15)
				)
				(justify mirror)
			)
		)
		(property "DNP" ""
			(at 0 0 0)
			(unlocked yes)
			(layer "B.Fab")
			(hide yes)
			(effects
				(font
					(size 1 1)
					(thickness 0.15)
				)
				(justify mirror)
			)
		)
		(sheetname "/FPGA power supply/")
		(sheetfile "fpga-power-supply.kicad_sch")
		(attr smd)
		(fp_rect
			(start -0.7 0.35)
			(end 0.7 -0.35)
			(stroke
				(width 0.05)
				(type default)
			)
			(fill no)
			(layer "B.CrtYd")
		)
		(fp_rect
			(start 0.3 -0.15)
			(end -0.301 0.149)
			(stroke
				(width 0.15)
				(type solid)
			)
			(fill no)
			(layer "B.Fab")
		)
		(pad "" smd roundrect
			(at -0.349 0.002)
			(size 0.318 0.36)
			(layers "B.Paste")
			(roundrect_rratio 0.25)
		)
		(pad "" smd roundrect
			(at 0.341 0.002)
			(size 0.318 0.36)
			(layers "B.Paste")
			(roundrect_rratio 0.25)
		)
		(pad "1" smd roundrect
			(at -0.321 0.002)
			(size 0.46 0.4)
			(layers "B.Cu" "B.Mask")
			(roundrect_rratio 0.25)
			(net 1 "GND")
			(pintype "passive")
		)
		(pad "2" smd roundrect
			(at 0.32 0.002)
			(size 0.46 0.4)
			(layers "B.Cu" "B.Mask")
			(roundrect_rratio 0.25)
			(net 6 "VCC1V0")
			(pintype "passive")
		)
	)
	(footprint "antmicro-footprints:C_0201"
		(layer "B.Cu")
		(at 104.325 123.625)
		(descr "Capacitor SMD 0201")
		(tags "capacitor SMD 0201")
		(property "Reference" "C171"
			(at 8.175 0.475 0)
			(layer "B.SilkS")
			(effects
				(font
					(size 0.7 0.7)
					(thickness 0.15)
				)
				(justify right bottom mirror)
			)
		)
		(property "Value" "C_470n_0201"
			(at 0 -1.4 0)
			(layer "B.Fab")
			(effects
				(font
					(size 0.7 0.7)
					(thickness 0.15)
				)
				(justify right bottom mirror)
			)
		)
		(property "Datasheet" "https://product.tdk.com/en/search/capacitor/ceramic/mlcc/info?part_no=C0603X5R1A474M030BC"
			(at 0 0 0)
			(layer "F.Fab")
			(hide yes)
			(effects
				(font
					(size 1.27 1.27)
					(thickness 0.15)
				)
			)
		)
		(property "Description" "SMD Multilayer Ceramic Capacitor, 0.47 µF, 10 V, 0201 [0603 Metric], ± 20%, X5R, C"
			(at 0 0 0)
			(layer "F.Fab")
			(hide yes)
			(effects
				(font
					(size 1.27 1.27)
					(thickness 0.15)
				)
			)
		)
		(property "Author" "Antmicro"
			(at 0 0 0)
			(layer "B.Fab")
			(hide yes)
			(effects
				(font
					(size 1 1)
					(thickness 0.15)
				)
				(justify mirror)
			)
		)
		(property "Dielectric" ""
			(at 0 0 0)
			(layer "B.Fab")
			(hide yes)
			(effects
				(font
					(size 1 1)
					(thickness 0.15)
				)
				(justify mirror)
			)
		)
		(property "License" "Apache-2.0"
			(at 0 0 0)
			(layer "B.Fab")
			(hide yes)
			(effects
				(font
					(size 1 1)
					(thickness 0.15)
				)
				(justify mirror)
			)
		)
		(property "MPN" "C0603X5R1A474M030BC"
			(at 0 0 0)
			(layer "B.Fab")
			(hide yes)
			(effects
				(font
					(size 1 1)
					(thickness 0.15)
				)
				(justify mirror)
			)
		)
		(property "Manufacturer" "TDK"
			(at 0 0 0)
			(layer "B.Fab")
			(hide yes)
			(effects
				(font
					(size 1 1)
					(thickness 0.15)
				)
				(justify mirror)
			)
		)
		(property "Public" "False"
			(at 0 0 0)
			(layer "B.Fab")
			(hide yes)
			(effects
				(font
					(size 1 1)
					(thickness 0.15)
				)
				(justify mirror)
			)
		)
		(property "Val" "470n"
			(at 0 0 0)
			(layer "B.Fab")
			(hide yes)
			(effects
				(font
					(size 1 1)
					(thickness 0.15)
				)
				(justify mirror)
			)
		)
		(property "Voltage" ""
			(at 0 0 0)
			(layer "B.Fab")
			(hide yes)
			(effects
				(font
					(size 1 1)
					(thickness 0.15)
				)
				(justify mirror)
			)
		)
		(property "DNP" ""
			(at 0 0 0)
			(unlocked yes)
			(layer "B.Fab")
			(hide yes)
			(effects
				(font
					(size 1 1)
					(thickness 0.15)
				)
				(justify mirror)
			)
		)
		(sheetname "/FPGA power supply/")
		(sheetfile "fpga-power-supply.kicad_sch")
		(attr smd)
		(fp_rect
			(start -0.7 0.35)
			(end 0.7 -0.35)
			(stroke
				(width 0.05)
				(type default)
			)
			(fill no)
			(layer "B.CrtYd")
		)
		(fp_rect
			(start 0.3 -0.15)
			(end -0.301 0.149)
			(stroke
				(width 0.15)
				(type solid)
			)
			(fill no)
			(layer "B.Fab")
		)
		(pad "" smd roundrect
			(at -0.349 0.002)
			(size 0.318 0.36)
			(layers "B.Paste")
			(roundrect_rratio 0.25)
		)
		(pad "" smd roundrect
			(at 0.341 0.002)
			(size 0.318 0.36)
			(layers "B.Paste")
			(roundrect_rratio 0.25)
		)
		(pad "1" smd roundrect
			(at -0.321 0.002)
			(size 0.46 0.4)
			(layers "B.Cu" "B.Mask")
			(roundrect_rratio 0.25)
			(net 1 "GND")
			(pintype "passive")
		)
		(pad "2" smd roundrect
			(at 0.32 0.002)
			(size 0.46 0.4)
			(layers "B.Cu" "B.Mask")
			(roundrect_rratio 0.25)
			(net 6 "VCC1V0")
			(pintype "passive")
		)
	)
	(footprint "antmicro-footprints:C_0201"
		(layer "B.Cu")
		(at 98.275 120.675)
		(descr "Capacitor SMD 0201")
		(tags "capacitor SMD 0201")
		(property "Reference" "C159"
			(at -22.375 0.625 0)
			(layer "B.SilkS")
			(effects
				(font
					(size 0.7 0.7)
					(thickness 0.15)
				)
				(justify right bottom mirror)
			)
		)
		(property "Value" "C_470n_0201"
			(at 0 -1.4 0)
			(layer "B.Fab")
			(effects
				(font
					(size 0.7 0.7)
					(thickness 0.15)
				)
				(justify right bottom mirror)
			)
		)
		(property "Datasheet" "https://product.tdk.com/en/search/capacitor/ceramic/mlcc/info?part_no=C0603X5R1A474M030BC"
			(at 0 0 0)
			(layer "F.Fab")
			(hide yes)
			(effects
				(font
					(size 1.27 1.27)
					(thickness 0.15)
				)
			)
		)
		(property "Description" "SMD Multilayer Ceramic Capacitor, 0.47 µF, 10 V, 0201 [0603 Metric], ± 20%, X5R, C"
			(at 0 0 0)
			(layer "F.Fab")
			(hide yes)
			(effects
				(font
					(size 1.27 1.27)
					(thickness 0.15)
				)
			)
		)
		(property "Author" "Antmicro"
			(at 0 0 0)
			(layer "B.Fab")
			(hide yes)
			(effects
				(font
					(size 1 1)
					(thickness 0.15)
				)
				(justify mirror)
			)
		)
		(property "Dielectric" ""
			(at 0 0 0)
			(layer "B.Fab")
			(hide yes)
			(effects
				(font
					(size 1 1)
					(thickness 0.15)
				)
				(justify mirror)
			)
		)
		(property "License" "Apache-2.0"
			(at 0 0 0)
			(layer "B.Fab")
			(hide yes)
			(effects
				(font
					(size 1 1)
					(thickness 0.15)
				)
				(justify mirror)
			)
		)
		(property "MPN" "C0603X5R1A474M030BC"
			(at 0 0 0)
			(layer "B.Fab")
			(hide yes)
			(effects
				(font
					(size 1 1)
					(thickness 0.15)
				)
				(justify mirror)
			)
		)
		(property "Manufacturer" "TDK"
			(at 0 0 0)
			(layer "B.Fab")
			(hide yes)
			(effects
				(font
					(size 1 1)
					(thickness 0.15)
				)
				(justify mirror)
			)
		)
		(property "Public" "False"
			(at 0 0 0)
			(layer "B.Fab")
			(hide yes)
			(effects
				(font
					(size 1 1)
					(thickness 0.15)
				)
				(justify mirror)
			)
		)
		(property "Val" "470n"
			(at 0 0 0)
			(layer "B.Fab")
			(hide yes)
			(effects
				(font
					(size 1 1)
					(thickness 0.15)
				)
				(justify mirror)
			)
		)
		(property "Voltage" ""
			(at 0 0 0)
			(layer "B.Fab")
			(hide yes)
			(effects
				(font
					(size 1 1)
					(thickness 0.15)
				)
				(justify mirror)
			)
		)
		(property "DNP" ""
			(at 0 0 0)
			(unlocked yes)
			(layer "B.Fab")
			(hide yes)
			(effects
				(font
					(size 1 1)
					(thickness 0.15)
				)
				(justify mirror)
			)
		)
		(sheetname "/FPGA power supply/")
		(sheetfile "fpga-power-supply.kicad_sch")
		(attr smd)
		(fp_rect
			(start -0.7 0.35)
			(end 0.7 -0.35)
			(stroke
				(width 0.05)
				(type default)
			)
			(fill no)
			(layer "B.CrtYd")
		)
		(fp_rect
			(start 0.3 -0.15)
			(end -0.301 0.149)
			(stroke
				(width 0.15)
				(type solid)
			)
			(fill no)
			(layer "B.Fab")
		)
		(pad "" smd roundrect
			(at -0.349 0.002)
			(size 0.318 0.36)
			(layers "B.Paste")
			(roundrect_rratio 0.25)
		)
		(pad "" smd roundrect
			(at 0.341 0.002)
			(size 0.318 0.36)
			(layers "B.Paste")
			(roundrect_rratio 0.25)
		)
		(pad "1" smd roundrect
			(at -0.321 0.002)
			(size 0.46 0.4)
			(layers "B.Cu" "B.Mask")
			(roundrect_rratio 0.25)
			(net 1 "GND")
			(pintype "passive")
		)
		(pad "2" smd roundrect
			(at 0.32 0.002)
			(size 0.46 0.4)
			(layers "B.Cu" "B.Mask")
			(roundrect_rratio 0.25)
			(net 6 "VCC1V0")
			(pintype "passive")
		)
	)
	(footprint "antmicro-footprints:C_0402_1005Metric"
		(layer "B.Cu")
		(at 109.375 110.275 -90)
		(descr "Capacitor SMD 0402")
		(tags "capacitor SMD 0402")
		(property "Reference" "C235"
			(at -1.475 -1.225 90)
			(layer "B.SilkS")
			(effects
				(font
					(size 0.7 0.7)
					(thickness 0.15)
				)
				(justify left bottom mirror)
			)
		)
		(property "Value" "C_470n_0402"
			(at 0 -1.4 90)
			(layer "B.Fab")
			(effects
				(font
					(size 0.7 0.7)
					(thickness 0.15)
				)
				(justify left bottom mirror)
			)
		)
		(property "Datasheet" "https://product.tdk.com/en/search/capacitor/ceramic/mlcc/info?part_no=C1005X5R1E474M050BB"
			(at 0 0 270)
			(layer "F.Fab")
			(hide yes)
			(effects
				(font
					(size 1.27 1.27)
					(thickness 0.15)
				)
			)
		)
		(property "Description" "SMD Multilayer Ceramic Capacitor, 0.47 µF, 25 V, 0402 [1005 Metric], ± 20%, X5R, C"
			(at 0 0 270)
			(layer "F.Fab")
			(hide yes)
			(effects
				(font
					(size 1.27 1.27)
					(thickness 0.15)
				)
			)
		)
		(property "Author" "Antmicro"
			(at -0.9 219.65 0)
			(layer "B.Fab")
			(hide yes)
			(effects
				(font
					(size 1 1)
					(thickness 0.15)
				)
				(justify mirror)
			)
		)
		(property "Dielectric" ""
			(at -0.9 219.65 0)
			(layer "B.Fab")
			(hide yes)
			(effects
				(font
					(size 1 1)
					(thickness 0.15)
				)
				(justify mirror)
			)
		)
		(property "License" "Apache-2.0"
			(at -0.9 219.65 0)
			(layer "B.Fab")
			(hide yes)
			(effects
				(font
					(size 1 1)
					(thickness 0.15)
				)
				(justify mirror)
			)
		)
		(property "MPN" "C1005X5R1E474M050BB"
			(at -0.9 219.65 0)
			(layer "B.Fab")
			(hide yes)
			(effects
				(font
					(size 1 1)
					(thickness 0.15)
				)
				(justify mirror)
			)
		)
		(property "Manufacturer" "TDK"
			(at -0.9 219.65 0)
			(layer "B.Fab")
			(hide yes)
			(effects
				(font
					(size 1 1)
					(thickness 0.15)
				)
				(justify mirror)
			)
		)
		(property "Val" "470n"
			(at -0.9 219.65 0)
			(layer "B.Fab")
			(hide yes)
			(effects
				(font
					(size 1 1)
					(thickness 0.15)
				)
				(justify mirror)
			)
		)
		(property "Voltage" ""
			(at -0.9 219.65 0)
			(layer "B.Fab")
			(hide yes)
			(effects
				(font
					(size 1 1)
					(thickness 0.15)
				)
				(justify mirror)
			)
		)
		(property "DNP" ""
			(at 0 0 270)
			(unlocked yes)
			(layer "B.Fab")
			(hide yes)
			(effects
				(font
					(size 1 1)
					(thickness 0.15)
				)
				(justify mirror)
			)
		)
		(sheetname "/FPGA banks 13-16/")
		(sheetfile "fpga-banks-13-16.kicad_sch")
		(attr smd)
		(fp_rect
			(start -0.925 0.47)
			(end 0.925 -0.47)
			(stroke
				(width 0.05)
				(type default)
			)
			(fill no)
			(layer "B.CrtYd")
		)
		(fp_line
			(start -0.494 0.25)
			(end 0.504 0.25)
			(stroke
				(width 0.15)
				(type solid)
			)
			(layer "B.Fab")
		)
		(fp_line
			(start 0.504 0.25)
			(end 0.504 -0.248)
			(stroke
				(width 0.15)
				(type solid)
			)
			(layer "B.Fab")
		)
		(fp_line
			(start -0.494 -0.248)
			(end -0.494 0.25)
			(stroke
				(width 0.15)
				(type solid)
			)
			(layer "B.Fab")
		)
		(fp_line
			(start 0.504 -0.248)
			(end -0.494 -0.248)
			(stroke
				(width 0.15)
				(type solid)
			)
			(layer "B.Fab")
		)
		(pad "1" smd roundrect
			(at -0.48 0 270)
			(size 0.59 0.64)
			(layers "B.Cu" "B.Mask" "B.Paste")
			(roundrect_rratio 0.25)
			(net 1 "GND")
			(pintype "passive")
		)
		(pad "2" smd roundrect
			(at 0.48 0 270)
			(size 0.59 0.64)
			(layers "B.Cu" "B.Mask" "B.Paste")
			(roundrect_rratio 0.25)
			(net 2 "VCC3V3")
			(pintype "passive")
		)
	)
	(footprint "antmicro-footprints:C_0402_1005Metric"
		(layer "B.Cu")
		(at 103.175 113.075)
		(descr "Capacitor SMD 0402")
		(tags "capacitor SMD 0402")
		(property "Reference" "C236"
			(at -1.475 -0.475 0)
			(layer "B.SilkS")
			(effects
				(font
					(size 0.7 0.7)
					(thickness 0.15)
				)
				(justify right bottom mirror)
			)
		)
		(property "Value" "C_470n_0402"
			(at 0 -1.4 0)
			(layer "B.Fab")
			(effects
				(font
					(size 0.7 0.7)
					(thickness 0.15)
				)
				(justify right bottom mirror)
			)
		)
		(property "Datasheet" "https://product.tdk.com/en/search/capacitor/ceramic/mlcc/info?part_no=C1005X5R1E474M050BB"
			(at 0 0 0)
			(layer "F.Fab")
			(hide yes)
			(effects
				(font
					(size 1.27 1.27)
					(thickness 0.15)
				)
			)
		)
		(property "Description" "SMD Multilayer Ceramic Capacitor, 0.47 µF, 25 V, 0402 [1005 Metric], ± 20%, X5R, C"
			(at 0 0 0)
			(layer "F.Fab")
			(hide yes)
			(effects
				(font
					(size 1.27 1.27)
					(thickness 0.15)
				)
			)
		)
		(property "Author" "Antmicro"
			(at 0 0 0)
			(layer "B.Fab")
			(hide yes)
			(effects
				(font
					(size 1 1)
					(thickness 0.15)
				)
				(justify mirror)
			)
		)
		(property "Dielectric" ""
			(at 0 0 0)
			(layer "B.Fab")
			(hide yes)
			(effects
				(font
					(size 1 1)
					(thickness 0.15)
				)
				(justify mirror)
			)
		)
		(property "License" "Apache-2.0"
			(at 0 0 0)
			(layer "B.Fab")
			(hide yes)
			(effects
				(font
					(size 1 1)
					(thickness 0.15)
				)
				(justify mirror)
			)
		)
		(property "MPN" "C1005X5R1E474M050BB"
			(at 0 0 0)
			(layer "B.Fab")
			(hide yes)
			(effects
				(font
					(size 1 1)
					(thickness 0.15)
				)
				(justify mirror)
			)
		)
		(property "Manufacturer" "TDK"
			(at 0 0 0)
			(layer "B.Fab")
			(hide yes)
			(effects
				(font
					(size 1 1)
					(thickness 0.15)
				)
				(justify mirror)
			)
		)
		(property "Val" "470n"
			(at 0 0 0)
			(layer "B.Fab")
			(hide yes)
			(effects
				(font
					(size 1 1)
					(thickness 0.15)
				)
				(justify mirror)
			)
		)
		(property "Voltage" ""
			(at 0 0 0)
			(layer "B.Fab")
			(hide yes)
			(effects
				(font
					(size 1 1)
					(thickness 0.15)
				)
				(justify mirror)
			)
		)
		(property "DNP" ""
			(at 0 0 0)
			(unlocked yes)
			(layer "B.Fab")
			(hide yes)
			(effects
				(font
					(size 1 1)
					(thickness 0.15)
				)
				(justify mirror)
			)
		)
		(sheetname "/FPGA banks 13-16/")
		(sheetfile "fpga-banks-13-16.kicad_sch")
		(attr smd)
		(fp_rect
			(start -0.925 0.47)
			(end 0.925 -0.47)
			(stroke
				(width 0.05)
				(type default)
			)
			(fill no)
			(layer "B.CrtYd")
		)
		(fp_line
			(start -0.494 -0.248)
			(end -0.494 0.25)
			(stroke
				(width 0.15)
				(type solid)
			)
			(layer "B.Fab")
		)
		(fp_line
			(start -0.494 0.25)
			(end 0.504 0.25)
			(stroke
				(width 0.15)
				(type solid)
			)
			(layer "B.Fab")
		)
		(fp_line
			(start 0.504 -0.248)
			(end -0.494 -0.248)
			(stroke
				(width 0.15)
				(type solid)
			)
			(layer "B.Fab")
		)
		(fp_line
			(start 0.504 0.25)
			(end 0.504 -0.248)
			(stroke
				(width 0.15)
				(type solid)
			)
			(layer "B.Fab")
		)
		(pad "1" smd roundrect
			(at -0.48 0)
			(size 0.59 0.64)
			(layers "B.Cu" "B.Mask" "B.Paste")
			(roundrect_rratio 0.25)
			(net 1 "GND")
			(pintype "passive")
		)
		(pad "2" smd roundrect
			(at 0.48 0)
			(size 0.59 0.64)
			(layers "B.Cu" "B.Mask" "B.Paste")
			(roundrect_rratio 0.25)
			(net 2 "VCC3V3")
			(pintype "passive")
		)
	)
	(footprint "antmicro-footprints:SC70-3"
		(layer "B.Cu")
		(at 81.575 82.075 180)
		(property "Reference" "Q1"
			(at 0.775 -1.325 0)
			(layer "B.SilkS")
			(effects
				(font
					(size 0.7 0.7)
					(thickness 0.15)
				)
				(justify left bottom mirror)
			)
		)
		(property "Value" "BSS138PW"
			(at 0 -2.3 0)
			(layer "B.Fab")
			(effects
				(font
					(size 0.7 0.7)
					(thickness 0.15)
				)
				(justify left bottom mirror)
			)
		)
		(property "Datasheet" "https://assets.nexperia.com/documents/data-sheet/BSS138PW.pdf"
			(at 0 0 180)
			(layer "F.Fab")
			(hide yes)
			(effects
				(font
					(size 1.27 1.27)
					(thickness 0.15)
				)
			)
		)
		(property "Description" "Power MOSFET, N Channel, 60 V, 320 mA, 0.9 ohm, SOT-323, Surface Mount"
			(at 0 0 180)
			(layer "F.Fab")
			(hide yes)
			(effects
				(font
					(size 1.27 1.27)
					(thickness 0.15)
				)
			)
		)
		(property "Author" "Antmicro"
			(at 163.15 164.15 0)
			(layer "B.Fab")
			(hide yes)
			(effects
				(font
					(size 1 1)
					(thickness 0.15)
				)
				(justify mirror)
			)
		)
		(property "License" "Apache-2.0"
			(at 163.15 164.15 0)
			(layer "B.Fab")
			(hide yes)
			(effects
				(font
					(size 1 1)
					(thickness 0.15)
				)
				(justify mirror)
			)
		)
		(property "MPN" "BSS138PW"
			(at 163.15 164.15 0)
			(layer "B.Fab")
			(hide yes)
			(effects
				(font
					(size 1 1)
					(thickness 0.15)
				)
				(justify mirror)
			)
		)
		(property "Manufacturer" "Nexperia"
			(at 163.15 164.15 0)
			(layer "B.Fab")
			(hide yes)
			(effects
				(font
					(size 1 1)
					(thickness 0.15)
				)
				(justify mirror)
			)
		)
		(sheetname "/Power supply/")
		(sheetfile "power-supply.kicad_sch")
		(attr smd)
		(fp_line
			(start 0.627 0.6)
			(end 0.627 0.999)
			(stroke
				(width 0.15)
				(type solid)
			)
			(layer "B.SilkS")
		)
		(fp_line
			(start 0.627 -0.6)
			(end 0.627 -1.001)
			(stroke
				(width 0.15)
				(type solid)
			)
			(layer "B.SilkS")
		)
		(fp_line
			(start -0.3 1)
			(end 0.627 0.999)
			(stroke
				(width 0.15)
				(type solid)
			)
			(layer "B.SilkS")
		)
		(fp_line
			(start -0.3 -1)
			(end 0.627 -1.001)
			(stroke
				(width 0.15)
				(type solid)
			)
			(layer "B.SilkS")
		)
		(fp_line
			(start 1.4 0.4)
			(end 1.4 -0.4)
			(stroke
				(width 0.05)
				(type solid)
			)
			(layer "B.CrtYd")
		)
		(fp_line
			(start 1.4 -0.4)
			(end 0.9 -0.4)
			(stroke
				(width 0.05)
				(type solid)
			)
			(layer "B.CrtYd")
		)
		(fp_line
			(start 0.9 1.3)
			(end 0.9 0.4)
			(stroke
				(width 0.05)
				(type solid)
			)
			(layer "B.CrtYd")
		)
		(fp_line
			(start 0.9 0.4)
			(end 1.4 0.4)
			(stroke
				(width 0.05)
				(type solid)
			)
			(layer "B.CrtYd")
		)
		(fp_line
			(start 0.9 -0.4)
			(end 0.9 -1.3)
			(stroke
				(width 0.05)
				(type solid)
			)
			(layer "B.CrtYd")
		)
		(fp_line
			(start 0.9 -1.3)
			(end -0.9 -1.3)
			(stroke
				(width 0.05)
				(type solid)
			)
			(layer "B.CrtYd")
		)
		(fp_line
			(start -0.9 1.3)
			(end 0.9 1.3)
			(stroke
				(width 0.05)
				(type solid)
			)
			(layer "B.CrtYd")
		)
		(fp_line
			(start -0.9 1.3)
			(end -0.9 1)
			(stroke
				(width 0.05)
				(type solid)
			)
			(layer "B.CrtYd")
		)
		(fp_line
			(start -0.9 1)
			(end -1.4 1)
			(stroke
				(width 0.05)
				(type solid)
			)
			(layer "B.CrtYd")
		)
		(fp_line
			(start -0.9 -1)
			(end -1.4 -1)
			(stroke
				(width 0.05)
				(type solid)
			)
			(layer "B.CrtYd")
		)
		(fp_line
			(start -0.9 -1.3)
			(end -0.9 -1)
			(stroke
				(width 0.05)
				(type solid)
			)
			(layer "B.CrtYd")
		)
		(fp_line
			(start -1.4 -1)
			(end -1.4 1)
			(stroke
				(width 0.05)
				(type solid)
			)
			(layer "B.CrtYd")
		)
		(fp_rect
			(start -0.623 0.999)
			(end 0.627 -1.001)
			(stroke
				(width 0.15)
				(type solid)
			)
			(fill no)
			(layer "B.Fab")
		)
		(pad "1" smd rect
			(at -1.051 0.65 90)
			(size 0.6 0.6)
			(layers "B.Cu" "B.Mask" "B.Paste")
			(net 538 "1V0_PG")
			(pinfunction "G")
			(pintype "input")
		)
		(pad "2" smd rect
			(at -1.051 -0.65 90)
			(size 0.6 0.6)
			(layers "B.Cu" "B.Mask" "B.Paste")
			(net 1 "GND")
			(pinfunction "S")
			(pintype "passive")
		)
		(pad "3" smd rect
			(at 1.05 0 90)
			(size 0.6 0.6)
			(layers "B.Cu" "B.Mask" "B.Paste")
			(net 207 "Net-(D4-C)")
			(pinfunction "D")
			(pintype "passive")
		)
	)
	(footprint "antmicro-footprints:SC70-3"
		(layer "B.Cu")
		(at 78.775 87.875 180)
		(property "Reference" "Q2"
			(at 0.675 -1.325 0)
			(layer "B.SilkS")
			(effects
				(font
					(size 0.7 0.7)
					(thickness 0.15)
				)
				(justify left bottom mirror)
			)
		)
		(property "Value" "BSS138PW"
			(at 0 -2.3 0)
			(layer "B.Fab")
			(effects
				(font
					(size 0.7 0.7)
					(thickness 0.15)
				)
				(justify left bottom mirror)
			)
		)
		(property "Datasheet" "https://assets.nexperia.com/documents/data-sheet/BSS138PW.pdf"
			(at 0 0 180)
			(layer "F.Fab")
			(hide yes)
			(effects
				(font
					(size 1.27 1.27)
					(thickness 0.15)
				)
			)
		)
		(property "Description" "Power MOSFET, N Channel, 60 V, 320 mA, 0.9 ohm, SOT-323, Surface Mount"
			(at 0 0 180)
			(layer "F.Fab")
			(hide yes)
			(effects
				(font
					(size 1.27 1.27)
					(thickness 0.15)
				)
			)
		)
		(property "Author" "Antmicro"
			(at 157.55 175.75 0)
			(layer "B.Fab")
			(hide yes)
			(effects
				(font
					(size 1 1)
					(thickness 0.15)
				)
				(justify mirror)
			)
		)
		(property "License" "Apache-2.0"
			(at 157.55 175.75 0)
			(layer "B.Fab")
			(hide yes)
			(effects
				(font
					(size 1 1)
					(thickness 0.15)
				)
				(justify mirror)
			)
		)
		(property "MPN" "BSS138PW"
			(at 157.55 175.75 0)
			(layer "B.Fab")
			(hide yes)
			(effects
				(font
					(size 1 1)
					(thickness 0.15)
				)
				(justify mirror)
			)
		)
		(property "Manufacturer" "Nexperia"
			(at 157.55 175.75 0)
			(layer "B.Fab")
			(hide yes)
			(effects
				(font
					(size 1 1)
					(thickness 0.15)
				)
				(justify mirror)
			)
		)
		(sheetname "/Power supply/")
		(sheetfile "power-supply.kicad_sch")
		(attr smd)
		(fp_line
			(start 0.627 0.6)
			(end 0.627 0.999)
			(stroke
				(width 0.15)
				(type solid)
			)
			(layer "B.SilkS")
		)
		(fp_line
			(start 0.627 -0.6)
			(end 0.627 -1.001)
			(stroke
				(width 0.15)
				(type solid)
			)
			(layer "B.SilkS")
		)
		(fp_line
			(start -0.3 1)
			(end 0.627 0.999)
			(stroke
				(width 0.15)
				(type solid)
			)
			(layer "B.SilkS")
		)
		(fp_line
			(start -0.3 -1)
			(end 0.627 -1.001)
			(stroke
				(width 0.15)
				(type solid)
			)
			(layer "B.SilkS")
		)
		(fp_line
			(start 1.4 0.4)
			(end 1.4 -0.4)
			(stroke
				(width 0.05)
				(type solid)
			)
			(layer "B.CrtYd")
		)
		(fp_line
			(start 1.4 -0.4)
			(end 0.9 -0.4)
			(stroke
				(width 0.05)
				(type solid)
			)
			(layer "B.CrtYd")
		)
		(fp_line
			(start 0.9 1.3)
			(end 0.9 0.4)
			(stroke
				(width 0.05)
				(type solid)
			)
			(layer "B.CrtYd")
		)
		(fp_line
			(start 0.9 0.4)
			(end 1.4 0.4)
			(stroke
				(width 0.05)
				(type solid)
			)
			(layer "B.CrtYd")
		)
		(fp_line
			(start 0.9 -0.4)
			(end 0.9 -1.3)
			(stroke
				(width 0.05)
				(type solid)
			)
			(layer "B.CrtYd")
		)
		(fp_line
			(start 0.9 -1.3)
			(end -0.9 -1.3)
			(stroke
				(width 0.05)
				(type solid)
			)
			(layer "B.CrtYd")
		)
		(fp_line
			(start -0.9 1.3)
			(end 0.9 1.3)
			(stroke
				(width 0.05)
				(type solid)
			)
			(layer "B.CrtYd")
		)
		(fp_line
			(start -0.9 1.3)
			(end -0.9 1)
			(stroke
				(width 0.05)
				(type solid)
			)
			(layer "B.CrtYd")
		)
		(fp_line
			(start -0.9 1)
			(end -1.4 1)
			(stroke
				(width 0.05)
				(type solid)
			)
			(layer "B.CrtYd")
		)
		(fp_line
			(start -0.9 -1)
			(end -1.4 -1)
			(stroke
				(width 0.05)
				(type solid)
			)
			(layer "B.CrtYd")
		)
		(fp_line
			(start -0.9 -1.3)
			(end -0.9 -1)
			(stroke
				(width 0.05)
				(type solid)
			)
			(layer "B.CrtYd")
		)
		(fp_line
			(start -1.4 -1)
			(end -1.4 1)
			(stroke
				(width 0.05)
				(type solid)
			)
			(layer "B.CrtYd")
		)
		(fp_rect
			(start -0.623 0.999)
			(end 0.627 -1.001)
			(stroke
				(width 0.15)
				(type solid)
			)
			(fill no)
			(layer "B.Fab")
		)
		(pad "1" smd rect
			(at -1.051 0.65 90)
			(size 0.6 0.6)
			(layers "B.Cu" "B.Mask" "B.Paste")
			(net 573 "/Power supply/5V0_PG")
			(pinfunction "G")
			(pintype "input")
		)
		(pad "2" smd rect
			(at -1.051 -0.65 90)
			(size 0.6 0.6)
			(layers "B.Cu" "B.Mask" "B.Paste")
			(net 1 "GND")
			(pinfunction "S")
			(pintype "passive")
		)
		(pad "3" smd rect
			(at 1.05 0 90)
			(size 0.6 0.6)
			(layers "B.Cu" "B.Mask" "B.Paste")
			(net 214 "Net-(D5-C)")
			(pinfunction "D")
			(pintype "passive")
		)
	)
	(footprint "antmicro-footprints:SC70-3"
		(layer "B.Cu")
		(at 81.475 96.675 180)
		(property "Reference" "Q3"
			(at 0.775 -1.325 0)
			(layer "B.SilkS")
			(effects
				(font
					(size 0.7 0.7)
					(thickness 0.15)
				)
				(justify left bottom mirror)
			)
		)
		(property "Value" "BSS138PW"
			(at 0 -2.3 0)
			(layer "B.Fab")
			(effects
				(font
					(size 0.7 0.7)
					(thickness 0.15)
				)
				(justify left bottom mirror)
			)
		)
		(property "Datasheet" "https://assets.nexperia.com/documents/data-sheet/BSS138PW.pdf"
			(at 0 0 180)
			(layer "F.Fab")
			(hide yes)
			(effects
				(font
					(size 1.27 1.27)
					(thickness 0.15)
				)
			)
		)
		(property "Description" "Power MOSFET, N Channel, 60 V, 320 mA, 0.9 ohm, SOT-323, Surface Mount"
			(at 0 0 180)
			(layer "F.Fab")
			(hide yes)
			(effects
				(font
					(size 1.27 1.27)
					(thickness 0.15)
				)
			)
		)
		(property "Author" "Antmicro"
			(at 162.95 193.35 0)
			(layer "B.Fab")
			(hide yes)
			(effects
				(font
					(size 1 1)
					(thickness 0.15)
				)
				(justify mirror)
			)
		)
		(property "License" "Apache-2.0"
			(at 162.95 193.35 0)
			(layer "B.Fab")
			(hide yes)
			(effects
				(font
					(size 1 1)
					(thickness 0.15)
				)
				(justify mirror)
			)
		)
		(property "MPN" "BSS138PW"
			(at 162.95 193.35 0)
			(layer "B.Fab")
			(hide yes)
			(effects
				(font
					(size 1 1)
					(thickness 0.15)
				)
				(justify mirror)
			)
		)
		(property "Manufacturer" "Nexperia"
			(at 162.95 193.35 0)
			(layer "B.Fab")
			(hide yes)
			(effects
				(font
					(size 1 1)
					(thickness 0.15)
				)
				(justify mirror)
			)
		)
		(sheetname "/Power supply/")
		(sheetfile "power-supply.kicad_sch")
		(attr smd)
		(fp_line
			(start 0.627 0.6)
			(end 0.627 0.999)
			(stroke
				(width 0.15)
				(type solid)
			)
			(layer "B.SilkS")
		)
		(fp_line
			(start 0.627 -0.6)
			(end 0.627 -1.001)
			(stroke
				(width 0.15)
				(type solid)
			)
			(layer "B.SilkS")
		)
		(fp_line
			(start -0.3 1)
			(end 0.627 0.999)
			(stroke
				(width 0.15)
				(type solid)
			)
			(layer "B.SilkS")
		)
		(fp_line
			(start -0.3 -1)
			(end 0.627 -1.001)
			(stroke
				(width 0.15)
				(type solid)
			)
			(layer "B.SilkS")
		)
		(fp_line
			(start 1.4 0.4)
			(end 1.4 -0.4)
			(stroke
				(width 0.05)
				(type solid)
			)
			(layer "B.CrtYd")
		)
		(fp_line
			(start 1.4 -0.4)
			(end 0.9 -0.4)
			(stroke
				(width 0.05)
				(type solid)
			)
			(layer "B.CrtYd")
		)
		(fp_line
			(start 0.9 1.3)
			(end 0.9 0.4)
			(stroke
				(width 0.05)
				(type solid)
			)
			(layer "B.CrtYd")
		)
		(fp_line
			(start 0.9 0.4)
			(end 1.4 0.4)
			(stroke
				(width 0.05)
				(type solid)
			)
			(layer "B.CrtYd")
		)
		(fp_line
			(start 0.9 -0.4)
			(end 0.9 -1.3)
			(stroke
				(width 0.05)
				(type solid)
			)
			(layer "B.CrtYd")
		)
		(fp_line
			(start 0.9 -1.3)
			(end -0.9 -1.3)
			(stroke
				(width 0.05)
				(type solid)
			)
			(layer "B.CrtYd")
		)
		(fp_line
			(start -0.9 1.3)
			(end 0.9 1.3)
			(stroke
				(width 0.05)
				(type solid)
			)
			(layer "B.CrtYd")
		)
		(fp_line
			(start -0.9 1.3)
			(end -0.9 1)
			(stroke
				(width 0.05)
				(type solid)
			)
			(layer "B.CrtYd")
		)
		(fp_line
			(start -0.9 1)
			(end -1.4 1)
			(stroke
				(width 0.05)
				(type solid)
			)
			(layer "B.CrtYd")
		)
		(fp_line
			(start -0.9 -1)
			(end -1.4 -1)
			(stroke
				(width 0.05)
				(type solid)
			)
			(layer "B.CrtYd")
		)
		(fp_line
			(start -0.9 -1.3)
			(end -0.9 -1)
			(stroke
				(width 0.05)
				(type solid)
			)
			(layer "B.CrtYd")
		)
		(fp_line
			(start -1.4 -1)
			(end -1.4 1)
			(stroke
				(width 0.05)
				(type solid)
			)
			(layer "B.CrtYd")
		)
		(fp_rect
			(start -0.623 0.999)
			(end 0.627 -1.001)
			(stroke
				(width 0.15)
				(type solid)
			)
			(fill no)
			(layer "B.Fab")
		)
		(pad "1" smd rect
			(at -1.051 0.65 90)
			(size 0.6 0.6)
			(layers "B.Cu" "B.Mask" "B.Paste")
			(net 292 "/Power supply/1V8_PG")
			(pinfunction "G")
			(pintype "input")
		)
		(pad "2" smd rect
			(at -1.051 -0.65 90)
			(size 0.6 0.6)
			(layers "B.Cu" "B.Mask" "B.Paste")
			(net 1 "GND")
			(pinfunction "S")
			(pintype "passive")
		)
		(pad "3" smd rect
			(at 1.05 0 90)
			(size 0.6 0.6)
			(layers "B.Cu" "B.Mask" "B.Paste")
			(net 216 "Net-(D6-C)")
			(pinfunction "D")
			(pintype "passive")
		)
	)
	(footprint "antmicro-footprints:SC70-3"
		(layer "B.Cu")
		(at 81.575 89.275 180)
		(property "Reference" "Q4"
			(at 0.775 -1.225 0)
			(layer "B.SilkS")
			(effects
				(font
					(size 0.7 0.7)
					(thickness 0.15)
				)
				(justify left bottom mirror)
			)
		)
		(property "Value" "BSS138PW"
			(at 0 -2.3 0)
			(layer "B.Fab")
			(effects
				(font
					(size 0.7 0.7)
					(thickness 0.15)
				)
				(justify left bottom mirror)
			)
		)
		(property "Datasheet" "https://assets.nexperia.com/documents/data-sheet/BSS138PW.pdf"
			(at 0 0 180)
			(layer "F.Fab")
			(hide yes)
			(effects
				(font
					(size 1.27 1.27)
					(thickness 0.15)
				)
			)
		)
		(property "Description" "Power MOSFET, N Channel, 60 V, 320 mA, 0.9 ohm, SOT-323, Surface Mount"
			(at 0 0 180)
			(layer "F.Fab")
			(hide yes)
			(effects
				(font
					(size 1.27 1.27)
					(thickness 0.15)
				)
			)
		)
		(property "Author" "Antmicro"
			(at 163.15 178.55 0)
			(layer "B.Fab")
			(hide yes)
			(effects
				(font
					(size 1 1)
					(thickness 0.15)
				)
				(justify mirror)
			)
		)
		(property "License" "Apache-2.0"
			(at 163.15 178.55 0)
			(layer "B.Fab")
			(hide yes)
			(effects
				(font
					(size 1 1)
					(thickness 0.15)
				)
				(justify mirror)
			)
		)
		(property "MPN" "BSS138PW"
			(at 163.15 178.55 0)
			(layer "B.Fab")
			(hide yes)
			(effects
				(font
					(size 1 1)
					(thickness 0.15)
				)
				(justify mirror)
			)
		)
		(property "Manufacturer" "Nexperia"
			(at 163.15 178.55 0)
			(layer "B.Fab")
			(hide yes)
			(effects
				(font
					(size 1 1)
					(thickness 0.15)
				)
				(justify mirror)
			)
		)
		(sheetname "/Power supply/")
		(sheetfile "power-supply.kicad_sch")
		(attr smd)
		(fp_line
			(start 0.627 0.6)
			(end 0.627 0.999)
			(stroke
				(width 0.15)
				(type solid)
			)
			(layer "B.SilkS")
		)
		(fp_line
			(start 0.627 -0.6)
			(end 0.627 -1.001)
			(stroke
				(width 0.15)
				(type solid)
			)
			(layer "B.SilkS")
		)
		(fp_line
			(start -0.3 1)
			(end 0.627 0.999)
			(stroke
				(width 0.15)
				(type solid)
			)
			(layer "B.SilkS")
		)
		(fp_line
			(start -0.3 -1)
			(end 0.627 -1.001)
			(stroke
				(width 0.15)
				(type solid)
			)
			(layer "B.SilkS")
		)
		(fp_line
			(start 1.4 0.4)
			(end 1.4 -0.4)
			(stroke
				(width 0.05)
				(type solid)
			)
			(layer "B.CrtYd")
		)
		(fp_line
			(start 1.4 -0.4)
			(end 0.9 -0.4)
			(stroke
				(width 0.05)
				(type solid)
			)
			(layer "B.CrtYd")
		)
		(fp_line
			(start 0.9 1.3)
			(end 0.9 0.4)
			(stroke
				(width 0.05)
				(type solid)
			)
			(layer "B.CrtYd")
		)
		(fp_line
			(start 0.9 0.4)
			(end 1.4 0.4)
			(stroke
				(width 0.05)
				(type solid)
			)
			(layer "B.CrtYd")
		)
		(fp_line
			(start 0.9 -0.4)
			(end 0.9 -1.3)
			(stroke
				(width 0.05)
				(type solid)
			)
			(layer "B.CrtYd")
		)
		(fp_line
			(start 0.9 -1.3)
			(end -0.9 -1.3)
			(stroke
				(width 0.05)
				(type solid)
			)
			(layer "B.CrtYd")
		)
		(fp_line
			(start -0.9 1.3)
			(end 0.9 1.3)
			(stroke
				(width 0.05)
				(type solid)
			)
			(layer "B.CrtYd")
		)
		(fp_line
			(start -0.9 1.3)
			(end -0.9 1)
			(stroke
				(width 0.05)
				(type solid)
			)
			(layer "B.CrtYd")
		)
		(fp_line
			(start -0.9 1)
			(end -1.4 1)
			(stroke
				(width 0.05)
				(type solid)
			)
			(layer "B.CrtYd")
		)
		(fp_line
			(start -0.9 -1)
			(end -1.4 -1)
			(stroke
				(width 0.05)
				(type solid)
			)
			(layer "B.CrtYd")
		)
		(fp_line
			(start -0.9 -1.3)
			(end -0.9 -1)
			(stroke
				(width 0.05)
				(type solid)
			)
			(layer "B.CrtYd")
		)
		(fp_line
			(start -1.4 -1)
			(end -1.4 1)
			(stroke
				(width 0.05)
				(type solid)
			)
			(layer "B.CrtYd")
		)
		(fp_rect
			(start -0.623 0.999)
			(end 0.627 -1.001)
			(stroke
				(width 0.15)
				(type solid)
			)
			(fill no)
			(layer "B.Fab")
		)
		(pad "1" smd rect
			(at -1.051 0.65 90)
			(size 0.6 0.6)
			(layers "B.Cu" "B.Mask" "B.Paste")
			(net 293 "/Power supply/1V35_PG")
			(pinfunction "G")
			(pintype "input")
		)
		(pad "2" smd rect
			(at -1.051 -0.65 90)
			(size 0.6 0.6)
			(layers "B.Cu" "B.Mask" "B.Paste")
			(net 1 "GND")
			(pinfunction "S")
			(pintype "passive")
		)
		(pad "3" smd rect
			(at 1.05 0 90)
			(size 0.6 0.6)
			(layers "B.Cu" "B.Mask" "B.Paste")
			(net 218 "Net-(D7-C)")
			(pinfunction "D")
			(pintype "passive")
		)
	)
	(footprint "antmicro-footprints:SC70-3"
		(layer "B.Cu")
		(at 81.475 103.975 180)
		(property "Reference" "Q5"
			(at 0.775 -1.325 0)
			(layer "B.SilkS")
			(effects
				(font
					(size 0.7 0.7)
					(thickness 0.15)
				)
				(justify left bottom mirror)
			)
		)
		(property "Value" "BSS138PW"
			(at 0 -2.3 0)
			(layer "B.Fab")
			(effects
				(font
					(size 0.7 0.7)
					(thickness 0.15)
				)
				(justify left bottom mirror)
			)
		)
		(property "Datasheet" "https://assets.nexperia.com/documents/data-sheet/BSS138PW.pdf"
			(at 0 0 180)
			(layer "F.Fab")
			(hide yes)
			(effects
				(font
					(size 1.27 1.27)
					(thickness 0.15)
				)
			)
		)
		(property "Description" "Power MOSFET, N Channel, 60 V, 320 mA, 0.9 ohm, SOT-323, Surface Mount"
			(at 0 0 180)
			(layer "F.Fab")
			(hide yes)
			(effects
				(font
					(size 1.27 1.27)
					(thickness 0.15)
				)
			)
		)
		(property "Author" "Antmicro"
			(at 162.95 207.95 0)
			(layer "B.Fab")
			(hide yes)
			(effects
				(font
					(size 1 1)
					(thickness 0.15)
				)
				(justify mirror)
			)
		)
		(property "License" "Apache-2.0"
			(at 162.95 207.95 0)
			(layer "B.Fab")
			(hide yes)
			(effects
				(font
					(size 1 1)
					(thickness 0.15)
				)
				(justify mirror)
			)
		)
		(property "MPN" "BSS138PW"
			(at 162.95 207.95 0)
			(layer "B.Fab")
			(hide yes)
			(effects
				(font
					(size 1 1)
					(thickness 0.15)
				)
				(justify mirror)
			)
		)
		(property "Manufacturer" "Nexperia"
			(at 162.95 207.95 0)
			(layer "B.Fab")
			(hide yes)
			(effects
				(font
					(size 1 1)
					(thickness 0.15)
				)
				(justify mirror)
			)
		)
		(sheetname "/Power supply/")
		(sheetfile "power-supply.kicad_sch")
		(attr smd)
		(fp_line
			(start 0.627 0.6)
			(end 0.627 0.999)
			(stroke
				(width 0.15)
				(type solid)
			)
			(layer "B.SilkS")
		)
		(fp_line
			(start 0.627 -0.6)
			(end 0.627 -1.001)
			(stroke
				(width 0.15)
				(type solid)
			)
			(layer "B.SilkS")
		)
		(fp_line
			(start -0.3 1)
			(end 0.627 0.999)
			(stroke
				(width 0.15)
				(type solid)
			)
			(layer "B.SilkS")
		)
		(fp_line
			(start -0.3 -1)
			(end 0.627 -1.001)
			(stroke
				(width 0.15)
				(type solid)
			)
			(layer "B.SilkS")
		)
		(fp_line
			(start 1.4 0.4)
			(end 1.4 -0.4)
			(stroke
				(width 0.05)
				(type solid)
			)
			(layer "B.CrtYd")
		)
		(fp_line
			(start 1.4 -0.4)
			(end 0.9 -0.4)
			(stroke
				(width 0.05)
				(type solid)
			)
			(layer "B.CrtYd")
		)
		(fp_line
			(start 0.9 1.3)
			(end 0.9 0.4)
			(stroke
				(width 0.05)
				(type solid)
			)
			(layer "B.CrtYd")
		)
		(fp_line
			(start 0.9 0.4)
			(end 1.4 0.4)
			(stroke
				(width 0.05)
				(type solid)
			)
			(layer "B.CrtYd")
		)
		(fp_line
			(start 0.9 -0.4)
			(end 0.9 -1.3)
			(stroke
				(width 0.05)
				(type solid)
			)
			(layer "B.CrtYd")
		)
		(fp_line
			(start 0.9 -1.3)
			(end -0.9 -1.3)
			(stroke
				(width 0.05)
				(type solid)
			)
			(layer "B.CrtYd")
		)
		(fp_line
			(start -0.9 1.3)
			(end 0.9 1.3)
			(stroke
				(width 0.05)
				(type solid)
			)
			(layer "B.CrtYd")
		)
		(fp_line
			(start -0.9 1.3)
			(end -0.9 1)
			(stroke
				(width 0.05)
				(type solid)
			)
			(layer "B.CrtYd")
		)
		(fp_line
			(start -0.9 1)
			(end -1.4 1)
			(stroke
				(width 0.05)
				(type solid)
			)
			(layer "B.CrtYd")
		)
		(fp_line
			(start -0.9 -1)
			(end -1.4 -1)
			(stroke
				(width 0.05)
				(type solid)
			)
			(layer "B.CrtYd")
		)
		(fp_line
			(start -0.9 -1.3)
			(end -0.9 -1)
			(stroke
				(width 0.05)
				(type solid)
			)
			(layer "B.CrtYd")
		)
		(fp_line
			(start -1.4 -1)
			(end -1.4 1)
			(stroke
				(width 0.05)
				(type solid)
			)
			(layer "B.CrtYd")
		)
		(fp_rect
			(start -0.623 0.999)
			(end 0.627 -1.001)
			(stroke
				(width 0.15)
				(type solid)
			)
			(fill no)
			(layer "B.Fab")
		)
		(pad "1" smd rect
			(at -1.051 0.65 90)
			(size 0.6 0.6)
			(layers "B.Cu" "B.Mask" "B.Paste")
			(net 294 "/Power supply/2V5_PG")
			(pinfunction "G")
			(pintype "input")
		)
		(pad "2" smd rect
			(at -1.051 -0.65 90)
			(size 0.6 0.6)
			(layers "B.Cu" "B.Mask" "B.Paste")
			(net 1 "GND")
			(pinfunction "S")
			(pintype "passive")
		)
		(pad "3" smd rect
			(at 1.05 0 90)
			(size 0.6 0.6)
			(layers "B.Cu" "B.Mask" "B.Paste")
			(net 223 "Net-(D8-C)")
			(pinfunction "D")
			(pintype "passive")
		)
	)
	(footprint "antmicro-footprints:C_0402_1005Metric"
		(layer "B.Cu")
		(at 111.175 117.675)
		(descr "Capacitor SMD 0402")
		(tags "capacitor SMD 0402")
		(property "Reference" "C115"
			(at 0.825 0.425 0)
			(layer "B.SilkS")
			(effects
				(font
					(size 0.7 0.7)
					(thickness 0.15)
				)
				(justify right bottom mirror)
			)
		)
		(property "Value" "C_470n_0402"
			(at 0 -1.4 0)
			(layer "B.Fab")
			(effects
				(font
					(size 0.7 0.7)
					(thickness 0.15)
				)
				(justify right bottom mirror)
			)
		)
		(property "Datasheet" "https://product.tdk.com/en/search/capacitor/ceramic/mlcc/info?part_no=C1005X5R1E474M050BB"
			(at 0 0 0)
			(layer "F.Fab")
			(hide yes)
			(effects
				(font
					(size 1.27 1.27)
					(thickness 0.15)
				)
			)
		)
		(property "Description" "SMD Multilayer Ceramic Capacitor, 0.47 µF, 25 V, 0402 [1005 Metric], ± 20%, X5R, C"
			(at 0 0 0)
			(layer "F.Fab")
			(hide yes)
			(effects
				(font
					(size 1.27 1.27)
					(thickness 0.15)
				)
			)
		)
		(property "Author" "Antmicro"
			(at 0 0 0)
			(layer "B.Fab")
			(hide yes)
			(effects
				(font
					(size 1 1)
					(thickness 0.15)
				)
				(justify mirror)
			)
		)
		(property "Dielectric" ""
			(at 0 0 0)
			(layer "B.Fab")
			(hide yes)
			(effects
				(font
					(size 1 1)
					(thickness 0.15)
				)
				(justify mirror)
			)
		)
		(property "License" "Apache-2.0"
			(at 0 0 0)
			(layer "B.Fab")
			(hide yes)
			(effects
				(font
					(size 1 1)
					(thickness 0.15)
				)
				(justify mirror)
			)
		)
		(property "MPN" "C1005X5R1E474M050BB"
			(at 0 0 0)
			(layer "B.Fab")
			(hide yes)
			(effects
				(font
					(size 1 1)
					(thickness 0.15)
				)
				(justify mirror)
			)
		)
		(property "Manufacturer" "TDK"
			(at 0 0 0)
			(layer "B.Fab")
			(hide yes)
			(effects
				(font
					(size 1 1)
					(thickness 0.15)
				)
				(justify mirror)
			)
		)
		(property "Val" "470n"
			(at 0 0 0)
			(layer "B.Fab")
			(hide yes)
			(effects
				(font
					(size 1 1)
					(thickness 0.15)
				)
				(justify mirror)
			)
		)
		(property "Voltage" ""
			(at 0 0 0)
			(layer "B.Fab")
			(hide yes)
			(effects
				(font
					(size 1 1)
					(thickness 0.15)
				)
				(justify mirror)
			)
		)
		(sheetname "/FPGA banks 34-35 & CFG/")
		(sheetfile "fpga-banks-34-25-cfg.kicad_sch")
		(attr smd)
		(fp_rect
			(start -0.925 0.47)
			(end 0.925 -0.47)
			(stroke
				(width 0.05)
				(type default)
			)
			(fill no)
			(layer "B.CrtYd")
		)
		(fp_line
			(start -0.494 -0.248)
			(end -0.494 0.25)
			(stroke
				(width 0.15)
				(type solid)
			)
			(layer "B.Fab")
		)
		(fp_line
			(start -0.494 0.25)
			(end 0.504 0.25)
			(stroke
				(width 0.15)
				(type solid)
			)
			(layer "B.Fab")
		)
		(fp_line
			(start 0.504 -0.248)
			(end -0.494 -0.248)
			(stroke
				(width 0.15)
				(type solid)
			)
			(layer "B.Fab")
		)
		(fp_line
			(start 0.504 0.25)
			(end 0.504 -0.248)
			(stroke
				(width 0.15)
				(type solid)
			)
			(layer "B.Fab")
		)
		(pad "1" smd roundrect
			(at -0.48 0)
			(size 0.59 0.64)
			(layers "B.Cu" "B.Mask" "B.Paste")
			(roundrect_rratio 0.25)
			(net 1 "GND")
			(pintype "passive")
		)
		(pad "2" smd roundrect
			(at 0.48 0)
			(size 0.59 0.64)
			(layers "B.Cu" "B.Mask" "B.Paste")
			(roundrect_rratio 0.25)
			(net 2 "VCC3V3")
			(pintype "passive")
		)
	)
	(footprint "antmicro-footprints:R_0402_1005Metric"
		(layer "B.Cu")
		(at 98.175 149.675 -90)
		(descr "Resistor SMD 0402")
		(tags "resistor SMD 0402")
		(property "Reference" "R55"
			(at 2.525 -0.425 90)
			(layer "B.SilkS")
			(effects
				(font
					(size 0.7 0.7)
					(thickness 0.15)
				)
				(justify left bottom mirror)
			)
		)
		(property "Value" "R_51R_0402"
			(at 0 -1.4 90)
			(layer "B.Fab")
			(effects
				(font
					(size 0.7 0.7)
					(thickness 0.15)
				)
				(justify left bottom mirror)
			)
		)
		(property "Datasheet" "https://www.bourns.com/docs/product-datasheets/cr.pdf"
			(at 0 0 270)
			(layer "F.Fab")
			(hide yes)
			(effects
				(font
					(size 1.27 1.27)
					(thickness 0.15)
				)
			)
		)
		(property "Description" "SMD Chip Resistor, 51 ohm, ± 1%, 63 mW, 0402 [1005 Metric], Thick Film, General Purpose"
			(at 0 0 270)
			(layer "F.Fab")
			(hide yes)
			(effects
				(font
					(size 1.27 1.27)
					(thickness 0.15)
				)
			)
		)
		(property "Author" "Antmicro"
			(at -51.5 247.85 0)
			(layer "B.Fab")
			(hide yes)
			(effects
				(font
					(size 1 1)
					(thickness 0.15)
				)
				(justify mirror)
			)
		)
		(property "License" "Apache-2.0"
			(at -51.5 247.85 0)
			(layer "B.Fab")
			(hide yes)
			(effects
				(font
					(size 1 1)
					(thickness 0.15)
				)
				(justify mirror)
			)
		)
		(property "MPN" "CR0402-FX-51R0GLF"
			(at -51.5 247.85 0)
			(layer "B.Fab")
			(hide yes)
			(effects
				(font
					(size 1 1)
					(thickness 0.15)
				)
				(justify mirror)
			)
		)
		(property "Manufacturer" "Bourns"
			(at -51.5 247.85 0)
			(layer "B.Fab")
			(hide yes)
			(effects
				(font
					(size 1 1)
					(thickness 0.15)
				)
				(justify mirror)
			)
		)
		(property "Tolerance" "1%"
			(at -51.5 247.85 0)
			(layer "B.Fab")
			(hide yes)
			(effects
				(font
					(size 1 1)
					(thickness 0.15)
				)
				(justify mirror)
			)
		)
		(property "Val" "51R"
			(at -51.5 247.85 0)
			(layer "B.Fab")
			(hide yes)
			(effects
				(font
					(size 1 1)
					(thickness 0.15)
				)
				(justify mirror)
			)
		)
		(sheetname "/DDR3/")
		(sheetfile "ddr3.kicad_sch")
		(attr smd exclude_from_pos_files exclude_from_bom dnp)
		(fp_rect
			(start -0.925 0.47)
			(end 0.925 -0.47)
			(stroke
				(width 0.05)
				(type default)
			)
			(fill no)
			(layer "B.CrtYd")
		)
		(fp_rect
			(start -0.5 0.25)
			(end 0.5 -0.25)
			(stroke
				(width 0.15)
				(type solid)
			)
			(fill no)
			(layer "B.Fab")
		)
		(pad "1" smd roundrect
			(at -0.48 0 270)
			(size 0.59 0.64)
			(layers "B.Cu" "B.Mask" "B.Paste")
			(roundrect_rratio 0.25)
			(net 166 "DDR3_CAS")
			(pintype "passive")
		)
		(pad "2" smd roundrect
			(at 0.48 0 270)
			(size 0.59 0.64)
			(layers "B.Cu" "B.Mask" "B.Paste")
			(roundrect_rratio 0.25)
			(net 143 "/DDR3/DDR3_VTT")
			(pintype "passive")
		)
	)
	(footprint "antmicro-footprints:R_0402_1005Metric"
		(layer "B.Cu")
		(at 99.075 146.375 90)
		(descr "Resistor SMD 0402")
		(tags "resistor SMD 0402")
		(property "Reference" "R56"
			(at 1.274 -8.675 90)
			(layer "B.SilkS")
			(effects
				(font
					(size 0.7 0.7)
					(thickness 0.15)
				)
				(justify right bottom mirror)
			)
		)
		(property "Value" "R_51R_0402"
			(at 0 -1.4 90)
			(layer "B.Fab")
			(effects
				(font
					(size 0.7 0.7)
					(thickness 0.15)
				)
				(justify right bottom mirror)
			)
		)
		(property "Datasheet" "https://www.bourns.com/docs/product-datasheets/cr.pdf"
			(at 0 0 90)
			(layer "F.Fab")
			(hide yes)
			(effects
				(font
					(size 1.27 1.27)
					(thickness 0.15)
				)
			)
		)
		(property "Description" "SMD Chip Resistor, 51 ohm, ± 1%, 63 mW, 0402 [1005 Metric], Thick Film, General Purpose"
			(at 0 0 90)
			(layer "F.Fab")
			(hide yes)
			(effects
				(font
					(size 1.27 1.27)
					(thickness 0.15)
				)
			)
		)
		(property "Author" "Antmicro"
			(at 245.45 47.3 0)
			(layer "B.Fab")
			(hide yes)
			(effects
				(font
					(size 1 1)
					(thickness 0.15)
				)
				(justify mirror)
			)
		)
		(property "License" "Apache-2.0"
			(at 245.45 47.3 0)
			(layer "B.Fab")
			(hide yes)
			(effects
				(font
					(size 1 1)
					(thickness 0.15)
				)
				(justify mirror)
			)
		)
		(property "MPN" "CR0402-FX-51R0GLF"
			(at 245.45 47.3 0)
			(layer "B.Fab")
			(hide yes)
			(effects
				(font
					(size 1 1)
					(thickness 0.15)
				)
				(justify mirror)
			)
		)
		(property "Manufacturer" "Bourns"
			(at 245.45 47.3 0)
			(layer "B.Fab")
			(hide yes)
			(effects
				(font
					(size 1 1)
					(thickness 0.15)
				)
				(justify mirror)
			)
		)
		(property "Tolerance" "1%"
			(at 245.45 47.3 0)
			(layer "B.Fab")
			(hide yes)
			(effects
				(font
					(size 1 1)
					(thickness 0.15)
				)
				(justify mirror)
			)
		)
		(property "Val" "51R"
			(at 245.45 47.3 0)
			(layer "B.Fab")
			(hide yes)
			(effects
				(font
					(size 1 1)
					(thickness 0.15)
				)
				(justify mirror)
			)
		)
		(sheetname "/DDR3/")
		(sheetfile "ddr3.kicad_sch")
		(attr smd exclude_from_pos_files exclude_from_bom dnp)
		(fp_rect
			(start -0.925 0.47)
			(end 0.925 -0.47)
			(stroke
				(width 0.05)
				(type default)
			)
			(fill no)
			(layer "B.CrtYd")
		)
		(fp_rect
			(start -0.5 0.25)
			(end 0.5 -0.25)
			(stroke
				(width 0.15)
				(type solid)
			)
			(fill no)
			(layer "B.Fab")
		)
		(pad "1" smd roundrect
			(at -0.48 0 90)
			(size 0.59 0.64)
			(layers "B.Cu" "B.Mask" "B.Paste")
			(roundrect_rratio 0.25)
			(net 161 "DDR3_ODT")
			(pintype "passive")
		)
		(pad "2" smd roundrect
			(at 0.48 0 90)
			(size 0.59 0.64)
			(layers "B.Cu" "B.Mask" "B.Paste")
			(roundrect_rratio 0.25)
			(net 143 "/DDR3/DDR3_VTT")
			(pintype "passive")
		)
	)
	(footprint "antmicro-footprints:R_0402_1005Metric"
		(layer "B.Cu")
		(at 99.175 149.675 -90)
		(descr "Resistor SMD 0402")
		(tags "resistor SMD 0402")
		(property "Reference" "R162"
			(at 2.525 -0.425 90)
			(layer "B.SilkS")
			(effects
				(font
					(size 0.7 0.7)
					(thickness 0.15)
				)
				(justify left bottom mirror)
			)
		)
		(property "Value" "R_51R_0402"
			(at 0 -1.4 90)
			(layer "B.Fab")
			(effects
				(font
					(size 0.7 0.7)
					(thickness 0.15)
				)
				(justify left bottom mirror)
			)
		)
		(property "Datasheet" "https://www.bourns.com/docs/product-datasheets/cr.pdf"
			(at 0 0 270)
			(layer "F.Fab")
			(hide yes)
			(effects
				(font
					(size 1.27 1.27)
					(thickness 0.15)
				)
			)
		)
		(property "Description" "SMD Chip Resistor, 51 ohm, ± 1%, 63 mW, 0402 [1005 Metric], Thick Film, General Purpose"
			(at 0 0 270)
			(layer "F.Fab")
			(hide yes)
			(effects
				(font
					(size 1.27 1.27)
					(thickness 0.15)
				)
			)
		)
		(property "Author" "Antmicro"
			(at -50.5 248.85 0)
			(layer "B.Fab")
			(hide yes)
			(effects
				(font
					(size 1 1)
					(thickness 0.15)
				)
				(justify mirror)
			)
		)
		(property "License" "Apache-2.0"
			(at -50.5 248.85 0)
			(layer "B.Fab")
			(hide yes)
			(effects
				(font
					(size 1 1)
					(thickness 0.15)
				)
				(justify mirror)
			)
		)
		(property "MPN" "CR0402-FX-51R0GLF"
			(at -50.5 248.85 0)
			(layer "B.Fab")
			(hide yes)
			(effects
				(font
					(size 1 1)
					(thickness 0.15)
				)
				(justify mirror)
			)
		)
		(property "Manufacturer" "Bourns"
			(at -50.5 248.85 0)
			(layer "B.Fab")
			(hide yes)
			(effects
				(font
					(size 1 1)
					(thickness 0.15)
				)
				(justify mirror)
			)
		)
		(property "Tolerance" "1%"
			(at -50.5 248.85 0)
			(layer "B.Fab")
			(hide yes)
			(effects
				(font
					(size 1 1)
					(thickness 0.15)
				)
				(justify mirror)
			)
		)
		(property "Val" "51R"
			(at -50.5 248.85 0)
			(layer "B.Fab")
			(hide yes)
			(effects
				(font
					(size 1 1)
					(thickness 0.15)
				)
				(justify mirror)
			)
		)
		(sheetname "/DDR3/")
		(sheetfile "ddr3.kicad_sch")
		(attr smd exclude_from_pos_files exclude_from_bom dnp)
		(fp_rect
			(start -0.925 0.47)
			(end 0.925 -0.47)
			(stroke
				(width 0.05)
				(type default)
			)
			(fill no)
			(layer "B.CrtYd")
		)
		(fp_rect
			(start -0.5 0.25)
			(end 0.5 -0.25)
			(stroke
				(width 0.15)
				(type solid)
			)
			(fill no)
			(layer "B.Fab")
		)
		(pad "1" smd roundrect
			(at -0.48 0 270)
			(size 0.59 0.64)
			(layers "B.Cu" "B.Mask" "B.Paste")
			(roundrect_rratio 0.25)
			(net 153 "DDR3_WE")
			(pintype "passive")
		)
		(pad "2" smd roundrect
			(at 0.48 0 270)
			(size 0.59 0.64)
			(layers "B.Cu" "B.Mask" "B.Paste")
			(roundrect_rratio 0.25)
			(net 143 "/DDR3/DDR3_VTT")
			(pintype "passive")
		)
	)
	(footprint "antmicro-footprints:R_0402_1005Metric"
		(layer "B.Cu")
		(at 100.075 146.375 90)
		(descr "Resistor SMD 0402")
		(tags "resistor SMD 0402")
		(property "Reference" "R163"
			(at 1.274 -8.675 90)
			(layer "B.SilkS")
			(effects
				(font
					(size 0.7 0.7)
					(thickness 0.15)
				)
				(justify right bottom mirror)
			)
		)
		(property "Value" "R_51R_0402"
			(at 0 -1.4 90)
			(layer "B.Fab")
			(effects
				(font
					(size 0.7 0.7)
					(thickness 0.15)
				)
				(justify right bottom mirror)
			)
		)
		(property "Datasheet" "https://www.bourns.com/docs/product-datasheets/cr.pdf"
			(at 0 0 90)
			(layer "F.Fab")
			(hide yes)
			(effects
				(font
					(size 1.27 1.27)
					(thickness 0.15)
				)
			)
		)
		(property "Description" "SMD Chip Resistor, 51 ohm, ± 1%, 63 mW, 0402 [1005 Metric], Thick Film, General Purpose"
			(at 0 0 90)
			(layer "F.Fab")
			(hide yes)
			(effects
				(font
					(size 1.27 1.27)
					(thickness 0.15)
				)
			)
		)
		(property "Author" "Antmicro"
			(at 246.45 46.3 0)
			(layer "B.Fab")
			(hide yes)
			(effects
				(font
					(size 1 1)
					(thickness 0.15)
				)
				(justify mirror)
			)
		)
		(property "License" "Apache-2.0"
			(at 246.45 46.3 0)
			(layer "B.Fab")
			(hide yes)
			(effects
				(font
					(size 1 1)
					(thickness 0.15)
				)
				(justify mirror)
			)
		)
		(property "MPN" "CR0402-FX-51R0GLF"
			(at 246.45 46.3 0)
			(layer "B.Fab")
			(hide yes)
			(effects
				(font
					(size 1 1)
					(thickness 0.15)
				)
				(justify mirror)
			)
		)
		(property "Manufacturer" "Bourns"
			(at 246.45 46.3 0)
			(layer "B.Fab")
			(hide yes)
			(effects
				(font
					(size 1 1)
					(thickness 0.15)
				)
				(justify mirror)
			)
		)
		(property "Tolerance" "1%"
			(at 246.45 46.3 0)
			(layer "B.Fab")
			(hide yes)
			(effects
				(font
					(size 1 1)
					(thickness 0.15)
				)
				(justify mirror)
			)
		)
		(property "Val" "51R"
			(at 246.45 46.3 0)
			(layer "B.Fab")
			(hide yes)
			(effects
				(font
					(size 1 1)
					(thickness 0.15)
				)
				(justify mirror)
			)
		)
		(sheetname "/DDR3/")
		(sheetfile "ddr3.kicad_sch")
		(attr smd exclude_from_pos_files exclude_from_bom dnp)
		(fp_rect
			(start -0.925 0.47)
			(end 0.925 -0.47)
			(stroke
				(width 0.05)
				(type default)
			)
			(fill no)
			(layer "B.CrtYd")
		)
		(fp_rect
			(start -0.5 0.25)
			(end 0.5 -0.25)
			(stroke
				(width 0.15)
				(type solid)
			)
			(fill no)
			(layer "B.Fab")
		)
		(pad "1" smd roundrect
			(at -0.48 0 90)
			(size 0.59 0.64)
			(layers "B.Cu" "B.Mask" "B.Paste")
			(roundrect_rratio 0.25)
			(net 164 "DDR3_BA0")
			(pintype "passive")
		)
		(pad "2" smd roundrect
			(at 0.48 0 90)
			(size 0.59 0.64)
			(layers "B.Cu" "B.Mask" "B.Paste")
			(roundrect_rratio 0.25)
			(net 143 "/DDR3/DDR3_VTT")
			(pintype "passive")
		)
	)
	(footprint "antmicro-footprints:R_0402_1005Metric"
		(layer "B.Cu")
		(at 100.175 149.675 -90)
		(descr "Resistor SMD 0402")
		(tags "resistor SMD 0402")
		(property "Reference" "R164"
			(at 2.525 -0.425 90)
			(layer "B.SilkS")
			(effects
				(font
					(size 0.7 0.7)
					(thickness 0.15)
				)
				(justify left bottom mirror)
			)
		)
		(property "Value" "R_51R_0402"
			(at 0 -1.4 90)
			(layer "B.Fab")
			(effects
				(font
					(size 0.7 0.7)
					(thickness 0.15)
				)
				(justify left bottom mirror)
			)
		)
		(property "Datasheet" "https://www.bourns.com/docs/product-datasheets/cr.pdf"
			(at 0 0 270)
			(layer "F.Fab")
			(hide yes)
			(effects
				(font
					(size 1.27 1.27)
					(thickness 0.15)
				)
			)
		)
		(property "Description" "SMD Chip Resistor, 51 ohm, ± 1%, 63 mW, 0402 [1005 Metric], Thick Film, General Purpose"
			(at 0 0 270)
			(layer "F.Fab")
			(hide yes)
			(effects
				(font
					(size 1.27 1.27)
					(thickness 0.15)
				)
			)
		)
		(property "Author" "Antmicro"
			(at -49.5 249.85 0)
			(layer "B.Fab")
			(hide yes)
			(effects
				(font
					(size 1 1)
					(thickness 0.15)
				)
				(justify mirror)
			)
		)
		(property "License" "Apache-2.0"
			(at -49.5 249.85 0)
			(layer "B.Fab")
			(hide yes)
			(effects
				(font
					(size 1 1)
					(thickness 0.15)
				)
				(justify mirror)
			)
		)
		(property "MPN" "CR0402-FX-51R0GLF"
			(at -49.5 249.85 0)
			(layer "B.Fab")
			(hide yes)
			(effects
				(font
					(size 1 1)
					(thickness 0.15)
				)
				(justify mirror)
			)
		)
		(property "Manufacturer" "Bourns"
			(at -49.5 249.85 0)
			(layer "B.Fab")
			(hide yes)
			(effects
				(font
					(size 1 1)
					(thickness 0.15)
				)
				(justify mirror)
			)
		)
		(property "Tolerance" "1%"
			(at -49.5 249.85 0)
			(layer "B.Fab")
			(hide yes)
			(effects
				(font
					(size 1 1)
					(thickness 0.15)
				)
				(justify mirror)
			)
		)
		(property "Val" "51R"
			(at -49.5 249.85 0)
			(layer "B.Fab")
			(hide yes)
			(effects
				(font
					(size 1 1)
					(thickness 0.15)
				)
				(justify mirror)
			)
		)
		(sheetname "/DDR3/")
		(sheetfile "ddr3.kicad_sch")
		(attr smd exclude_from_pos_files exclude_from_bom dnp)
		(fp_rect
			(start -0.925 0.47)
			(end 0.925 -0.47)
			(stroke
				(width 0.05)
				(type default)
			)
			(fill no)
			(layer "B.CrtYd")
		)
		(fp_rect
			(start -0.5 0.25)
			(end 0.5 -0.25)
			(stroke
				(width 0.15)
				(type solid)
			)
			(fill no)
			(layer "B.Fab")
		)
		(pad "1" smd roundrect
			(at -0.48 0 270)
			(size 0.59 0.64)
			(layers "B.Cu" "B.Mask" "B.Paste")
			(roundrect_rratio 0.25)
			(net 152 "DDR3_BA2")
			(pintype "passive")
		)
		(pad "2" smd roundrect
			(at 0.48 0 270)
			(size 0.59 0.64)
			(layers "B.Cu" "B.Mask" "B.Paste")
			(roundrect_rratio 0.25)
			(net 143 "/DDR3/DDR3_VTT")
			(pintype "passive")
		)
	)
	(footprint "antmicro-footprints:R_0402_1005Metric"
		(layer "B.Cu")
		(at 101.075 146.375 90)
		(descr "Resistor SMD 0402")
		(tags "resistor SMD 0402")
		(property "Reference" "R167"
			(at 1.274 -8.675 90)
			(layer "B.SilkS")
			(effects
				(font
					(size 0.7 0.7)
					(thickness 0.15)
				)
				(justify right bottom mirror)
			)
		)
		(property "Value" "R_51R_0402"
			(at 0 -1.4 90)
			(layer "B.Fab")
			(effects
				(font
					(size 0.7 0.7)
					(thickness 0.15)
				)
				(justify right bottom mirror)
			)
		)
		(property "Datasheet" "https://www.bourns.com/docs/product-datasheets/cr.pdf"
			(at 0 0 90)
			(layer "F.Fab")
			(hide yes)
			(effects
				(font
					(size 1.27 1.27)
					(thickness 0.15)
				)
			)
		)
		(property "Description" "SMD Chip Resistor, 51 ohm, ± 1%, 63 mW, 0402 [1005 Metric], Thick Film, General Purpose"
			(at 0 0 90)
			(layer "F.Fab")
			(hide yes)
			(effects
				(font
					(size 1.27 1.27)
					(thickness 0.15)
				)
			)
		)
		(property "Author" "Antmicro"
			(at 247.45 45.3 0)
			(layer "B.Fab")
			(hide yes)
			(effects
				(font
					(size 1 1)
					(thickness 0.15)
				)
				(justify mirror)
			)
		)
		(property "License" "Apache-2.0"
			(at 247.45 45.3 0)
			(layer "B.Fab")
			(hide yes)
			(effects
				(font
					(size 1 1)
					(thickness 0.15)
				)
				(justify mirror)
			)
		)
		(property "MPN" "CR0402-FX-51R0GLF"
			(at 247.45 45.3 0)
			(layer "B.Fab")
			(hide yes)
			(effects
				(font
					(size 1 1)
					(thickness 0.15)
				)
				(justify mirror)
			)
		)
		(property "Manufacturer" "Bourns"
			(at 247.45 45.3 0)
			(layer "B.Fab")
			(hide yes)
			(effects
				(font
					(size 1 1)
					(thickness 0.15)
				)
				(justify mirror)
			)
		)
		(property "Tolerance" "1%"
			(at 247.45 45.3 0)
			(layer "B.Fab")
			(hide yes)
			(effects
				(font
					(size 1 1)
					(thickness 0.15)
				)
				(justify mirror)
			)
		)
		(property "Val" "51R"
			(at 247.45 45.3 0)
			(layer "B.Fab")
			(hide yes)
			(effects
				(font
					(size 1 1)
					(thickness 0.15)
				)
				(justify mirror)
			)
		)
		(sheetname "/DDR3/")
		(sheetfile "ddr3.kicad_sch")
		(attr smd exclude_from_pos_files exclude_from_bom dnp)
		(fp_rect
			(start -0.925 0.47)
			(end 0.925 -0.47)
			(stroke
				(width 0.05)
				(type default)
			)
			(fill no)
			(layer "B.CrtYd")
		)
		(fp_rect
			(start -0.5 0.25)
			(end 0.5 -0.25)
			(stroke
				(width 0.15)
				(type solid)
			)
			(fill no)
			(layer "B.Fab")
		)
		(pad "1" smd roundrect
			(at -0.48 0 90)
			(size 0.59 0.64)
			(layers "B.Cu" "B.Mask" "B.Paste")
			(roundrect_rratio 0.25)
			(net 165 "DDR3_A3")
			(pintype "passive")
		)
		(pad "2" smd roundrect
			(at 0.48 0 90)
			(size 0.59 0.64)
			(layers "B.Cu" "B.Mask" "B.Paste")
			(roundrect_rratio 0.25)
			(net 143 "/DDR3/DDR3_VTT")
			(pintype "passive")
		)
	)
	(footprint "antmicro-footprints:R_0402_1005Metric"
		(layer "B.Cu")
		(at 101.175 149.675 -90)
		(descr "Resistor SMD 0402")
		(tags "resistor SMD 0402")
		(property "Reference" "R168"
			(at 2.525 -0.425 90)
			(layer "B.SilkS")
			(effects
				(font
					(size 0.7 0.7)
					(thickness 0.15)
				)
				(justify left bottom mirror)
			)
		)
		(property "Value" "R_51R_0402"
			(at 0 -1.4 90)
			(layer "B.Fab")
			(effects
				(font
					(size 0.7 0.7)
					(thickness 0.15)
				)
				(justify left bottom mirror)
			)
		)
		(property "Datasheet" "https://www.bourns.com/docs/product-datasheets/cr.pdf"
			(at 0 0 270)
			(layer "F.Fab")
			(hide yes)
			(effects
				(font
					(size 1.27 1.27)
					(thickness 0.15)
				)
			)
		)
		(property "Description" "SMD Chip Resistor, 51 ohm, ± 1%, 63 mW, 0402 [1005 Metric], Thick Film, General Purpose"
			(at 0 0 270)
			(layer "F.Fab")
			(hide yes)
			(effects
				(font
					(size 1.27 1.27)
					(thickness 0.15)
				)
			)
		)
		(property "Author" "Antmicro"
			(at -48.5 250.85 0)
			(layer "B.Fab")
			(hide yes)
			(effects
				(font
					(size 1 1)
					(thickness 0.15)
				)
				(justify mirror)
			)
		)
		(property "License" "Apache-2.0"
			(at -48.5 250.85 0)
			(layer "B.Fab")
			(hide yes)
			(effects
				(font
					(size 1 1)
					(thickness 0.15)
				)
				(justify mirror)
			)
		)
		(property "MPN" "CR0402-FX-51R0GLF"
			(at -48.5 250.85 0)
			(layer "B.Fab")
			(hide yes)
			(effects
				(font
					(size 1 1)
					(thickness 0.15)
				)
				(justify mirror)
			)
		)
		(property "Manufacturer" "Bourns"
			(at -48.5 250.85 0)
			(layer "B.Fab")
			(hide yes)
			(effects
				(font
					(size 1 1)
					(thickness 0.15)
				)
				(justify mirror)
			)
		)
		(property "Tolerance" "1%"
			(at -48.5 250.85 0)
			(layer "B.Fab")
			(hide yes)
			(effects
				(font
					(size 1 1)
					(thickness 0.15)
				)
				(justify mirror)
			)
		)
		(property "Val" "51R"
			(at -48.5 250.85 0)
			(layer "B.Fab")
			(hide yes)
			(effects
				(font
					(size 1 1)
					(thickness 0.15)
				)
				(justify mirror)
			)
		)
		(sheetname "/DDR3/")
		(sheetfile "ddr3.kicad_sch")
		(attr smd exclude_from_pos_files exclude_from_bom dnp)
		(fp_rect
			(start -0.925 0.47)
			(end 0.925 -0.47)
			(stroke
				(width 0.05)
				(type default)
			)
			(fill no)
			(layer "B.CrtYd")
		)
		(fp_rect
			(start -0.5 0.25)
			(end 0.5 -0.25)
			(stroke
				(width 0.15)
				(type solid)
			)
			(fill no)
			(layer "B.Fab")
		)
		(pad "1" smd roundrect
			(at -0.48 0 270)
			(size 0.59 0.64)
			(layers "B.Cu" "B.Mask" "B.Paste")
			(roundrect_rratio 0.25)
			(net 158 "DDR3_A0")
			(pintype "passive")
		)
		(pad "2" smd roundrect
			(at 0.48 0 270)
			(size 0.59 0.64)
			(layers "B.Cu" "B.Mask" "B.Paste")
			(roundrect_rratio 0.25)
			(net 143 "/DDR3/DDR3_VTT")
			(pintype "passive")
		)
	)
	(footprint "antmicro-footprints:R_0402_1005Metric"
		(layer "B.Cu")
		(at 102.175 149.675 -90)
		(descr "Resistor SMD 0402")
		(tags "resistor SMD 0402")
		(property "Reference" "R169"
			(at 2.525 -0.425 90)
			(layer "B.SilkS")
			(effects
				(font
					(size 0.7 0.7)
					(thickness 0.15)
				)
				(justify left bottom mirror)
			)
		)
		(property "Value" "R_51R_0402"
			(at 0 -1.4 90)
			(layer "B.Fab")
			(effects
				(font
					(size 0.7 0.7)
					(thickness 0.15)
				)
				(justify left bottom mirror)
			)
		)
		(property "Datasheet" "https://www.bourns.com/docs/product-datasheets/cr.pdf"
			(at 0 0 270)
			(layer "F.Fab")
			(hide yes)
			(effects
				(font
					(size 1.27 1.27)
					(thickness 0.15)
				)
			)
		)
		(property "Description" "SMD Chip Resistor, 51 ohm, ± 1%, 63 mW, 0402 [1005 Metric], Thick Film, General Purpose"
			(at 0 0 270)
			(layer "F.Fab")
			(hide yes)
			(effects
				(font
					(size 1.27 1.27)
					(thickness 0.15)
				)
			)
		)
		(property "Author" "Antmicro"
			(at -47.5 251.85 0)
			(layer "B.Fab")
			(hide yes)
			(effects
				(font
					(size 1 1)
					(thickness 0.15)
				)
				(justify mirror)
			)
		)
		(property "License" "Apache-2.0"
			(at -47.5 251.85 0)
			(layer "B.Fab")
			(hide yes)
			(effects
				(font
					(size 1 1)
					(thickness 0.15)
				)
				(justify mirror)
			)
		)
		(property "MPN" "CR0402-FX-51R0GLF"
			(at -47.5 251.85 0)
			(layer "B.Fab")
			(hide yes)
			(effects
				(font
					(size 1 1)
					(thickness 0.15)
				)
				(justify mirror)
			)
		)
		(property "Manufacturer" "Bourns"
			(at -47.5 251.85 0)
			(layer "B.Fab")
			(hide yes)
			(effects
				(font
					(size 1 1)
					(thickness 0.15)
				)
				(justify mirror)
			)
		)
		(property "Tolerance" "1%"
			(at -47.5 251.85 0)
			(layer "B.Fab")
			(hide yes)
			(effects
				(font
					(size 1 1)
					(thickness 0.15)
				)
				(justify mirror)
			)
		)
		(property "Val" "51R"
			(at -47.5 251.85 0)
			(layer "B.Fab")
			(hide yes)
			(effects
				(font
					(size 1 1)
					(thickness 0.15)
				)
				(justify mirror)
			)
		)
		(sheetname "/DDR3/")
		(sheetfile "ddr3.kicad_sch")
		(attr smd exclude_from_pos_files exclude_from_bom dnp)
		(fp_rect
			(start -0.925 0.47)
			(end 0.925 -0.47)
			(stroke
				(width 0.05)
				(type default)
			)
			(fill no)
			(layer "B.CrtYd")
		)
		(fp_rect
			(start -0.5 0.25)
			(end 0.5 -0.25)
			(stroke
				(width 0.15)
				(type solid)
			)
			(fill no)
			(layer "B.Fab")
		)
		(pad "1" smd roundrect
			(at -0.48 0 270)
			(size 0.59 0.64)
			(layers "B.Cu" "B.Mask" "B.Paste")
			(roundrect_rratio 0.25)
			(net 147 "DDR3_A2")
			(pintype "passive")
		)
		(pad "2" smd roundrect
			(at 0.48 0 270)
			(size 0.59 0.64)
			(layers "B.Cu" "B.Mask" "B.Paste")
			(roundrect_rratio 0.25)
			(net 143 "/DDR3/DDR3_VTT")
			(pintype "passive")
		)
	)
	(footprint "antmicro-footprints:R_0402_1005Metric"
		(layer "B.Cu")
		(at 103.175 149.675 -90)
		(descr "Resistor SMD 0402")
		(tags "resistor SMD 0402")
		(property "Reference" "R170"
			(at 2.525 -0.425 90)
			(layer "B.SilkS")
			(effects
				(font
					(size 0.7 0.7)
					(thickness 0.15)
				)
				(justify left bottom mirror)
			)
		)
		(property "Value" "R_51R_0402"
			(at 0 -1.4 90)
			(layer "B.Fab")
			(effects
				(font
					(size 0.7 0.7)
					(thickness 0.15)
				)
				(justify left bottom mirror)
			)
		)
		(property "Datasheet" "https://www.bourns.com/docs/product-datasheets/cr.pdf"
			(at 0 0 270)
			(layer "F.Fab")
			(hide yes)
			(effects
				(font
					(size 1.27 1.27)
					(thickness 0.15)
				)
			)
		)
		(property "Description" "SMD Chip Resistor, 51 ohm, ± 1%, 63 mW, 0402 [1005 Metric], Thick Film, General Purpose"
			(at 0 0 270)
			(layer "F.Fab")
			(hide yes)
			(effects
				(font
					(size 1.27 1.27)
					(thickness 0.15)
				)
			)
		)
		(property "Author" "Antmicro"
			(at -46.5 252.85 0)
			(layer "B.Fab")
			(hide yes)
			(effects
				(font
					(size 1 1)
					(thickness 0.15)
				)
				(justify mirror)
			)
		)
		(property "License" "Apache-2.0"
			(at -46.5 252.85 0)
			(layer "B.Fab")
			(hide yes)
			(effects
				(font
					(size 1 1)
					(thickness 0.15)
				)
				(justify mirror)
			)
		)
		(property "MPN" "CR0402-FX-51R0GLF"
			(at -46.5 252.85 0)
			(layer "B.Fab")
			(hide yes)
			(effects
				(font
					(size 1 1)
					(thickness 0.15)
				)
				(justify mirror)
			)
		)
		(property "Manufacturer" "Bourns"
			(at -46.5 252.85 0)
			(layer "B.Fab")
			(hide yes)
			(effects
				(font
					(size 1 1)
					(thickness 0.15)
				)
				(justify mirror)
			)
		)
		(property "Tolerance" "1%"
			(at -46.5 252.85 0)
			(layer "B.Fab")
			(hide yes)
			(effects
				(font
					(size 1 1)
					(thickness 0.15)
				)
				(justify mirror)
			)
		)
		(property "Val" "51R"
			(at -46.5 252.85 0)
			(layer "B.Fab")
			(hide yes)
			(effects
				(font
					(size 1 1)
					(thickness 0.15)
				)
				(justify mirror)
			)
		)
		(sheetname "/DDR3/")
		(sheetfile "ddr3.kicad_sch")
		(attr smd exclude_from_pos_files exclude_from_bom dnp)
		(fp_rect
			(start -0.925 0.47)
			(end 0.925 -0.47)
			(stroke
				(width 0.05)
				(type default)
			)
			(fill no)
			(layer "B.CrtYd")
		)
		(fp_rect
			(start -0.5 0.25)
			(end 0.5 -0.25)
			(stroke
				(width 0.15)
				(type solid)
			)
			(fill no)
			(layer "B.Fab")
		)
		(pad "1" smd roundrect
			(at -0.48 0 270)
			(size 0.59 0.64)
			(layers "B.Cu" "B.Mask" "B.Paste")
			(roundrect_rratio 0.25)
			(net 148 "DDR3_A7")
			(pintype "passive")
		)
		(pad "2" smd roundrect
			(at 0.48 0 270)
			(size 0.59 0.64)
			(layers "B.Cu" "B.Mask" "B.Paste")
			(roundrect_rratio 0.25)
			(net 143 "/DDR3/DDR3_VTT")
			(pintype "passive")
		)
	)
	(footprint "antmicro-footprints:R_0402_1005Metric"
		(layer "B.Cu")
		(at 104.175 149.675 -90)
		(descr "Resistor SMD 0402")
		(tags "resistor SMD 0402")
		(property "Reference" "R171"
			(at 2.525 -0.425 90)
			(layer "B.SilkS")
			(effects
				(font
					(size 0.7 0.7)
					(thickness 0.15)
				)
				(justify left bottom mirror)
			)
		)
		(property "Value" "R_51R_0402"
			(at 0 -1.4 90)
			(layer "B.Fab")
			(effects
				(font
					(size 0.7 0.7)
					(thickness 0.15)
				)
				(justify left bottom mirror)
			)
		)
		(property "Datasheet" "https://www.bourns.com/docs/product-datasheets/cr.pdf"
			(at 0 0 270)
			(layer "F.Fab")
			(hide yes)
			(effects
				(font
					(size 1.27 1.27)
					(thickness 0.15)
				)
			)
		)
		(property "Description" "SMD Chip Resistor, 51 ohm, ± 1%, 63 mW, 0402 [1005 Metric], Thick Film, General Purpose"
			(at 0 0 270)
			(layer "F.Fab")
			(hide yes)
			(effects
				(font
					(size 1.27 1.27)
					(thickness 0.15)
				)
			)
		)
		(property "Author" "Antmicro"
			(at -45.5 253.85 0)
			(layer "B.Fab")
			(hide yes)
			(effects
				(font
					(size 1 1)
					(thickness 0.15)
				)
				(justify mirror)
			)
		)
		(property "License" "Apache-2.0"
			(at -45.5 253.85 0)
			(layer "B.Fab")
			(hide yes)
			(effects
				(font
					(size 1 1)
					(thickness 0.15)
				)
				(justify mirror)
			)
		)
		(property "MPN" "CR0402-FX-51R0GLF"
			(at -45.5 253.85 0)
			(layer "B.Fab")
			(hide yes)
			(effects
				(font
					(size 1 1)
					(thickness 0.15)
				)
				(justify mirror)
			)
		)
		(property "Manufacturer" "Bourns"
			(at -45.5 253.85 0)
			(layer "B.Fab")
			(hide yes)
			(effects
				(font
					(size 1 1)
					(thickness 0.15)
				)
				(justify mirror)
			)
		)
		(property "Tolerance" "1%"
			(at -45.5 253.85 0)
			(layer "B.Fab")
			(hide yes)
			(effects
				(font
					(size 1 1)
					(thickness 0.15)
				)
				(justify mirror)
			)
		)
		(property "Val" "51R"
			(at -45.5 253.85 0)
			(layer "B.Fab")
			(hide yes)
			(effects
				(font
					(size 1 1)
					(thickness 0.15)
				)
				(justify mirror)
			)
		)
		(sheetname "/DDR3/")
		(sheetfile "ddr3.kicad_sch")
		(attr smd exclude_from_pos_files exclude_from_bom dnp)
		(fp_rect
			(start -0.925 0.47)
			(end 0.925 -0.47)
			(stroke
				(width 0.05)
				(type default)
			)
			(fill no)
			(layer "B.CrtYd")
		)
		(fp_rect
			(start -0.5 0.25)
			(end 0.5 -0.25)
			(stroke
				(width 0.15)
				(type solid)
			)
			(fill no)
			(layer "B.Fab")
		)
		(pad "1" smd roundrect
			(at -0.48 0 270)
			(size 0.59 0.64)
			(layers "B.Cu" "B.Mask" "B.Paste")
			(roundrect_rratio 0.25)
			(net 149 "DDR3_A9")
			(pintype "passive")
		)
		(pad "2" smd roundrect
			(at 0.48 0 270)
			(size 0.59 0.64)
			(layers "B.Cu" "B.Mask" "B.Paste")
			(roundrect_rratio 0.25)
			(net 143 "/DDR3/DDR3_VTT")
			(pintype "passive")
		)
	)
	(footprint "antmicro-footprints:R_0402_1005Metric"
		(layer "B.Cu")
		(at 104.575 145.175 90)
		(descr "Resistor SMD 0402")
		(tags "resistor SMD 0402")
		(property "Reference" "R172"
			(at 1.375 -8.675 90)
			(layer "B.SilkS")
			(effects
				(font
					(size 0.7 0.7)
					(thickness 0.15)
				)
				(justify right bottom mirror)
			)
		)
		(property "Value" "R_51R_0402"
			(at 0 -1.4 90)
			(layer "B.Fab")
			(effects
				(font
					(size 0.7 0.7)
					(thickness 0.15)
				)
				(justify right bottom mirror)
			)
		)
		(property "Datasheet" "https://www.bourns.com/docs/product-datasheets/cr.pdf"
			(at 0 0 90)
			(layer "F.Fab")
			(hide yes)
			(effects
				(font
					(size 1.27 1.27)
					(thickness 0.15)
				)
			)
		)
		(property "Description" "SMD Chip Resistor, 51 ohm, ± 1%, 63 mW, 0402 [1005 Metric], Thick Film, General Purpose"
			(at 0 0 90)
			(layer "F.Fab")
			(hide yes)
			(effects
				(font
					(size 1.27 1.27)
					(thickness 0.15)
				)
			)
		)
		(property "Author" "Antmicro"
			(at 249.75 40.6 0)
			(layer "B.Fab")
			(hide yes)
			(effects
				(font
					(size 1 1)
					(thickness 0.15)
				)
				(justify mirror)
			)
		)
		(property "License" "Apache-2.0"
			(at 249.75 40.6 0)
			(layer "B.Fab")
			(hide yes)
			(effects
				(font
					(size 1 1)
					(thickness 0.15)
				)
				(justify mirror)
			)
		)
		(property "MPN" "CR0402-FX-51R0GLF"
			(at 249.75 40.6 0)
			(layer "B.Fab")
			(hide yes)
			(effects
				(font
					(size 1 1)
					(thickness 0.15)
				)
				(justify mirror)
			)
		)
		(property "Manufacturer" "Bourns"
			(at 249.75 40.6 0)
			(layer "B.Fab")
			(hide yes)
			(effects
				(font
					(size 1 1)
					(thickness 0.15)
				)
				(justify mirror)
			)
		)
		(property "Tolerance" "1%"
			(at 249.75 40.6 0)
			(layer "B.Fab")
			(hide yes)
			(effects
				(font
					(size 1 1)
					(thickness 0.15)
				)
				(justify mirror)
			)
		)
		(property "Val" "51R"
			(at 249.75 40.6 0)
			(layer "B.Fab")
			(hide yes)
			(effects
				(font
					(size 1 1)
					(thickness 0.15)
				)
				(justify mirror)
			)
		)
		(sheetname "/DDR3/")
		(sheetfile "ddr3.kicad_sch")
		(attr smd exclude_from_pos_files exclude_from_bom dnp)
		(fp_rect
			(start -0.925 0.47)
			(end 0.925 -0.47)
			(stroke
				(width 0.05)
				(type default)
			)
			(fill no)
			(layer "B.CrtYd")
		)
		(fp_rect
			(start -0.5 0.25)
			(end 0.5 -0.25)
			(stroke
				(width 0.15)
				(type solid)
			)
			(fill no)
			(layer "B.Fab")
		)
		(pad "1" smd roundrect
			(at -0.48 0 90)
			(size 0.59 0.64)
			(layers "B.Cu" "B.Mask" "B.Paste")
			(roundrect_rratio 0.25)
			(net 167 "DDR3_A5")
			(pintype "passive")
		)
		(pad "2" smd roundrect
			(at 0.48 0 90)
			(size 0.59 0.64)
			(layers "B.Cu" "B.Mask" "B.Paste")
			(roundrect_rratio 0.25)
			(net 143 "/DDR3/DDR3_VTT")
			(pintype "passive")
		)
	)
	(footprint "antmicro-footprints:R_0402_1005Metric"
		(layer "B.Cu")
		(at 105.575 145.175 90)
		(descr "Resistor SMD 0402")
		(tags "resistor SMD 0402")
		(property "Reference" "R173"
			(at 1.375 -8.675 90)
			(layer "B.SilkS")
			(effects
				(font
					(size 0.7 0.7)
					(thickness 0.15)
				)
				(justify right bottom mirror)
			)
		)
		(property "Value" "R_51R_0402"
			(at 0 -1.4 90)
			(layer "B.Fab")
			(effects
				(font
					(size 0.7 0.7)
					(thickness 0.15)
				)
				(justify right bottom mirror)
			)
		)
		(property "Datasheet" "https://www.bourns.com/docs/product-datasheets/cr.pdf"
			(at 0 0 90)
			(layer "F.Fab")
			(hide yes)
			(effects
				(font
					(size 1.27 1.27)
					(thickness 0.15)
				)
			)
		)
		(property "Description" "SMD Chip Resistor, 51 ohm, ± 1%, 63 mW, 0402 [1005 Metric], Thick Film, General Purpose"
			(at 0 0 90)
			(layer "F.Fab")
			(hide yes)
			(effects
				(font
					(size 1.27 1.27)
					(thickness 0.15)
				)
			)
		)
		(property "Author" "Antmicro"
			(at 250.75 39.6 0)
			(layer "B.Fab")
			(hide yes)
			(effects
				(font
					(size 1 1)
					(thickness 0.15)
				)
				(justify mirror)
			)
		)
		(property "License" "Apache-2.0"
			(at 250.75 39.6 0)
			(layer "B.Fab")
			(hide yes)
			(effects
				(font
					(size 1 1)
					(thickness 0.15)
				)
				(justify mirror)
			)
		)
		(property "MPN" "CR0402-FX-51R0GLF"
			(at 250.75 39.6 0)
			(layer "B.Fab")
			(hide yes)
			(effects
				(font
					(size 1 1)
					(thickness 0.15)
				)
				(justify mirror)
			)
		)
		(property "Manufacturer" "Bourns"
			(at 250.75 39.6 0)
			(layer "B.Fab")
			(hide yes)
			(effects
				(font
					(size 1 1)
					(thickness 0.15)
				)
				(justify mirror)
			)
		)
		(property "Tolerance" "1%"
			(at 250.75 39.6 0)
			(layer "B.Fab")
			(hide yes)
			(effects
				(font
					(size 1 1)
					(thickness 0.15)
				)
				(justify mirror)
			)
		)
		(property "Val" "51R"
			(at 250.75 39.6 0)
			(layer "B.Fab")
			(hide yes)
			(effects
				(font
					(size 1 1)
					(thickness 0.15)
				)
				(justify mirror)
			)
		)
		(sheetname "/DDR3/")
		(sheetfile "ddr3.kicad_sch")
		(attr smd exclude_from_pos_files exclude_from_bom dnp)
		(fp_rect
			(start -0.925 0.47)
			(end 0.925 -0.47)
			(stroke
				(width 0.05)
				(type default)
			)
			(fill no)
			(layer "B.CrtYd")
		)
		(fp_rect
			(start -0.5 0.25)
			(end 0.5 -0.25)
			(stroke
				(width 0.15)
				(type solid)
			)
			(fill no)
			(layer "B.Fab")
		)
		(pad "1" smd roundrect
			(at -0.48 0 90)
			(size 0.59 0.64)
			(layers "B.Cu" "B.Mask" "B.Paste")
			(roundrect_rratio 0.25)
			(net 151 "DDR3_A13")
			(pintype "passive")
		)
		(pad "2" smd roundrect
			(at 0.48 0 90)
			(size 0.59 0.64)
			(layers "B.Cu" "B.Mask" "B.Paste")
			(roundrect_rratio 0.25)
			(net 143 "/DDR3/DDR3_VTT")
			(pintype "passive")
		)
	)
	(footprint "antmicro-footprints:R_0402_1005Metric"
		(layer "B.Cu")
		(at 101.075 144.775 180)
		(descr "Resistor SMD 0402")
		(tags "resistor SMD 0402")
		(property "Reference" "R174"
			(at 7.975 2.775 0)
			(layer "B.SilkS")
			(effects
				(font
					(size 0.7 0.7)
					(thickness 0.15)
				)
				(justify left bottom mirror)
			)
		)
		(property "Value" "R_51R_0402"
			(at 0 -1.4 0)
			(layer "B.Fab")
			(effects
				(font
					(size 0.7 0.7)
					(thickness 0.15)
				)
				(justify left bottom mirror)
			)
		)
		(property "Datasheet" "https://www.bourns.com/docs/product-datasheets/cr.pdf"
			(at 0 0 180)
			(layer "F.Fab")
			(hide yes)
			(effects
				(font
					(size 1.27 1.27)
					(thickness 0.15)
				)
			)
		)
		(property "Description" "SMD Chip Resistor, 51 ohm, ± 1%, 63 mW, 0402 [1005 Metric], Thick Film, General Purpose"
			(at 0 0 180)
			(layer "F.Fab")
			(hide yes)
			(effects
				(font
					(size 1.27 1.27)
					(thickness 0.15)
				)
			)
		)
		(property "Author" "Antmicro"
			(at 202.15 289.55 0)
			(layer "B.Fab")
			(hide yes)
			(effects
				(font
					(size 1 1)
					(thickness 0.15)
				)
				(justify mirror)
			)
		)
		(property "License" "Apache-2.0"
			(at 202.15 289.55 0)
			(layer "B.Fab")
			(hide yes)
			(effects
				(font
					(size 1 1)
					(thickness 0.15)
				)
				(justify mirror)
			)
		)
		(property "MPN" "CR0402-FX-51R0GLF"
			(at 202.15 289.55 0)
			(layer "B.Fab")
			(hide yes)
			(effects
				(font
					(size 1 1)
					(thickness 0.15)
				)
				(justify mirror)
			)
		)
		(property "Manufacturer" "Bourns"
			(at 202.15 289.55 0)
			(layer "B.Fab")
			(hide yes)
			(effects
				(font
					(size 1 1)
					(thickness 0.15)
				)
				(justify mirror)
			)
		)
		(property "Tolerance" "1%"
			(at 202.15 289.55 0)
			(layer "B.Fab")
			(hide yes)
			(effects
				(font
					(size 1 1)
					(thickness 0.15)
				)
				(justify mirror)
			)
		)
		(property "Val" "51R"
			(at 202.15 289.55 0)
			(layer "B.Fab")
			(hide yes)
			(effects
				(font
					(size 1 1)
					(thickness 0.15)
				)
				(justify mirror)
			)
		)
		(sheetname "/DDR3/")
		(sheetfile "ddr3.kicad_sch")
		(attr smd exclude_from_pos_files exclude_from_bom dnp)
		(fp_rect
			(start -0.925 0.47)
			(end 0.925 -0.47)
			(stroke
				(width 0.05)
				(type default)
			)
			(fill no)
			(layer "B.CrtYd")
		)
		(fp_rect
			(start -0.5 0.25)
			(end 0.5 -0.25)
			(stroke
				(width 0.15)
				(type solid)
			)
			(fill no)
			(layer "B.Fab")
		)
		(pad "1" smd roundrect
			(at -0.48 0 180)
			(size 0.59 0.64)
			(layers "B.Cu" "B.Mask" "B.Paste")
			(roundrect_rratio 0.25)
			(net 156 "DDR3_A12")
			(pintype "passive")
		)
		(pad "2" smd roundrect
			(at 0.48 0 180)
			(size 0.59 0.64)
			(layers "B.Cu" "B.Mask" "B.Paste")
			(roundrect_rratio 0.25)
			(net 143 "/DDR3/DDR3_VTT")
			(pintype "passive")
		)
	)
	(footprint "antmicro-footprints:R_0402_1005Metric"
		(layer "B.Cu")
		(at 102.575 144.675 90)
		(descr "Resistor SMD 0402")
		(tags "resistor SMD 0402")
		(property "Reference" "R175"
			(at 1.375 -8.675 90)
			(layer "B.SilkS")
			(effects
				(font
					(size 0.7 0.7)
					(thickness 0.15)
				)
				(justify right bottom mirror)
			)
		)
		(property "Value" "R_51R_0402"
			(at 0 -1.4 90)
			(layer "B.Fab")
			(effects
				(font
					(size 0.7 0.7)
					(thickness 0.15)
				)
				(justify right bottom mirror)
			)
		)
		(property "Datasheet" "https://www.bourns.com/docs/product-datasheets/cr.pdf"
			(at 0 0 90)
			(layer "F.Fab")
			(hide yes)
			(effects
				(font
					(size 1.27 1.27)
					(thickness 0.15)
				)
			)
		)
		(property "Description" "SMD Chip Resistor, 51 ohm, ± 1%, 63 mW, 0402 [1005 Metric], Thick Film, General Purpose"
			(at 0 0 90)
			(layer "F.Fab")
			(hide yes)
			(effects
				(font
					(size 1.27 1.27)
					(thickness 0.15)
				)
			)
		)
		(property "Author" "Antmicro"
			(at 247.25 42.1 0)
			(layer "B.Fab")
			(hide yes)
			(effects
				(font
					(size 1 1)
					(thickness 0.15)
				)
				(justify mirror)
			)
		)
		(property "License" "Apache-2.0"
			(at 247.25 42.1 0)
			(layer "B.Fab")
			(hide yes)
			(effects
				(font
					(size 1 1)
					(thickness 0.15)
				)
				(justify mirror)
			)
		)
		(property "MPN" "CR0402-FX-51R0GLF"
			(at 247.25 42.1 0)
			(layer "B.Fab")
			(hide yes)
			(effects
				(font
					(size 1 1)
					(thickness 0.15)
				)
				(justify mirror)
			)
		)
		(property "Manufacturer" "Bourns"
			(at 247.25 42.1 0)
			(layer "B.Fab")
			(hide yes)
			(effects
				(font
					(size 1 1)
					(thickness 0.15)
				)
				(justify mirror)
			)
		)
		(property "Tolerance" "1%"
			(at 247.25 42.1 0)
			(layer "B.Fab")
			(hide yes)
			(effects
				(font
					(size 1 1)
					(thickness 0.15)
				)
				(justify mirror)
			)
		)
		(property "Val" "51R"
			(at 247.25 42.1 0)
			(layer "B.Fab")
			(hide yes)
			(effects
				(font
					(size 1 1)
					(thickness 0.15)
				)
				(justify mirror)
			)
		)
		(sheetname "/DDR3/")
		(sheetfile "ddr3.kicad_sch")
		(attr smd exclude_from_pos_files exclude_from_bom dnp)
		(fp_rect
			(start -0.925 0.47)
			(end 0.925 -0.47)
			(stroke
				(width 0.05)
				(type default)
			)
			(fill no)
			(layer "B.CrtYd")
		)
		(fp_rect
			(start -0.5 0.25)
			(end 0.5 -0.25)
			(stroke
				(width 0.15)
				(type solid)
			)
			(fill no)
			(layer "B.Fab")
		)
		(pad "1" smd roundrect
			(at -0.48 0 90)
			(size 0.59 0.64)
			(layers "B.Cu" "B.Mask" "B.Paste")
			(roundrect_rratio 0.25)
			(net 157 "DDR3_A1")
			(pintype "passive")
		)
		(pad "2" smd roundrect
			(at 0.48 0 90)
			(size 0.59 0.64)
			(layers "B.Cu" "B.Mask" "B.Paste")
			(roundrect_rratio 0.25)
			(net 143 "/DDR3/DDR3_VTT")
			(pintype "passive")
		)
	)
	(footprint "antmicro-footprints:R_0402_1005Metric"
		(layer "B.Cu")
		(at 103.575 144.675 90)
		(descr "Resistor SMD 0402")
		(tags "resistor SMD 0402")
		(property "Reference" "R176"
			(at 1.375 -8.675 90)
			(layer "B.SilkS")
			(effects
				(font
					(size 0.7 0.7)
					(thickness 0.15)
				)
				(justify right bottom mirror)
			)
		)
		(property "Value" "R_51R_0402"
			(at 0 -1.4 90)
			(layer "B.Fab")
			(effects
				(font
					(size 0.7 0.7)
					(thickness 0.15)
				)
				(justify right bottom mirror)
			)
		)
		(property "Datasheet" "https://www.bourns.com/docs/product-datasheets/cr.pdf"
			(at 0 0 90)
			(layer "F.Fab")
			(hide yes)
			(effects
				(font
					(size 1.27 1.27)
					(thickness 0.15)
				)
			)
		)
		(property "Description" "SMD Chip Resistor, 51 ohm, ± 1%, 63 mW, 0402 [1005 Metric], Thick Film, General Purpose"
			(at 0 0 90)
			(layer "F.Fab")
			(hide yes)
			(effects
				(font
					(size 1.27 1.27)
					(thickness 0.15)
				)
			)
		)
		(property "Author" "Antmicro"
			(at 248.25 41.1 0)
			(layer "B.Fab")
			(hide yes)
			(effects
				(font
					(size 1 1)
					(thickness 0.15)
				)
				(justify mirror)
			)
		)
		(property "License" "Apache-2.0"
			(at 248.25 41.1 0)
			(layer "B.Fab")
			(hide yes)
			(effects
				(font
					(size 1 1)
					(thickness 0.15)
				)
				(justify mirror)
			)
		)
		(property "MPN" "CR0402-FX-51R0GLF"
			(at 248.25 41.1 0)
			(layer "B.Fab")
			(hide yes)
			(effects
				(font
					(size 1 1)
					(thickness 0.15)
				)
				(justify mirror)
			)
		)
		(property "Manufacturer" "Bourns"
			(at 248.25 41.1 0)
			(layer "B.Fab")
			(hide yes)
			(effects
				(font
					(size 1 1)
					(thickness 0.15)
				)
				(justify mirror)
			)
		)
		(property "Tolerance" "1%"
			(at 248.25 41.1 0)
			(layer "B.Fab")
			(hide yes)
			(effects
				(font
					(size 1 1)
					(thickness 0.15)
				)
				(justify mirror)
			)
		)
		(property "Val" "51R"
			(at 248.25 41.1 0)
			(layer "B.Fab")
			(hide yes)
			(effects
				(font
					(size 1 1)
					(thickness 0.15)
				)
				(justify mirror)
			)
		)
		(sheetname "/DDR3/")
		(sheetfile "ddr3.kicad_sch")
		(attr smd exclude_from_pos_files exclude_from_bom dnp)
		(fp_rect
			(start -0.925 0.47)
			(end 0.925 -0.47)
			(stroke
				(width 0.05)
				(type default)
			)
			(fill no)
			(layer "B.CrtYd")
		)
		(fp_rect
			(start -0.5 0.25)
			(end 0.5 -0.25)
			(stroke
				(width 0.15)
				(type solid)
			)
			(fill no)
			(layer "B.Fab")
		)
		(pad "1" smd roundrect
			(at -0.48 0 90)
			(size 0.59 0.64)
			(layers "B.Cu" "B.Mask" "B.Paste")
			(roundrect_rratio 0.25)
			(net 150 "DDR3_A11")
			(pintype "passive")
		)
		(pad "2" smd roundrect
			(at 0.48 0 90)
			(size 0.59 0.64)
			(layers "B.Cu" "B.Mask" "B.Paste")
			(roundrect_rratio 0.25)
			(net 143 "/DDR3/DDR3_VTT")
			(pintype "passive")
		)
	)
	(footprint "antmicro-footprints:R_0402_1005Metric"
		(layer "B.Cu")
		(at 106.575 144.075 90)
		(descr "Resistor SMD 0402")
		(tags "resistor SMD 0402")
		(property "Reference" "R177"
			(at 0.775 -8.675 90)
			(layer "B.SilkS")
			(effects
				(font
					(size 0.7 0.7)
					(thickness 0.15)
				)
				(justify right bottom mirror)
			)
		)
		(property "Value" "R_51R_0402"
			(at 0 -1.4 90)
			(layer "B.Fab")
			(effects
				(font
					(size 0.7 0.7)
					(thickness 0.15)
				)
				(justify right bottom mirror)
			)
		)
		(property "Datasheet" "https://www.bourns.com/docs/product-datasheets/cr.pdf"
			(at 0 0 90)
			(layer "F.Fab")
			(hide yes)
			(effects
				(font
					(size 1.27 1.27)
					(thickness 0.15)
				)
			)
		)
		(property "Description" "SMD Chip Resistor, 51 ohm, ± 1%, 63 mW, 0402 [1005 Metric], Thick Film, General Purpose"
			(at 0 0 90)
			(layer "F.Fab")
			(hide yes)
			(effects
				(font
					(size 1.27 1.27)
					(thickness 0.15)
				)
			)
		)
		(property "Author" "Antmicro"
			(at 250.65 37.5 0)
			(layer "B.Fab")
			(hide yes)
			(effects
				(font
					(size 1 1)
					(thickness 0.15)
				)
				(justify mirror)
			)
		)
		(property "License" "Apache-2.0"
			(at 250.65 37.5 0)
			(layer "B.Fab")
			(hide yes)
			(effects
				(font
					(size 1 1)
					(thickness 0.15)
				)
				(justify mirror)
			)
		)
		(property "MPN" "CR0402-FX-51R0GLF"
			(at 250.65 37.5 0)
			(layer "B.Fab")
			(hide yes)
			(effects
				(font
					(size 1 1)
					(thickness 0.15)
				)
				(justify mirror)
			)
		)
		(property "Manufacturer" "Bourns"
			(at 250.65 37.5 0)
			(layer "B.Fab")
			(hide yes)
			(effects
				(font
					(size 1 1)
					(thickness 0.15)
				)
				(justify mirror)
			)
		)
		(property "Tolerance" "1%"
			(at 250.65 37.5 0)
			(layer "B.Fab")
			(hide yes)
			(effects
				(font
					(size 1 1)
					(thickness 0.15)
				)
				(justify mirror)
			)
		)
		(property "Val" "51R"
			(at 250.65 37.5 0)
			(layer "B.Fab")
			(hide yes)
			(effects
				(font
					(size 1 1)
					(thickness 0.15)
				)
				(justify mirror)
			)
		)
		(sheetname "/DDR3/")
		(sheetfile "ddr3.kicad_sch")
		(attr smd exclude_from_pos_files exclude_from_bom dnp)
		(fp_rect
			(start -0.925 0.47)
			(end 0.925 -0.47)
			(stroke
				(width 0.05)
				(type default)
			)
			(fill no)
			(layer "B.CrtYd")
		)
		(fp_rect
			(start -0.5 0.25)
			(end 0.5 -0.25)
			(stroke
				(width 0.15)
				(type solid)
			)
			(fill no)
			(layer "B.Fab")
		)
		(pad "1" smd roundrect
			(at -0.48 0 90)
			(size 0.59 0.64)
			(layers "B.Cu" "B.Mask" "B.Paste")
			(roundrect_rratio 0.25)
			(net 144 "DDR3_A14")
			(pintype "passive")
		)
		(pad "2" smd roundrect
			(at 0.48 0 90)
			(size 0.59 0.64)
			(layers "B.Cu" "B.Mask" "B.Paste")
			(roundrect_rratio 0.25)
			(net 143 "/DDR3/DDR3_VTT")
			(pintype "passive")
		)
	)
	(footprint "antmicro-footprints:R_0402_1005Metric"
		(layer "B.Cu")
		(at 102.175 141.875 90)
		(descr "Resistor SMD 0402")
		(tags "resistor SMD 0402")
		(property "Reference" "R178"
			(at 0.775 0.425 90)
			(layer "B.SilkS")
			(effects
				(font
					(size 0.7 0.7)
					(thickness 0.15)
				)
				(justify right bottom mirror)
			)
		)
		(property "Value" "R_51R_0402"
			(at 0 -1.4 90)
			(layer "B.Fab")
			(effects
				(font
					(size 0.7 0.7)
					(thickness 0.15)
				)
				(justify right bottom mirror)
			)
		)
		(property "Datasheet" "https://www.bourns.com/docs/product-datasheets/cr.pdf"
			(at 0 0 90)
			(layer "F.Fab")
			(hide yes)
			(effects
				(font
					(size 1.27 1.27)
					(thickness 0.15)
				)
			)
		)
		(property "Description" "SMD Chip Resistor, 51 ohm, ± 1%, 63 mW, 0402 [1005 Metric], Thick Film, General Purpose"
			(at 0 0 90)
			(layer "F.Fab")
			(hide yes)
			(effects
				(font
					(size 1.27 1.27)
					(thickness 0.15)
				)
			)
		)
		(property "Author" "Antmicro"
			(at 244.05 39.7 0)
			(layer "B.Fab")
			(hide yes)
			(effects
				(font
					(size 1 1)
					(thickness 0.15)
				)
				(justify mirror)
			)
		)
		(property "License" "Apache-2.0"
			(at 244.05 39.7 0)
			(layer "B.Fab")
			(hide yes)
			(effects
				(font
					(size 1 1)
					(thickness 0.15)
				)
				(justify mirror)
			)
		)
		(property "MPN" "CR0402-FX-51R0GLF"
			(at 244.05 39.7 0)
			(layer "B.Fab")
			(hide yes)
			(effects
				(font
					(size 1 1)
					(thickness 0.15)
				)
				(justify mirror)
			)
		)
		(property "Manufacturer" "Bourns"
			(at 244.05 39.7 0)
			(layer "B.Fab")
			(hide yes)
			(effects
				(font
					(size 1 1)
					(thickness 0.15)
				)
				(justify mirror)
			)
		)
		(property "Tolerance" "1%"
			(at 244.05 39.7 0)
			(layer "B.Fab")
			(hide yes)
			(effects
				(font
					(size 1 1)
					(thickness 0.15)
				)
				(justify mirror)
			)
		)
		(property "Val" "51R"
			(at 244.05 39.7 0)
			(layer "B.Fab")
			(hide yes)
			(effects
				(font
					(size 1 1)
					(thickness 0.15)
				)
				(justify mirror)
			)
		)
		(sheetname "/DDR3/")
		(sheetfile "ddr3.kicad_sch")
		(attr smd exclude_from_pos_files exclude_from_bom dnp)
		(fp_rect
			(start -0.925 0.47)
			(end 0.925 -0.47)
			(stroke
				(width 0.05)
				(type default)
			)
			(fill no)
			(layer "B.CrtYd")
		)
		(fp_rect
			(start -0.5 0.25)
			(end 0.5 -0.25)
			(stroke
				(width 0.15)
				(type solid)
			)
			(fill no)
			(layer "B.Fab")
		)
		(pad "1" smd roundrect
			(at -0.48 0 90)
			(size 0.59 0.64)
			(layers "B.Cu" "B.Mask" "B.Paste")
			(roundrect_rratio 0.25)
			(net 159 "DDR3_A4")
			(pintype "passive")
		)
		(pad "2" smd roundrect
			(at 0.48 0 90)
			(size 0.59 0.64)
			(layers "B.Cu" "B.Mask" "B.Paste")
			(roundrect_rratio 0.25)
			(net 143 "/DDR3/DDR3_VTT")
			(pintype "passive")
		)
	)
	(footprint "antmicro-footprints:R_0402_1005Metric"
		(layer "B.Cu")
		(at 103.175 141.875 90)
		(descr "Resistor SMD 0402")
		(tags "resistor SMD 0402")
		(property "Reference" "R179"
			(at 0.775 0.425 90)
			(layer "B.SilkS")
			(effects
				(font
					(size 0.7 0.7)
					(thickness 0.15)
				)
				(justify right bottom mirror)
			)
		)
		(property "Value" "R_51R_0402"
			(at 0 -1.4 90)
			(layer "B.Fab")
			(effects
				(font
					(size 0.7 0.7)
					(thickness 0.15)
				)
				(justify right bottom mirror)
			)
		)
		(property "Datasheet" "https://www.bourns.com/docs/product-datasheets/cr.pdf"
			(at 0 0 90)
			(layer "F.Fab")
			(hide yes)
			(effects
				(font
					(size 1.27 1.27)
					(thickness 0.15)
				)
			)
		)
		(property "Description" "SMD Chip Resistor, 51 ohm, ± 1%, 63 mW, 0402 [1005 Metric], Thick Film, General Purpose"
			(at 0 0 90)
			(layer "F.Fab")
			(hide yes)
			(effects
				(font
					(size 1.27 1.27)
					(thickness 0.15)
				)
			)
		)
		(property "Author" "Antmicro"
			(at 245.05 38.7 0)
			(layer "B.Fab")
			(hide yes)
			(effects
				(font
					(size 1 1)
					(thickness 0.15)
				)
				(justify mirror)
			)
		)
		(property "License" "Apache-2.0"
			(at 245.05 38.7 0)
			(layer "B.Fab")
			(hide yes)
			(effects
				(font
					(size 1 1)
					(thickness 0.15)
				)
				(justify mirror)
			)
		)
		(property "MPN" "CR0402-FX-51R0GLF"
			(at 245.05 38.7 0)
			(layer "B.Fab")
			(hide yes)
			(effects
				(font
					(size 1 1)
					(thickness 0.15)
				)
				(justify mirror)
			)
		)
		(property "Manufacturer" "Bourns"
			(at 245.05 38.7 0)
			(layer "B.Fab")
			(hide yes)
			(effects
				(font
					(size 1 1)
					(thickness 0.15)
				)
				(justify mirror)
			)
		)
		(property "Tolerance" "1%"
			(at 245.05 38.7 0)
			(layer "B.Fab")
			(hide yes)
			(effects
				(font
					(size 1 1)
					(thickness 0.15)
				)
				(justify mirror)
			)
		)
		(property "Val" "51R"
			(at 245.05 38.7 0)
			(layer "B.Fab")
			(hide yes)
			(effects
				(font
					(size 1 1)
					(thickness 0.15)
				)
				(justify mirror)
			)
		)
		(sheetname "/DDR3/")
		(sheetfile "ddr3.kicad_sch")
		(attr smd exclude_from_pos_files exclude_from_bom dnp)
		(fp_rect
			(start -0.925 0.47)
			(end 0.925 -0.47)
			(stroke
				(width 0.05)
				(type default)
			)
			(fill no)
			(layer "B.CrtYd")
		)
		(fp_rect
			(start -0.5 0.25)
			(end 0.5 -0.25)
			(stroke
				(width 0.15)
				(type solid)
			)
			(fill no)
			(layer "B.Fab")
		)
		(pad "1" smd roundrect
			(at -0.48 0 90)
			(size 0.59 0.64)
			(layers "B.Cu" "B.Mask" "B.Paste")
			(roundrect_rratio 0.25)
			(net 146 "DDR3_A6")
			(pintype "passive")
		)
		(pad "2" smd roundrect
			(at 0.48 0 90)
			(size 0.59 0.64)
			(layers "B.Cu" "B.Mask" "B.Paste")
			(roundrect_rratio 0.25)
			(net 143 "/DDR3/DDR3_VTT")
			(pintype "passive")
		)
	)
	(footprint "antmicro-footprints:R_0402_1005Metric"
		(layer "B.Cu")
		(at 101.175 141.075 90)
		(descr "Resistor SMD 0402")
		(tags "resistor SMD 0402")
		(property "Reference" "R181"
			(at 0.775 0.425 90)
			(layer "B.SilkS")
			(effects
				(font
					(size 0.7 0.7)
					(thickness 0.15)
				)
				(justify right bottom mirror)
			)
		)
		(property "Value" "R_51R_0402"
			(at 0 -1.4 90)
			(layer "B.Fab")
			(effects
				(font
					(size 0.7 0.7)
					(thickness 0.15)
				)
				(justify right bottom mirror)
			)
		)
		(property "Datasheet" "https://www.bourns.com/docs/product-datasheets/cr.pdf"
			(at 0 0 90)
			(layer "F.Fab")
			(hide yes)
			(effects
				(font
					(size 1.27 1.27)
					(thickness 0.15)
				)
			)
		)
		(property "Description" "SMD Chip Resistor, 51 ohm, ± 1%, 63 mW, 0402 [1005 Metric], Thick Film, General Purpose"
			(at 0 0 90)
			(layer "F.Fab")
			(hide yes)
			(effects
				(font
					(size 1.27 1.27)
					(thickness 0.15)
				)
			)
		)
		(property "Author" "Antmicro"
			(at 242.25 39.9 0)
			(layer "B.Fab")
			(hide yes)
			(effects
				(font
					(size 1 1)
					(thickness 0.15)
				)
				(justify mirror)
			)
		)
		(property "License" "Apache-2.0"
			(at 242.25 39.9 0)
			(layer "B.Fab")
			(hide yes)
			(effects
				(font
					(size 1 1)
					(thickness 0.15)
				)
				(justify mirror)
			)
		)
		(property "MPN" "CR0402-FX-51R0GLF"
			(at 242.25 39.9 0)
			(layer "B.Fab")
			(hide yes)
			(effects
				(font
					(size 1 1)
					(thickness 0.15)
				)
				(justify mirror)
			)
		)
		(property "Manufacturer" "Bourns"
			(at 242.25 39.9 0)
			(layer "B.Fab")
			(hide yes)
			(effects
				(font
					(size 1 1)
					(thickness 0.15)
				)
				(justify mirror)
			)
		)
		(property "Tolerance" "1%"
			(at 242.25 39.9 0)
			(layer "B.Fab")
			(hide yes)
			(effects
				(font
					(size 1 1)
					(thickness 0.15)
				)
				(justify mirror)
			)
		)
		(property "Val" "51R"
			(at 242.25 39.9 0)
			(layer "B.Fab")
			(hide yes)
			(effects
				(font
					(size 1 1)
					(thickness 0.15)
				)
				(justify mirror)
			)
		)
		(sheetname "/DDR3/")
		(sheetfile "ddr3.kicad_sch")
		(attr smd exclude_from_pos_files exclude_from_bom dnp)
		(fp_rect
			(start -0.925 0.47)
			(end 0.925 -0.47)
			(stroke
				(width 0.05)
				(type default)
			)
			(fill no)
			(layer "B.CrtYd")
		)
		(fp_rect
			(start -0.5 0.25)
			(end 0.5 -0.25)
			(stroke
				(width 0.15)
				(type solid)
			)
			(fill no)
			(layer "B.Fab")
		)
		(pad "1" smd roundrect
			(at -0.48 0 90)
			(size 0.59 0.64)
			(layers "B.Cu" "B.Mask" "B.Paste")
			(roundrect_rratio 0.25)
			(net 155 "DDR3_BA1")
			(pintype "passive")
		)
		(pad "2" smd roundrect
			(at 0.48 0 90)
			(size 0.59 0.64)
			(layers "B.Cu" "B.Mask" "B.Paste")
			(roundrect_rratio 0.25)
			(net 143 "/DDR3/DDR3_VTT")
			(pintype "passive")
		)
	)
	(footprint "antmicro-footprints:R_0402_1005Metric"
		(layer "B.Cu")
		(at 99.075 144.775)
		(descr "Resistor SMD 0402")
		(tags "resistor SMD 0402")
		(property "Reference" "R182"
			(at -11.875 -2.775 0)
			(layer "B.SilkS")
			(effects
				(font
					(size 0.7 0.7)
					(thickness 0.15)
				)
				(justify right bottom mirror)
			)
		)
		(property "Value" "R_51R_0402"
			(at 0 -1.4 0)
			(layer "B.Fab")
			(effects
				(font
					(size 0.7 0.7)
					(thickness 0.15)
				)
				(justify right bottom mirror)
			)
		)
		(property "Datasheet" "https://www.bourns.com/docs/product-datasheets/cr.pdf"
			(at 0 0 0)
			(layer "F.Fab")
			(hide yes)
			(effects
				(font
					(size 1.27 1.27)
					(thickness 0.15)
				)
			)
		)
		(property "Description" "SMD Chip Resistor, 51 ohm, ± 1%, 63 mW, 0402 [1005 Metric], Thick Film, General Purpose"
			(at 0 0 0)
			(layer "F.Fab")
			(hide yes)
			(effects
				(font
					(size 1.27 1.27)
					(thickness 0.15)
				)
			)
		)
		(property "Author" "Antmicro"
			(at 0 0 0)
			(layer "B.Fab")
			(hide yes)
			(effects
				(font
					(size 1 1)
					(thickness 0.15)
				)
				(justify mirror)
			)
		)
		(property "License" "Apache-2.0"
			(at 0 0 0)
			(layer "B.Fab")
			(hide yes)
			(effects
				(font
					(size 1 1)
					(thickness 0.15)
				)
				(justify mirror)
			)
		)
		(property "MPN" "CR0402-FX-51R0GLF"
			(at 0 0 0)
			(layer "B.Fab")
			(hide yes)
			(effects
				(font
					(size 1 1)
					(thickness 0.15)
				)
				(justify mirror)
			)
		)
		(property "Manufacturer" "Bourns"
			(at 0 0 0)
			(layer "B.Fab")
			(hide yes)
			(effects
				(font
					(size 1 1)
					(thickness 0.15)
				)
				(justify mirror)
			)
		)
		(property "Tolerance" "1%"
			(at 0 0 0)
			(layer "B.Fab")
			(hide yes)
			(effects
				(font
					(size 1 1)
					(thickness 0.15)
				)
				(justify mirror)
			)
		)
		(property "Val" "51R"
			(at 0 0 0)
			(layer "B.Fab")
			(hide yes)
			(effects
				(font
					(size 1 1)
					(thickness 0.15)
				)
				(justify mirror)
			)
		)
		(sheetname "/DDR3/")
		(sheetfile "ddr3.kicad_sch")
		(attr smd exclude_from_pos_files exclude_from_bom dnp)
		(fp_rect
			(start -0.925 0.47)
			(end 0.925 -0.47)
			(stroke
				(width 0.05)
				(type default)
			)
			(fill no)
			(layer "B.CrtYd")
		)
		(fp_rect
			(start -0.5 0.25)
			(end 0.5 -0.25)
			(stroke
				(width 0.15)
				(type solid)
			)
			(fill no)
			(layer "B.Fab")
		)
		(pad "1" smd roundrect
			(at -0.48 0)
			(size 0.59 0.64)
			(layers "B.Cu" "B.Mask" "B.Paste")
			(roundrect_rratio 0.25)
			(net 160 "DDR3_CKE")
			(pintype "passive")
		)
		(pad "2" smd roundrect
			(at 0.48 0)
			(size 0.59 0.64)
			(layers "B.Cu" "B.Mask" "B.Paste")
			(roundrect_rratio 0.25)
			(net 143 "/DDR3/DDR3_VTT")
			(pintype "passive")
		)
	)
	(footprint "antmicro-footprints:R_0402_1005Metric"
		(layer "B.Cu")
		(at 99.775 141.475 90)
		(descr "Resistor SMD 0402")
		(tags "resistor SMD 0402")
		(property "Reference" "R183"
			(at 0.775 0.425 90)
			(layer "B.SilkS")
			(effects
				(font
					(size 0.7 0.7)
					(thickness 0.15)
				)
				(justify right bottom mirror)
			)
		)
		(property "Value" "R_51R_0402"
			(at 0 -1.4 90)
			(layer "B.Fab")
			(effects
				(font
					(size 0.7 0.7)
					(thickness 0.15)
				)
				(justify right bottom mirror)
			)
		)
		(property "Datasheet" "https://www.bourns.com/docs/product-datasheets/cr.pdf"
			(at 0 0 90)
			(layer "F.Fab")
			(hide yes)
			(effects
				(font
					(size 1.27 1.27)
					(thickness 0.15)
				)
			)
		)
		(property "Description" "SMD Chip Resistor, 51 ohm, ± 1%, 63 mW, 0402 [1005 Metric], Thick Film, General Purpose"
			(at 0 0 90)
			(layer "F.Fab")
			(hide yes)
			(effects
				(font
					(size 1.27 1.27)
					(thickness 0.15)
				)
			)
		)
		(property "Author" "Antmicro"
			(at 241.25 41.7 0)
			(layer "B.Fab")
			(hide yes)
			(effects
				(font
					(size 1 1)
					(thickness 0.15)
				)
				(justify mirror)
			)
		)
		(property "License" "Apache-2.0"
			(at 241.25 41.7 0)
			(layer "B.Fab")
			(hide yes)
			(effects
				(font
					(size 1 1)
					(thickness 0.15)
				)
				(justify mirror)
			)
		)
		(property "MPN" "CR0402-FX-51R0GLF"
			(at 241.25 41.7 0)
			(layer "B.Fab")
			(hide yes)
			(effects
				(font
					(size 1 1)
					(thickness 0.15)
				)
				(justify mirror)
			)
		)
		(property "Manufacturer" "Bourns"
			(at 241.25 41.7 0)
			(layer "B.Fab")
			(hide yes)
			(effects
				(font
					(size 1 1)
					(thickness 0.15)
				)
				(justify mirror)
			)
		)
		(property "Tolerance" "1%"
			(at 241.25 41.7 0)
			(layer "B.Fab")
			(hide yes)
			(effects
				(font
					(size 1 1)
					(thickness 0.15)
				)
				(justify mirror)
			)
		)
		(property "Val" "51R"
			(at 241.25 41.7 0)
			(layer "B.Fab")
			(hide yes)
			(effects
				(font
					(size 1 1)
					(thickness 0.15)
				)
				(justify mirror)
			)
		)
		(sheetname "/DDR3/")
		(sheetfile "ddr3.kicad_sch")
		(attr smd exclude_from_pos_files exclude_from_bom dnp)
		(fp_rect
			(start -0.925 0.47)
			(end 0.925 -0.47)
			(stroke
				(width 0.05)
				(type default)
			)
			(fill no)
			(layer "B.CrtYd")
		)
		(fp_rect
			(start -0.5 0.25)
			(end 0.5 -0.25)
			(stroke
				(width 0.15)
				(type solid)
			)
			(fill no)
			(layer "B.Fab")
		)
		(pad "1" smd roundrect
			(at -0.48 0 90)
			(size 0.59 0.64)
			(layers "B.Cu" "B.Mask" "B.Paste")
			(roundrect_rratio 0.25)
			(net 154 "DDR3_A10")
			(pintype "passive")
		)
		(pad "2" smd roundrect
			(at 0.48 0 90)
			(size 0.59 0.64)
			(layers "B.Cu" "B.Mask" "B.Paste")
			(roundrect_rratio 0.25)
			(net 143 "/DDR3/DDR3_VTT")
			(pintype "passive")
		)
	)
	(footprint "antmicro-footprints:R_0402_1005Metric"
		(layer "B.Cu")
		(at 101.875 151.675)
		(descr "Resistor SMD 0402")
		(tags "resistor SMD 0402")
		(property "Reference" "R184"
			(at -3.575 0.325 0)
			(layer "B.SilkS")
			(effects
				(font
					(size 0.7 0.7)
					(thickness 0.15)
				)
				(justify right bottom mirror)
			)
		)
		(property "Value" "R_51R_0402"
			(at 0 -1.4 0)
			(layer "B.Fab")
			(effects
				(font
					(size 0.7 0.7)
					(thickness 0.15)
				)
				(justify right bottom mirror)
			)
		)
		(property "Datasheet" "https://www.bourns.com/docs/product-datasheets/cr.pdf"
			(at 0 0 0)
			(layer "F.Fab")
			(hide yes)
			(effects
				(font
					(size 1.27 1.27)
					(thickness 0.15)
				)
			)
		)
		(property "Description" "SMD Chip Resistor, 51 ohm, ± 1%, 63 mW, 0402 [1005 Metric], Thick Film, General Purpose"
			(at 0 0 0)
			(layer "F.Fab")
			(hide yes)
			(effects
				(font
					(size 1.27 1.27)
					(thickness 0.15)
				)
			)
		)
		(property "Author" "Antmicro"
			(at 0 0 0)
			(layer "B.Fab")
			(hide yes)
			(effects
				(font
					(size 1 1)
					(thickness 0.15)
				)
				(justify mirror)
			)
		)
		(property "License" "Apache-2.0"
			(at 0 0 0)
			(layer "B.Fab")
			(hide yes)
			(effects
				(font
					(size 1 1)
					(thickness 0.15)
				)
				(justify mirror)
			)
		)
		(property "MPN" "CR0402-FX-51R0GLF"
			(at 0 0 0)
			(layer "B.Fab")
			(hide yes)
			(effects
				(font
					(size 1 1)
					(thickness 0.15)
				)
				(justify mirror)
			)
		)
		(property "Manufacturer" "Bourns"
			(at 0 0 0)
			(layer "B.Fab")
			(hide yes)
			(effects
				(font
					(size 1 1)
					(thickness 0.15)
				)
				(justify mirror)
			)
		)
		(property "Tolerance" "1%"
			(at 0 0 0)
			(layer "B.Fab")
			(hide yes)
			(effects
				(font
					(size 1 1)
					(thickness 0.15)
				)
				(justify mirror)
			)
		)
		(property "Val" "51R"
			(at 0 0 0)
			(layer "B.Fab")
			(hide yes)
			(effects
				(font
					(size 1 1)
					(thickness 0.15)
				)
				(justify mirror)
			)
		)
		(sheetname "/DDR3/")
		(sheetfile "ddr3.kicad_sch")
		(attr smd exclude_from_pos_files exclude_from_bom dnp)
		(fp_rect
			(start -0.925 0.47)
			(end 0.925 -0.47)
			(stroke
				(width 0.05)
				(type default)
			)
			(fill no)
			(layer "B.CrtYd")
		)
		(fp_rect
			(start -0.5 0.25)
			(end 0.5 -0.25)
			(stroke
				(width 0.15)
				(type solid)
			)
			(fill no)
			(layer "B.Fab")
		)
		(pad "1" smd roundrect
			(at -0.48 0)
			(size 0.59 0.64)
			(layers "B.Cu" "B.Mask" "B.Paste")
			(roundrect_rratio 0.25)
			(net 163 "DDR3_CS")
			(pintype "passive")
		)
		(pad "2" smd roundrect
			(at 0.48 0)
			(size 0.59 0.64)
			(layers "B.Cu" "B.Mask" "B.Paste")
			(roundrect_rratio 0.25)
			(net 143 "/DDR3/DDR3_VTT")
			(pintype "passive")
		)
	)
	(footprint "antmicro-footprints:R_0402_1005Metric"
		(layer "B.Cu")
		(at 94.975 149.675 -90)
		(descr "Resistor SMD 0402")
		(tags "resistor SMD 0402")
		(property "Reference" "R54"
			(at 0.725 -0.425 90)
			(layer "B.SilkS")
			(effects
				(font
					(size 0.7 0.7)
					(thickness 0.15)
				)
				(justify left bottom mirror)
			)
		)
		(property "Value" "R_51R_0402"
			(at 0 -1.4 90)
			(layer "B.Fab")
			(effects
				(font
					(size 0.7 0.7)
					(thickness 0.15)
				)
				(justify left bottom mirror)
			)
		)
		(property "Datasheet" "https://www.bourns.com/docs/product-datasheets/cr.pdf"
			(at 0 0 270)
			(layer "F.Fab")
			(hide yes)
			(effects
				(font
					(size 1.27 1.27)
					(thickness 0.15)
				)
			)
		)
		(property "Description" "SMD Chip Resistor, 51 ohm, ± 1%, 63 mW, 0402 [1005 Metric], Thick Film, General Purpose"
			(at 0 0 270)
			(layer "F.Fab")
			(hide yes)
			(effects
				(font
					(size 1.27 1.27)
					(thickness 0.15)
				)
			)
		)
		(property "Author" "Antmicro"
			(at -54.7 244.65 0)
			(layer "B.Fab")
			(hide yes)
			(effects
				(font
					(size 1 1)
					(thickness 0.15)
				)
				(justify mirror)
			)
		)
		(property "License" "Apache-2.0"
			(at -54.7 244.65 0)
			(layer "B.Fab")
			(hide yes)
			(effects
				(font
					(size 1 1)
					(thickness 0.15)
				)
				(justify mirror)
			)
		)
		(property "MPN" "CR0402-FX-51R0GLF"
			(at -54.7 244.65 0)
			(layer "B.Fab")
			(hide yes)
			(effects
				(font
					(size 1 1)
					(thickness 0.15)
				)
				(justify mirror)
			)
		)
		(property "Manufacturer" "Bourns"
			(at -54.7 244.65 0)
			(layer "B.Fab")
			(hide yes)
			(effects
				(font
					(size 1 1)
					(thickness 0.15)
				)
				(justify mirror)
			)
		)
		(property "Tolerance" "1%"
			(at -54.7 244.65 0)
			(layer "B.Fab")
			(hide yes)
			(effects
				(font
					(size 1 1)
					(thickness 0.15)
				)
				(justify mirror)
			)
		)
		(property "Val" "51R"
			(at -54.7 244.65 0)
			(layer "B.Fab")
			(hide yes)
			(effects
				(font
					(size 1 1)
					(thickness 0.15)
				)
				(justify mirror)
			)
		)
		(sheetname "/DDR3/")
		(sheetfile "ddr3.kicad_sch")
		(attr smd exclude_from_pos_files exclude_from_bom dnp)
		(fp_rect
			(start -0.925 0.47)
			(end 0.925 -0.47)
			(stroke
				(width 0.05)
				(type default)
			)
			(fill no)
			(layer "B.CrtYd")
		)
		(fp_rect
			(start -0.5 0.25)
			(end 0.5 -0.25)
			(stroke
				(width 0.15)
				(type solid)
			)
			(fill no)
			(layer "B.Fab")
		)
		(pad "1" smd roundrect
			(at -0.48 0 270)
			(size 0.59 0.64)
			(layers "B.Cu" "B.Mask" "B.Paste")
			(roundrect_rratio 0.25)
			(net 162 "DDR3_RAS")
			(pintype "passive")
		)
		(pad "2" smd roundrect
			(at 0.48 0 270)
			(size 0.59 0.64)
			(layers "B.Cu" "B.Mask" "B.Paste")
			(roundrect_rratio 0.25)
			(net 143 "/DDR3/DDR3_VTT")
			(pintype "passive")
		)
	)
	(footprint "antmicro-footprints:C_0402_1005Metric"
		(layer "B.Cu")
		(at 103.775 116.675 180)
		(descr "Capacitor SMD 0402")
		(tags "capacitor SMD 0402")
		(property "Reference" "C238"
			(at -2.025 1.475 0)
			(layer "B.SilkS")
			(effects
				(font
					(size 0.7 0.7)
					(thickness 0.15)
				)
				(justify left bottom mirror)
			)
		)
		(property "Value" "C_470n_0402"
			(at 0 -1.4 0)
			(layer "B.Fab")
			(effects
				(font
					(size 0.7 0.7)
					(thickness 0.15)
				)
				(justify left bottom mirror)
			)
		)
		(property "Datasheet" "https://product.tdk.com/en/search/capacitor/ceramic/mlcc/info?part_no=C1005X5R1E474M050BB"
			(at 0 0 180)
			(layer "F.Fab")
			(hide yes)
			(effects
				(font
					(size 1.27 1.27)
					(thickness 0.15)
				)
			)
		)
		(property "Description" "SMD Multilayer Ceramic Capacitor, 0.47 µF, 25 V, 0402 [1005 Metric], ± 20%, X5R, C"
			(at 0 0 180)
			(layer "F.Fab")
			(hide yes)
			(effects
				(font
					(size 1.27 1.27)
					(thickness 0.15)
				)
			)
		)
		(property "Author" "Antmicro"
			(at 207.55 233.35 0)
			(layer "B.Fab")
			(hide yes)
			(effects
				(font
					(size 1 1)
					(thickness 0.15)
				)
				(justify mirror)
			)
		)
		(property "Dielectric" ""
			(at 207.55 233.35 0)
			(layer "B.Fab")
			(hide yes)
			(effects
				(font
					(size 1 1)
					(thickness 0.15)
				)
				(justify mirror)
			)
		)
		(property "License" "Apache-2.0"
			(at 207.55 233.35 0)
			(layer "B.Fab")
			(hide yes)
			(effects
				(font
					(size 1 1)
					(thickness 0.15)
				)
				(justify mirror)
			)
		)
		(property "MPN" "C1005X5R1E474M050BB"
			(at 207.55 233.35 0)
			(layer "B.Fab")
			(hide yes)
			(effects
				(font
					(size 1 1)
					(thickness 0.15)
				)
				(justify mirror)
			)
		)
		(property "Manufacturer" "TDK"
			(at 207.55 233.35 0)
			(layer "B.Fab")
			(hide yes)
			(effects
				(font
					(size 1 1)
					(thickness 0.15)
				)
				(justify mirror)
			)
		)
		(property "Val" "470n"
			(at 207.55 233.35 0)
			(layer "B.Fab")
			(hide yes)
			(effects
				(font
					(size 1 1)
					(thickness 0.15)
				)
				(justify mirror)
			)
		)
		(property "Voltage" ""
			(at 207.55 233.35 0)
			(layer "B.Fab")
			(hide yes)
			(effects
				(font
					(size 1 1)
					(thickness 0.15)
				)
				(justify mirror)
			)
		)
		(property "DNP" ""
			(at 0 0 180)
			(unlocked yes)
			(layer "B.Fab")
			(hide yes)
			(effects
				(font
					(size 1 1)
					(thickness 0.15)
				)
				(justify mirror)
			)
		)
		(sheetname "/FPGA banks 13-16/")
		(sheetfile "fpga-banks-13-16.kicad_sch")
		(attr smd)
		(fp_rect
			(start -0.925 0.47)
			(end 0.925 -0.47)
			(stroke
				(width 0.05)
				(type default)
			)
			(fill no)
			(layer "B.CrtYd")
		)
		(fp_line
			(start 0.504 0.25)
			(end 0.504 -0.248)
			(stroke
				(width 0.15)
				(type solid)
			)
			(layer "B.Fab")
		)
		(fp_line
			(start 0.504 -0.248)
			(end -0.494 -0.248)
			(stroke
				(width 0.15)
				(type solid)
			)
			(layer "B.Fab")
		)
		(fp_line
			(start -0.494 0.25)
			(end 0.504 0.25)
			(stroke
				(width 0.15)
				(type solid)
			)
			(layer "B.Fab")
		)
		(fp_line
			(start -0.494 -0.248)
			(end -0.494 0.25)
			(stroke
				(width 0.15)
				(type solid)
			)
			(layer "B.Fab")
		)
		(pad "1" smd roundrect
			(at -0.48 0 180)
			(size 0.59 0.64)
			(layers "B.Cu" "B.Mask" "B.Paste")
			(roundrect_rratio 0.25)
			(net 1 "GND")
			(pintype "passive")
		)
		(pad "2" smd roundrect
			(at 0.48 0 180)
			(size 0.59 0.64)
			(layers "B.Cu" "B.Mask" "B.Paste")
			(roundrect_rratio 0.25)
			(net 2 "VCC3V3")
			(pintype "passive")
		)
	)
	(footprint "antmicro-footprints:R_0402_1005Metric"
		(layer "B.Cu")
		(at 104.175 141.875 90)
		(descr "Resistor SMD 0402")
		(tags "resistor SMD 0402")
		(property "Reference" "R180"
			(at 0.775 0.425 90)
			(layer "B.SilkS")
			(effects
				(font
					(size 0.7 0.7)
					(thickness 0.15)
				)
				(justify right bottom mirror)
			)
		)
		(property "Value" "R_51R_0402"
			(at 0 -1.4 90)
			(layer "B.Fab")
			(effects
				(font
					(size 0.7 0.7)
					(thickness 0.15)
				)
				(justify right bottom mirror)
			)
		)
		(property "Datasheet" "https://www.bourns.com/docs/product-datasheets/cr.pdf"
			(at 0 0 90)
			(layer "F.Fab")
			(hide yes)
			(effects
				(font
					(size 1.27 1.27)
					(thickness 0.15)
				)
			)
		)
		(property "Description" "SMD Chip Resistor, 51 ohm, ± 1%, 63 mW, 0402 [1005 Metric], Thick Film, General Purpose"
			(at 0 0 90)
			(layer "F.Fab")
			(hide yes)
			(effects
				(font
					(size 1.27 1.27)
					(thickness 0.15)
				)
			)
		)
		(property "Author" "Antmicro"
			(at 246.05 37.7 0)
			(layer "B.Fab")
			(hide yes)
			(effects
				(font
					(size 1 1)
					(thickness 0.15)
				)
				(justify mirror)
			)
		)
		(property "License" "Apache-2.0"
			(at 246.05 37.7 0)
			(layer "B.Fab")
			(hide yes)
			(effects
				(font
					(size 1 1)
					(thickness 0.15)
				)
				(justify mirror)
			)
		)
		(property "MPN" "CR0402-FX-51R0GLF"
			(at 246.05 37.7 0)
			(layer "B.Fab")
			(hide yes)
			(effects
				(font
					(size 1 1)
					(thickness 0.15)
				)
				(justify mirror)
			)
		)
		(property "Manufacturer" "Bourns"
			(at 246.05 37.7 0)
			(layer "B.Fab")
			(hide yes)
			(effects
				(font
					(size 1 1)
					(thickness 0.15)
				)
				(justify mirror)
			)
		)
		(property "Tolerance" "1%"
			(at 246.05 37.7 0)
			(layer "B.Fab")
			(hide yes)
			(effects
				(font
					(size 1 1)
					(thickness 0.15)
				)
				(justify mirror)
			)
		)
		(property "Val" "51R"
			(at 246.05 37.7 0)
			(layer "B.Fab")
			(hide yes)
			(effects
				(font
					(size 1 1)
					(thickness 0.15)
				)
				(justify mirror)
			)
		)
		(sheetname "/DDR3/")
		(sheetfile "ddr3.kicad_sch")
		(attr smd exclude_from_pos_files exclude_from_bom dnp)
		(fp_rect
			(start -0.925 0.47)
			(end 0.925 -0.47)
			(stroke
				(width 0.05)
				(type default)
			)
			(fill no)
			(layer "B.CrtYd")
		)
		(fp_rect
			(start -0.5 0.25)
			(end 0.5 -0.25)
			(stroke
				(width 0.15)
				(type solid)
			)
			(fill no)
			(layer "B.Fab")
		)
		(pad "1" smd roundrect
			(at -0.48 0 90)
			(size 0.59 0.64)
			(layers "B.Cu" "B.Mask" "B.Paste")
			(roundrect_rratio 0.25)
			(net 145 "DDR3_A8")
			(pintype "passive")
		)
		(pad "2" smd roundrect
			(at 0.48 0 90)
			(size 0.59 0.64)
			(layers "B.Cu" "B.Mask" "B.Paste")
			(roundrect_rratio 0.25)
			(net 143 "/DDR3/DDR3_VTT")
			(pintype "passive")
		)
	)
	(footprint "antmicro-footprints:C_0402_1005Metric"
		(layer "B.Cu")
		(at 90.275 112.475 -90)
		(descr "Capacitor SMD 0402")
		(tags "capacitor SMD 0402")
		(property "Reference" "C239"
			(at -1.375 0.475 90)
			(layer "B.SilkS")
			(effects
				(font
					(size 0.7 0.7)
					(thickness 0.15)
				)
				(justify left bottom mirror)
			)
		)
		(property "Value" "C_470n_0402"
			(at 0 -1.4 90)
			(layer "B.Fab")
			(effects
				(font
					(size 0.7 0.7)
					(thickness 0.15)
				)
				(justify left bottom mirror)
			)
		)
		(property "Datasheet" "https://product.tdk.com/en/search/capacitor/ceramic/mlcc/info?part_no=C1005X5R1E474M050BB"
			(at 0 0 270)
			(layer "F.Fab")
			(hide yes)
			(effects
				(font
					(size 1.27 1.27)
					(thickness 0.15)
				)
			)
		)
		(property "Description" "SMD Multilayer Ceramic Capacitor, 0.47 µF, 25 V, 0402 [1005 Metric], ± 20%, X5R, C"
			(at 0 0 270)
			(layer "F.Fab")
			(hide yes)
			(effects
				(font
					(size 1.27 1.27)
					(thickness 0.15)
				)
			)
		)
		(property "Author" "Antmicro"
			(at -22.2 202.75 0)
			(layer "B.Fab")
			(hide yes)
			(effects
				(font
					(size 1 1)
					(thickness 0.15)
				)
				(justify mirror)
			)
		)
		(property "Dielectric" ""
			(at -22.2 202.75 0)
			(layer "B.Fab")
			(hide yes)
			(effects
				(font
					(size 1 1)
					(thickness 0.15)
				)
				(justify mirror)
			)
		)
		(property "License" "Apache-2.0"
			(at -22.2 202.75 0)
			(layer "B.Fab")
			(hide yes)
			(effects
				(font
					(size 1 1)
					(thickness 0.15)
				)
				(justify mirror)
			)
		)
		(property "MPN" "C1005X5R1E474M050BB"
			(at -22.2 202.75 0)
			(layer "B.Fab")
			(hide yes)
			(effects
				(font
					(size 1 1)
					(thickness 0.15)
				)
				(justify mirror)
			)
		)
		(property "Manufacturer" "TDK"
			(at -22.2 202.75 0)
			(layer "B.Fab")
			(hide yes)
			(effects
				(font
					(size 1 1)
					(thickness 0.15)
				)
				(justify mirror)
			)
		)
		(property "Val" "470n"
			(at -22.2 202.75 0)
			(layer "B.Fab")
			(hide yes)
			(effects
				(font
					(size 1 1)
					(thickness 0.15)
				)
				(justify mirror)
			)
		)
		(property "Voltage" ""
			(at -22.2 202.75 0)
			(layer "B.Fab")
			(hide yes)
			(effects
				(font
					(size 1 1)
					(thickness 0.15)
				)
				(justify mirror)
			)
		)
		(sheetname "/FPGA banks 34-35 & CFG/")
		(sheetfile "fpga-banks-34-25-cfg.kicad_sch")
		(attr smd)
		(fp_rect
			(start -0.925 0.47)
			(end 0.925 -0.47)
			(stroke
				(width 0.05)
				(type default)
			)
			(fill no)
			(layer "B.CrtYd")
		)
		(fp_line
			(start -0.494 0.25)
			(end 0.504 0.25)
			(stroke
				(width 0.15)
				(type solid)
			)
			(layer "B.Fab")
		)
		(fp_line
			(start 0.504 0.25)
			(end 0.504 -0.248)
			(stroke
				(width 0.15)
				(type solid)
			)
			(layer "B.Fab")
		)
		(fp_line
			(start -0.494 -0.248)
			(end -0.494 0.25)
			(stroke
				(width 0.15)
				(type solid)
			)
			(layer "B.Fab")
		)
		(fp_line
			(start 0.504 -0.248)
			(end -0.494 -0.248)
			(stroke
				(width 0.15)
				(type solid)
			)
			(layer "B.Fab")
		)
		(pad "1" smd roundrect
			(at -0.48 0 270)
			(size 0.59 0.64)
			(layers "B.Cu" "B.Mask" "B.Paste")
			(roundrect_rratio 0.25)
			(net 1 "GND")
			(pintype "passive")
		)
		(pad "2" smd roundrect
			(at 0.48 0 270)
			(size 0.59 0.64)
			(layers "B.Cu" "B.Mask" "B.Paste")
			(roundrect_rratio 0.25)
			(net 2 "VCC3V3")
			(pintype "passive")
		)
	)
	(footprint "antmicro-footprints:C_0402_1005Metric"
		(layer "B.Cu")
		(at 90.825 117.325)
		(descr "Capacitor SMD 0402")
		(tags "capacitor SMD 0402")
		(property "Reference" "C240"
			(at -3.625 0.375 0)
			(layer "B.SilkS")
			(effects
				(font
					(size 0.7 0.7)
					(thickness 0.15)
				)
				(justify right bottom mirror)
			)
		)
		(property "Value" "C_470n_0402"
			(at 0 -1.4 0)
			(layer "B.Fab")
			(effects
				(font
					(size 0.7 0.7)
					(thickness 0.15)
				)
				(justify right bottom mirror)
			)
		)
		(property "Datasheet" "https://product.tdk.com/en/search/capacitor/ceramic/mlcc/info?part_no=C1005X5R1E474M050BB"
			(at 0 0 0)
			(layer "F.Fab")
			(hide yes)
			(effects
				(font
					(size 1.27 1.27)
					(thickness 0.15)
				)
			)
		)
		(property "Description" "SMD Multilayer Ceramic Capacitor, 0.47 µF, 25 V, 0402 [1005 Metric], ± 20%, X5R, C"
			(at 0 0 0)
			(layer "F.Fab")
			(hide yes)
			(effects
				(font
					(size 1.27 1.27)
					(thickness 0.15)
				)
			)
		)
		(property "Author" "Antmicro"
			(at 0 0 0)
			(layer "B.Fab")
			(hide yes)
			(effects
				(font
					(size 1 1)
					(thickness 0.15)
				)
				(justify mirror)
			)
		)
		(property "Dielectric" ""
			(at 0 0 0)
			(layer "B.Fab")
			(hide yes)
			(effects
				(font
					(size 1 1)
					(thickness 0.15)
				)
				(justify mirror)
			)
		)
		(property "License" "Apache-2.0"
			(at 0 0 0)
			(layer "B.Fab")
			(hide yes)
			(effects
				(font
					(size 1 1)
					(thickness 0.15)
				)
				(justify mirror)
			)
		)
		(property "MPN" "C1005X5R1E474M050BB"
			(at 0 0 0)
			(layer "B.Fab")
			(hide yes)
			(effects
				(font
					(size 1 1)
					(thickness 0.15)
				)
				(justify mirror)
			)
		)
		(property "Manufacturer" "TDK"
			(at 0 0 0)
			(layer "B.Fab")
			(hide yes)
			(effects
				(font
					(size 1 1)
					(thickness 0.15)
				)
				(justify mirror)
			)
		)
		(property "Val" "470n"
			(at 0 0 0)
			(layer "B.Fab")
			(hide yes)
			(effects
				(font
					(size 1 1)
					(thickness 0.15)
				)
				(justify mirror)
			)
		)
		(property "Voltage" ""
			(at 0 0 0)
			(layer "B.Fab")
			(hide yes)
			(effects
				(font
					(size 1 1)
					(thickness 0.15)
				)
				(justify mirror)
			)
		)
		(sheetname "/FPGA banks 13-16/")
		(sheetfile "fpga-banks-13-16.kicad_sch")
		(attr smd)
		(fp_rect
			(start -0.925 0.47)
			(end 0.925 -0.47)
			(stroke
				(width 0.05)
				(type default)
			)
			(fill no)
			(layer "B.CrtYd")
		)
		(fp_line
			(start -0.494 -0.248)
			(end -0.494 0.25)
			(stroke
				(width 0.15)
				(type solid)
			)
			(layer "B.Fab")
		)
		(fp_line
			(start -0.494 0.25)
			(end 0.504 0.25)
			(stroke
				(width 0.15)
				(type solid)
			)
			(layer "B.Fab")
		)
		(fp_line
			(start 0.504 -0.248)
			(end -0.494 -0.248)
			(stroke
				(width 0.15)
				(type solid)
			)
			(layer "B.Fab")
		)
		(fp_line
			(start 0.504 0.25)
			(end 0.504 -0.248)
			(stroke
				(width 0.15)
				(type solid)
			)
			(layer "B.Fab")
		)
		(pad "1" smd roundrect
			(at -0.48 0)
			(size 0.59 0.64)
			(layers "B.Cu" "B.Mask" "B.Paste")
			(roundrect_rratio 0.25)
			(net 1 "GND")
			(pintype "passive")
		)
		(pad "2" smd roundrect
			(at 0.48 0)
			(size 0.59 0.64)
			(layers "B.Cu" "B.Mask" "B.Paste")
			(roundrect_rratio 0.25)
			(net 2 "VCC3V3")
			(pintype "passive")
		)
	)
	(footprint "antmicro-footprints:R_0402_1005Metric"
		(layer "B.Cu")
		(at 91.975 158.875 180)
		(descr "Resistor SMD 0402")
		(tags "resistor SMD 0402")
		(property "Reference" "R88"
			(at 0.775 -0.325 0)
			(layer "B.SilkS")
			(effects
				(font
					(size 0.7 0.7)
					(thickness 0.15)
				)
				(justify left bottom mirror)
			)
		)
		(property "Value" "R_200R_0402"
			(at 0 -1.4 0)
			(layer "B.Fab")
			(effects
				(font
					(size 0.7 0.7)
					(thickness 0.15)
				)
				(justify left bottom mirror)
			)
		)
		(property "Datasheet" "https://www.bourns.com/docs/product-datasheets/cr.pdf"
			(at 0 0 180)
			(layer "F.Fab")
			(hide yes)
			(effects
				(font
					(size 1.27 1.27)
					(thickness 0.15)
				)
			)
		)
		(property "Description" "SMD Chip Resistor, 200 ohm, ± 1%, 62.5 mW, 0402 [1005 Metric], Thick Film, General Purpose"
			(at 0 0 180)
			(layer "F.Fab")
			(hide yes)
			(effects
				(font
					(size 1.27 1.27)
					(thickness 0.15)
				)
			)
		)
		(property "Author" "Antmicro"
			(at 183.95 317.75 0)
			(layer "B.Fab")
			(hide yes)
			(effects
				(font
					(size 1 1)
					(thickness 0.15)
				)
				(justify mirror)
			)
		)
		(property "License" "Apache-2.0"
			(at 183.95 317.75 0)
			(layer "B.Fab")
			(hide yes)
			(effects
				(font
					(size 1 1)
					(thickness 0.15)
				)
				(justify mirror)
			)
		)
		(property "MPN" "CR0402-FX-2000GLF"
			(at 183.95 317.75 0)
			(layer "B.Fab")
			(hide yes)
			(effects
				(font
					(size 1 1)
					(thickness 0.15)
				)
				(justify mirror)
			)
		)
		(property "Manufacturer" "Bourns"
			(at 183.95 317.75 0)
			(layer "B.Fab")
			(hide yes)
			(effects
				(font
					(size 1 1)
					(thickness 0.15)
				)
				(justify mirror)
			)
		)
		(property "Tolerance" "1%"
			(at 183.95 317.75 0)
			(layer "B.Fab")
			(hide yes)
			(effects
				(font
					(size 1 1)
					(thickness 0.15)
				)
				(justify mirror)
			)
		)
		(property "Val" "200R"
			(at 183.95 317.75 0)
			(layer "B.Fab")
			(hide yes)
			(effects
				(font
					(size 1 1)
					(thickness 0.15)
				)
				(justify mirror)
			)
		)
		(sheetname "/FPGA banks 34-35 & CFG/")
		(sheetfile "fpga-banks-34-25-cfg.kicad_sch")
		(attr smd)
		(fp_rect
			(start -0.925 0.47)
			(end 0.925 -0.47)
			(stroke
				(width 0.05)
				(type default)
			)
			(fill no)
			(layer "B.CrtYd")
		)
		(fp_rect
			(start -0.5 0.25)
			(end 0.5 -0.25)
			(stroke
				(width 0.15)
				(type solid)
			)
			(fill no)
			(layer "B.Fab")
		)
		(pad "1" smd roundrect
			(at -0.48 0 180)
			(size 0.59 0.64)
			(layers "B.Cu" "B.Mask" "B.Paste")
			(roundrect_rratio 0.25)
			(net 2 "VCC3V3")
			(pintype "passive")
		)
		(pad "2" smd roundrect
			(at 0.48 0 180)
			(size 0.59 0.64)
			(layers "B.Cu" "B.Mask" "B.Paste")
			(roundrect_rratio 0.25)
			(net 220 "DONE")
			(pintype "passive")
		)
	)
	(footprint "antmicro-footprints:C_0402_1005Metric"
		(layer "B.Cu")
		(at 91.175 122.675)
		(descr "Capacitor SMD 0402")
		(tags "capacitor SMD 0402")
		(property "Reference" "C193"
			(at -3.675 0.325 0)
			(layer "B.SilkS")
			(effects
				(font
					(size 0.7 0.7)
					(thickness 0.15)
				)
				(justify right bottom mirror)
			)
		)
		(property "Value" "C_100n_6V3_0402"
			(at 0 -1.4 0)
			(layer "B.Fab")
			(effects
				(font
					(size 0.7 0.7)
					(thickness 0.15)
				)
				(justify right bottom mirror)
			)
		)
		(property "Datasheet" "https://www.passivecomponent.com/wp-content/uploads/datasheet/WTC_MLCC_General_Purpose.pdf"
			(at 0 0 0)
			(layer "F.Fab")
			(hide yes)
			(effects
				(font
					(size 1.27 1.27)
					(thickness 0.15)
				)
			)
		)
		(property "Description" "SMT Multilayer Ceramic Capacitor, 0.1 µF, 6.3 V, 0402 [1005 Metric], ± 10%, X5R, Walsin MLCC"
			(at 0 0 0)
			(layer "F.Fab")
			(hide yes)
			(effects
				(font
					(size 1.27 1.27)
					(thickness 0.15)
				)
			)
		)
		(property "Author" "Antmicro"
			(at 0 0 0)
			(layer "B.Fab")
			(hide yes)
			(effects
				(font
					(size 1 1)
					(thickness 0.15)
				)
				(justify mirror)
			)
		)
		(property "Dielectric" ""
			(at 0 0 0)
			(layer "B.Fab")
			(hide yes)
			(effects
				(font
					(size 1 1)
					(thickness 0.15)
				)
				(justify mirror)
			)
		)
		(property "License" "Apache-2.0"
			(at 0 0 0)
			(layer "B.Fab")
			(hide yes)
			(effects
				(font
					(size 1 1)
					(thickness 0.15)
				)
				(justify mirror)
			)
		)
		(property "MPN" "0402X104K6R3CT"
			(at 0 0 0)
			(layer "B.Fab")
			(hide yes)
			(effects
				(font
					(size 1 1)
					(thickness 0.15)
				)
				(justify mirror)
			)
		)
		(property "Manufacturer" "Walsin"
			(at 0 0 0)
			(layer "B.Fab")
			(hide yes)
			(effects
				(font
					(size 1 1)
					(thickness 0.15)
				)
				(justify mirror)
			)
		)
		(property "Public" "False"
			(at 0 0 0)
			(layer "B.Fab")
			(hide yes)
			(effects
				(font
					(size 1 1)
					(thickness 0.15)
				)
				(justify mirror)
			)
		)
		(property "Val" "100n"
			(at 0 0 0)
			(layer "B.Fab")
			(hide yes)
			(effects
				(font
					(size 1 1)
					(thickness 0.15)
				)
				(justify mirror)
			)
		)
		(property "Voltage" ""
			(at 0 0 0)
			(layer "B.Fab")
			(hide yes)
			(effects
				(font
					(size 1 1)
					(thickness 0.15)
				)
				(justify mirror)
			)
		)
		(sheetname "/Interfaces/")
		(sheetfile "interfaces.kicad_sch")
		(attr smd)
		(fp_rect
			(start -0.925 0.47)
			(end 0.925 -0.47)
			(stroke
				(width 0.05)
				(type default)
			)
			(fill no)
			(layer "B.CrtYd")
		)
		(fp_line
			(start -0.494 -0.248)
			(end -0.494 0.25)
			(stroke
				(width 0.15)
				(type solid)
			)
			(layer "B.Fab")
		)
		(fp_line
			(start -0.494 0.25)
			(end 0.504 0.25)
			(stroke
				(width 0.15)
				(type solid)
			)
			(layer "B.Fab")
		)
		(fp_line
			(start 0.504 -0.248)
			(end -0.494 -0.248)
			(stroke
				(width 0.15)
				(type solid)
			)
			(layer "B.Fab")
		)
		(fp_line
			(start 0.504 0.25)
			(end 0.504 -0.248)
			(stroke
				(width 0.15)
				(type solid)
			)
			(layer "B.Fab")
		)
		(pad "1" smd roundrect
			(at -0.48 0)
			(size 0.59 0.64)
			(layers "B.Cu" "B.Mask" "B.Paste")
			(roundrect_rratio 0.25)
			(net 1 "GND")
			(pintype "passive")
		)
		(pad "2" smd roundrect
			(at 0.48 0)
			(size 0.59 0.64)
			(layers "B.Cu" "B.Mask" "B.Paste")
			(roundrect_rratio 0.25)
			(net 339 "VCC1V2")
			(pintype "passive")
		)
	)
	(footprint "antmicro-footprints:R_0402_1005Metric"
		(layer "B.Cu")
		(at 93.965 91.065 -90)
		(descr "Resistor SMD 0402")
		(tags "resistor SMD 0402")
		(property "Reference" "R165"
			(at -3.965 0.365 90)
			(layer "B.SilkS")
			(effects
				(font
					(size 0.7 0.7)
					(thickness 0.15)
				)
				(justify left bottom mirror)
			)
		)
		(property "Value" "R_220R_0402"
			(at 0 -1.4 90)
			(layer "B.Fab")
			(effects
				(font
					(size 0.7 0.7)
					(thickness 0.15)
				)
				(justify left bottom mirror)
			)
		)
		(property "Datasheet" "https://www.bourns.com/docs/product-datasheets/cr.pdf"
			(at 0 0 270)
			(layer "F.Fab")
			(hide yes)
			(effects
				(font
					(size 1.27 1.27)
					(thickness 0.15)
				)
			)
		)
		(property "Description" "SMD Chip Resistor, 220 ohm, ± 1%, 62.5 mW, 0402 [1005 Metric], Thick Film, General Purpose"
			(at 0 0 270)
			(layer "F.Fab")
			(hide yes)
			(effects
				(font
					(size 1.27 1.27)
					(thickness 0.15)
				)
			)
		)
		(property "Author" "Antmicro"
			(at 2.9 185.03 0)
			(layer "B.Fab")
			(hide yes)
			(effects
				(font
					(size 1 1)
					(thickness 0.15)
				)
				(justify mirror)
			)
		)
		(property "License" "Apache-2.0"
			(at 2.9 185.03 0)
			(layer "B.Fab")
			(hide yes)
			(effects
				(font
					(size 1 1)
					(thickness 0.15)
				)
				(justify mirror)
			)
		)
		(property "MPN" "CR0402-FX-2200GLF"
			(at 2.9 185.03 0)
			(layer "B.Fab")
			(hide yes)
			(effects
				(font
					(size 1 1)
					(thickness 0.15)
				)
				(justify mirror)
			)
		)
		(property "Manufacturer" "Bourns"
			(at 2.9 185.03 0)
			(layer "B.Fab")
			(hide yes)
			(effects
				(font
					(size 1 1)
					(thickness 0.15)
				)
				(justify mirror)
			)
		)
		(property "Tolerance" "1%"
			(at 2.9 185.03 0)
			(layer "B.Fab")
			(hide yes)
			(effects
				(font
					(size 1 1)
					(thickness 0.15)
				)
				(justify mirror)
			)
		)
		(property "Val" "220R"
			(at 2.9 185.03 0)
			(layer "B.Fab")
			(hide yes)
			(effects
				(font
					(size 1 1)
					(thickness 0.15)
				)
				(justify mirror)
			)
		)
		(sheetname "/Ethernet/")
		(sheetfile "ethernet.kicad_sch")
		(attr smd)
		(fp_rect
			(start -0.925 0.47)
			(end 0.925 -0.47)
			(stroke
				(width 0.05)
				(type default)
			)
			(fill no)
			(layer "B.CrtYd")
		)
		(fp_rect
			(start -0.5 0.25)
			(end 0.5 -0.25)
			(stroke
				(width 0.15)
				(type solid)
			)
			(fill no)
			(layer "B.Fab")
		)
		(pad "1" smd roundrect
			(at -0.48 0 270)
			(size 0.59 0.64)
			(layers "B.Cu" "B.Mask" "B.Paste")
			(roundrect_rratio 0.25)
			(net 575 "Net-(J1-Pad13)")
			(pintype "passive")
		)
		(pad "2" smd roundrect
			(at 0.48 0 270)
			(size 0.59 0.64)
			(layers "B.Cu" "B.Mask" "B.Paste")
			(roundrect_rratio 0.25)
			(net 415 "/Ethernet/ETH_LED1")
			(pintype "passive")
		)
	)
	(footprint "antmicro-footprints:C_0402_1005Metric"
		(layer "B.Cu")
		(at 91.775 124.375)
		(descr "Capacitor SMD 0402")
		(tags "capacitor SMD 0402")
		(property "Reference" "C241"
			(at -3.775 0.325 0)
			(layer "B.SilkS")
			(effects
				(font
					(size 0.7 0.7)
					(thickness 0.15)
				)
				(justify right bottom mirror)
			)
		)
		(property "Value" "C_100n_6V3_0402"
			(at 0 -1.4 0)
			(layer "B.Fab")
			(effects
				(font
					(size 0.7 0.7)
					(thickness 0.15)
				)
				(justify right bottom mirror)
			)
		)
		(property "Datasheet" "https://www.passivecomponent.com/wp-content/uploads/datasheet/WTC_MLCC_General_Purpose.pdf"
			(at 0 0 0)
			(layer "F.Fab")
			(hide yes)
			(effects
				(font
					(size 1.27 1.27)
					(thickness 0.15)
				)
			)
		)
		(property "Description" "SMT Multilayer Ceramic Capacitor, 0.1 µF, 6.3 V, 0402 [1005 Metric], ± 10%, X5R, Walsin MLCC"
			(at 0 0 0)
			(layer "F.Fab")
			(hide yes)
			(effects
				(font
					(size 1.27 1.27)
					(thickness 0.15)
				)
			)
		)
		(property "Author" "Antmicro"
			(at 0 0 0)
			(layer "B.Fab")
			(hide yes)
			(effects
				(font
					(size 1 1)
					(thickness 0.15)
				)
				(justify mirror)
			)
		)
		(property "Dielectric" ""
			(at 0 0 0)
			(layer "B.Fab")
			(hide yes)
			(effects
				(font
					(size 1 1)
					(thickness 0.15)
				)
				(justify mirror)
			)
		)
		(property "License" "Apache-2.0"
			(at 0 0 0)
			(layer "B.Fab")
			(hide yes)
			(effects
				(font
					(size 1 1)
					(thickness 0.15)
				)
				(justify mirror)
			)
		)
		(property "MPN" "0402X104K6R3CT"
			(at 0 0 0)
			(layer "B.Fab")
			(hide yes)
			(effects
				(font
					(size 1 1)
					(thickness 0.15)
				)
				(justify mirror)
			)
		)
		(property "Manufacturer" "Walsin"
			(at 0 0 0)
			(layer "B.Fab")
			(hide yes)
			(effects
				(font
					(size 1 1)
					(thickness 0.15)
				)
				(justify mirror)
			)
		)
		(property "Public" "False"
			(at 0 0 0)
			(layer "B.Fab")
			(hide yes)
			(effects
				(font
					(size 1 1)
					(thickness 0.15)
				)
				(justify mirror)
			)
		)
		(property "Val" "100n"
			(at 0 0 0)
			(layer "B.Fab")
			(hide yes)
			(effects
				(font
					(size 1 1)
					(thickness 0.15)
				)
				(justify mirror)
			)
		)
		(property "Voltage" ""
			(at 0 0 0)
			(layer "B.Fab")
			(hide yes)
			(effects
				(font
					(size 1 1)
					(thickness 0.15)
				)
				(justify mirror)
			)
		)
		(sheetname "/Interfaces/")
		(sheetfile "interfaces.kicad_sch")
		(attr smd)
		(fp_rect
			(start -0.925 0.47)
			(end 0.925 -0.47)
			(stroke
				(width 0.05)
				(type default)
			)
			(fill no)
			(layer "B.CrtYd")
		)
		(fp_line
			(start -0.494 -0.248)
			(end -0.494 0.25)
			(stroke
				(width 0.15)
				(type solid)
			)
			(layer "B.Fab")
		)
		(fp_line
			(start -0.494 0.25)
			(end 0.504 0.25)
			(stroke
				(width 0.15)
				(type solid)
			)
			(layer "B.Fab")
		)
		(fp_line
			(start 0.504 -0.248)
			(end -0.494 -0.248)
			(stroke
				(width 0.15)
				(type solid)
			)
			(layer "B.Fab")
		)
		(fp_line
			(start 0.504 0.25)
			(end 0.504 -0.248)
			(stroke
				(width 0.15)
				(type solid)
			)
			(layer "B.Fab")
		)
		(pad "1" smd roundrect
			(at -0.48 0)
			(size 0.59 0.64)
			(layers "B.Cu" "B.Mask" "B.Paste")
			(roundrect_rratio 0.25)
			(net 1 "GND")
			(pintype "passive")
		)
		(pad "2" smd roundrect
			(at 0.48 0)
			(size 0.59 0.64)
			(layers "B.Cu" "B.Mask" "B.Paste")
			(roundrect_rratio 0.25)
			(net 339 "VCC1V2")
			(pintype "passive")
		)
	)
	(footprint "antmicro-footprints:C_0201"
		(layer "B.Cu")
		(at 99.225 123.675 180)
		(descr "Capacitor SMD 0201")
		(tags "capacitor SMD 0201")
		(property "Reference" "C153"
			(at -1.075 0.375 0)
			(layer "B.SilkS")
			(effects
				(font
					(size 0.7 0.7)
					(thickness 0.15)
				)
				(justify left bottom mirror)
			)
		)
		(property "Value" "C_470n_0201"
			(at 0 -1.4 0)
			(layer "B.Fab")
			(effects
				(font
					(size 0.7 0.7)
					(thickness 0.15)
				)
				(justify left bottom mirror)
			)
		)
		(property "Datasheet" "https://product.tdk.com/en/search/capacitor/ceramic/mlcc/info?part_no=C0603X5R1A474M030BC"
			(at 0 0 180)
			(layer "F.Fab")
			(hide yes)
			(effects
				(font
					(size 1.27 1.27)
					(thickness 0.15)
				)
			)
		)
		(property "Description" "SMD Multilayer Ceramic Capacitor, 0.47 µF, 10 V, 0201 [0603 Metric], ± 20%, X5R, C"
			(at 0 0 180)
			(layer "F.Fab")
			(hide yes)
			(effects
				(font
					(size 1.27 1.27)
					(thickness 0.15)
				)
			)
		)
		(property "Author" "Antmicro"
			(at 198.45 247.35 0)
			(layer "B.Fab")
			(hide yes)
			(effects
				(font
					(size 1 1)
					(thickness 0.15)
				)
				(justify mirror)
			)
		)
		(property "Dielectric" ""
			(at 198.45 247.35 0)
			(layer "B.Fab")
			(hide yes)
			(effects
				(font
					(size 1 1)
					(thickness 0.15)
				)
				(justify mirror)
			)
		)
		(property "License" "Apache-2.0"
			(at 198.45 247.35 0)
			(layer "B.Fab")
			(hide yes)
			(effects
				(font
					(size 1 1)
					(thickness 0.15)
				)
				(justify mirror)
			)
		)
		(property "MPN" "C0603X5R1A474M030BC"
			(at 198.45 247.35 0)
			(layer "B.Fab")
			(hide yes)
			(effects
				(font
					(size 1 1)
					(thickness 0.15)
				)
				(justify mirror)
			)
		)
		(property "Manufacturer" "TDK"
			(at 198.45 247.35 0)
			(layer "B.Fab")
			(hide yes)
			(effects
				(font
					(size 1 1)
					(thickness 0.15)
				)
				(justify mirror)
			)
		)
		(property "Public" "False"
			(at 198.45 247.35 0)
			(layer "B.Fab")
			(hide yes)
			(effects
				(font
					(size 1 1)
					(thickness 0.15)
				)
				(justify mirror)
			)
		)
		(property "Val" "470n"
			(at 198.45 247.35 0)
			(layer "B.Fab")
			(hide yes)
			(effects
				(font
					(size 1 1)
					(thickness 0.15)
				)
				(justify mirror)
			)
		)
		(property "Voltage" ""
			(at 198.45 247.35 0)
			(layer "B.Fab")
			(hide yes)
			(effects
				(font
					(size 1 1)
					(thickness 0.15)
				)
				(justify mirror)
			)
		)
		(property "DNP" ""
			(at 0 0 180)
			(unlocked yes)
			(layer "B.Fab")
			(hide yes)
			(effects
				(font
					(size 1 1)
					(thickness 0.15)
				)
				(justify mirror)
			)
		)
		(sheetname "/FPGA power supply/")
		(sheetfile "fpga-power-supply.kicad_sch")
		(attr smd)
		(fp_rect
			(start -0.7 0.35)
			(end 0.7 -0.35)
			(stroke
				(width 0.05)
				(type default)
			)
			(fill no)
			(layer "B.CrtYd")
		)
		(fp_rect
			(start 0.3 -0.15)
			(end -0.301 0.149)
			(stroke
				(width 0.15)
				(type solid)
			)
			(fill no)
			(layer "B.Fab")
		)
		(pad "" smd roundrect
			(at -0.349 0.002 180)
			(size 0.318 0.36)
			(layers "B.Paste")
			(roundrect_rratio 0.25)
		)
		(pad "" smd roundrect
			(at 0.341 0.002 180)
			(size 0.318 0.36)
			(layers "B.Paste")
			(roundrect_rratio 0.25)
		)
		(pad "1" smd roundrect
			(at -0.321 0.002 180)
			(size 0.46 0.4)
			(layers "B.Cu" "B.Mask")
			(roundrect_rratio 0.25)
			(net 1 "GND")
			(pintype "passive")
		)
		(pad "2" smd roundrect
			(at 0.32 0.002 180)
			(size 0.46 0.4)
			(layers "B.Cu" "B.Mask")
			(roundrect_rratio 0.25)
			(net 6 "VCC1V0")
			(pintype "passive")
		)
	)
	(footprint "antmicro-footprints:C_0402_1005Metric"
		(layer "B.Cu")
		(at 97.369 90.777 -90)
		(descr "Capacitor SMD 0402")
		(tags "capacitor SMD 0402")
		(property "Reference" "C215"
			(at -3.68 1.519 90)
			(layer "B.SilkS")
			(effects
				(font
					(size 0.7 0.7)
					(thickness 0.15)
				)
				(justify left bottom mirror)
			)
		)
		(property "Value" "C_10n_0402"
			(at 0 -1.4 90)
			(layer "B.Fab")
			(effects
				(font
					(size 0.7 0.7)
					(thickness 0.15)
				)
				(justify left bottom mirror)
			)
		)
		(property "Datasheet" "https://www.murata.com/products/productdetail?partno=GRM155R71H103KA88%23"
			(at 0 0 270)
			(layer "F.Fab")
			(hide yes)
			(effects
				(font
					(size 1.27 1.27)
					(thickness 0.15)
				)
			)
		)
		(property "Description" "SMD Multilayer Ceramic Capacitor, 10000 pF, 50 V, 0402 [1005 Metric], ± 10%, X7R, GRM Series"
			(at 0 0 270)
			(layer "F.Fab")
			(hide yes)
			(effects
				(font
					(size 1.27 1.27)
					(thickness 0.15)
				)
			)
		)
		(property "Author" "Antmicro"
			(at 6.592 188.146 0)
			(layer "B.Fab")
			(hide yes)
			(effects
				(font
					(size 1 1)
					(thickness 0.15)
				)
				(justify mirror)
			)
		)
		(property "Dielectric" "X7R"
			(at 6.592 188.146 0)
			(layer "B.Fab")
			(hide yes)
			(effects
				(font
					(size 1 1)
					(thickness 0.15)
				)
				(justify mirror)
			)
		)
		(property "License" "Apache-2.0"
			(at 6.592 188.146 0)
			(layer "B.Fab")
			(hide yes)
			(effects
				(font
					(size 1 1)
					(thickness 0.15)
				)
				(justify mirror)
			)
		)
		(property "MPN" "GRM155R71H103KA88D"
			(at 6.592 188.146 0)
			(layer "B.Fab")
			(hide yes)
			(effects
				(font
					(size 1 1)
					(thickness 0.15)
				)
				(justify mirror)
			)
		)
		(property "Manufacturer" "Murata"
			(at 6.592 188.146 0)
			(layer "B.Fab")
			(hide yes)
			(effects
				(font
					(size 1 1)
					(thickness 0.15)
				)
				(justify mirror)
			)
		)
		(property "Val" "10n"
			(at 6.592 188.146 0)
			(layer "B.Fab")
			(hide yes)
			(effects
				(font
					(size 1 1)
					(thickness 0.15)
				)
				(justify mirror)
			)
		)
		(property "Voltage" "50V"
			(at 6.592 188.146 0)
			(layer "B.Fab")
			(hide yes)
			(effects
				(font
					(size 1 1)
					(thickness 0.15)
				)
				(justify mirror)
			)
		)
		(sheetname "/Ethernet/")
		(sheetfile "ethernet.kicad_sch")
		(attr smd)
		(fp_rect
			(start -0.925 0.47)
			(end 0.925 -0.47)
			(stroke
				(width 0.05)
				(type default)
			)
			(fill no)
			(layer "B.CrtYd")
		)
		(fp_line
			(start -0.494 0.25)
			(end 0.504 0.25)
			(stroke
				(width 0.15)
				(type solid)
			)
			(layer "B.Fab")
		)
		(fp_line
			(start 0.504 0.25)
			(end 0.504 -0.248)
			(stroke
				(width 0.15)
				(type solid)
			)
			(layer "B.Fab")
		)
		(fp_line
			(start -0.494 -0.248)
			(end -0.494 0.25)
			(stroke
				(width 0.15)
				(type solid)
			)
			(layer "B.Fab")
		)
		(fp_line
			(start 0.504 -0.248)
			(end -0.494 -0.248)
			(stroke
				(width 0.15)
				(type solid)
			)
			(layer "B.Fab")
		)
		(pad "1" smd roundrect
			(at -0.48 0 270)
			(size 0.59 0.64)
			(layers "B.Cu" "B.Mask" "B.Paste")
			(roundrect_rratio 0.25)
			(net 1 "GND")
			(pintype "passive")
		)
		(pad "2" smd roundrect
			(at 0.48 0 270)
			(size 0.59 0.64)
			(layers "B.Cu" "B.Mask" "B.Paste")
			(roundrect_rratio 0.25)
			(net 406 "/Ethernet/AVDDH")
			(pintype "passive")
		)
	)
	(footprint "antmicro-footprints:C_0402_1005Metric"
		(layer "B.Cu")
		(at 96.69 94.06)
		(descr "Capacitor SMD 0402")
		(tags "capacitor SMD 0402")
		(property "Reference" "C197"
			(at -9.2 0.2 0)
			(layer "B.SilkS")
			(effects
				(font
					(size 0.7 0.7)
					(thickness 0.15)
				)
				(justify right bottom mirror)
			)
		)
		(property "Value" "C_470n_0402"
			(at 0 -1.4 0)
			(layer "B.Fab")
			(effects
				(font
					(size 0.7 0.7)
					(thickness 0.15)
				)
				(justify right bottom mirror)
			)
		)
		(property "Datasheet" "https://product.tdk.com/en/search/capacitor/ceramic/mlcc/info?part_no=C1005X5R1E474M050BB"
			(at 0 0 0)
			(layer "F.Fab")
			(hide yes)
			(effects
				(font
					(size 1.27 1.27)
					(thickness 0.15)
				)
			)
		)
		(property "Description" "SMD Multilayer Ceramic Capacitor, 0.47 µF, 25 V, 0402 [1005 Metric], ± 20%, X5R, C"
			(at 0 0 0)
			(layer "F.Fab")
			(hide yes)
			(effects
				(font
					(size 1.27 1.27)
					(thickness 0.15)
				)
			)
		)
		(property "Author" "Antmicro"
			(at 0 0 0)
			(layer "B.Fab")
			(hide yes)
			(effects
				(font
					(size 1 1)
					(thickness 0.15)
				)
				(justify mirror)
			)
		)
		(property "Dielectric" ""
			(at 0 0 0)
			(layer "B.Fab")
			(hide yes)
			(effects
				(font
					(size 1 1)
					(thickness 0.15)
				)
				(justify mirror)
			)
		)
		(property "License" "Apache-2.0"
			(at 0 0 0)
			(layer "B.Fab")
			(hide yes)
			(effects
				(font
					(size 1 1)
					(thickness 0.15)
				)
				(justify mirror)
			)
		)
		(property "MPN" "C1005X5R1E474M050BB"
			(at 0 0 0)
			(layer "B.Fab")
			(hide yes)
			(effects
				(font
					(size 1 1)
					(thickness 0.15)
				)
				(justify mirror)
			)
		)
		(property "Manufacturer" "TDK"
			(at 0 0 0)
			(layer "B.Fab")
			(hide yes)
			(effects
				(font
					(size 1 1)
					(thickness 0.15)
				)
				(justify mirror)
			)
		)
		(property "Val" "470n"
			(at 0 0 0)
			(layer "B.Fab")
			(hide yes)
			(effects
				(font
					(size 1 1)
					(thickness 0.15)
				)
				(justify mirror)
			)
		)
		(property "Voltage" ""
			(at 0 0 0)
			(layer "B.Fab")
			(hide yes)
			(effects
				(font
					(size 1 1)
					(thickness 0.15)
				)
				(justify mirror)
			)
		)
		(sheetname "/Ethernet/")
		(sheetfile "ethernet.kicad_sch")
		(attr smd)
		(fp_rect
			(start -0.925 0.47)
			(end 0.925 -0.47)
			(stroke
				(width 0.05)
				(type default)
			)
			(fill no)
			(layer "B.CrtYd")
		)
		(fp_line
			(start -0.494 -0.248)
			(end -0.494 0.25)
			(stroke
				(width 0.15)
				(type solid)
			)
			(layer "B.Fab")
		)
		(fp_line
			(start -0.494 0.25)
			(end 0.504 0.25)
			(stroke
				(width 0.15)
				(type solid)
			)
			(layer "B.Fab")
		)
		(fp_line
			(start 0.504 -0.248)
			(end -0.494 -0.248)
			(stroke
				(width 0.15)
				(type solid)
			)
			(layer "B.Fab")
		)
		(fp_line
			(start 0.504 0.25)
			(end 0.504 -0.248)
			(stroke
				(width 0.15)
				(type solid)
			)
			(layer "B.Fab")
		)
		(pad "1" smd roundrect
			(at -0.48 0)
			(size 0.59 0.64)
			(layers "B.Cu" "B.Mask" "B.Paste")
			(roundrect_rratio 0.25)
			(net 1 "GND")
			(pintype "passive")
		)
		(pad "2" smd roundrect
			(at 0.48 0)
			(size 0.59 0.64)
			(layers "B.Cu" "B.Mask" "B.Paste")
			(roundrect_rratio 0.25)
			(net 339 "VCC1V2")
			(pintype "passive")
		)
	)
	(footprint "antmicro-footprints:C_0402_1005Metric"
		(layer "B.Cu")
		(at 96.69 99.49)
		(descr "Capacitor SMD 0402")
		(tags "capacitor SMD 0402")
		(property "Reference" "C201"
			(at -9.19 -0.077 0)
			(layer "B.SilkS")
			(effects
				(font
					(size 0.7 0.7)
					(thickness 0.15)
				)
				(justify right bottom mirror)
			)
		)
		(property "Value" "C_470n_0402"
			(at 0 -1.4 0)
			(layer "B.Fab")
			(effects
				(font
					(size 0.7 0.7)
					(thickness 0.15)
				)
				(justify right bottom mirror)
			)
		)
		(property "Datasheet" "https://product.tdk.com/en/search/capacitor/ceramic/mlcc/info?part_no=C1005X5R1E474M050BB"
			(at 0 0 0)
			(layer "F.Fab")
			(hide yes)
			(effects
				(font
					(size 1.27 1.27)
					(thickness 0.15)
				)
			)
		)
		(property "Description" "SMD Multilayer Ceramic Capacitor, 0.47 µF, 25 V, 0402 [1005 Metric], ± 20%, X5R, C"
			(at 0 0 0)
			(layer "F.Fab")
			(hide yes)
			(effects
				(font
					(size 1.27 1.27)
					(thickness 0.15)
				)
			)
		)
		(property "Author" "Antmicro"
			(at 0 0 0)
			(layer "B.Fab")
			(hide yes)
			(effects
				(font
					(size 1 1)
					(thickness 0.15)
				)
				(justify mirror)
			)
		)
		(property "Dielectric" ""
			(at 0 0 0)
			(layer "B.Fab")
			(hide yes)
			(effects
				(font
					(size 1 1)
					(thickness 0.15)
				)
				(justify mirror)
			)
		)
		(property "License" "Apache-2.0"
			(at 0 0 0)
			(layer "B.Fab")
			(hide yes)
			(effects
				(font
					(size 1 1)
					(thickness 0.15)
				)
				(justify mirror)
			)
		)
		(property "MPN" "C1005X5R1E474M050BB"
			(at 0 0 0)
			(layer "B.Fab")
			(hide yes)
			(effects
				(font
					(size 1 1)
					(thickness 0.15)
				)
				(justify mirror)
			)
		)
		(property "Manufacturer" "TDK"
			(at 0 0 0)
			(layer "B.Fab")
			(hide yes)
			(effects
				(font
					(size 1 1)
					(thickness 0.15)
				)
				(justify mirror)
			)
		)
		(property "Val" "470n"
			(at 0 0 0)
			(layer "B.Fab")
			(hide yes)
			(effects
				(font
					(size 1 1)
					(thickness 0.15)
				)
				(justify mirror)
			)
		)
		(property "Voltage" ""
			(at 0 0 0)
			(layer "B.Fab")
			(hide yes)
			(effects
				(font
					(size 1 1)
					(thickness 0.15)
				)
				(justify mirror)
			)
		)
		(sheetname "/Ethernet/")
		(sheetfile "ethernet.kicad_sch")
		(attr smd)
		(fp_rect
			(start -0.925 0.47)
			(end 0.925 -0.47)
			(stroke
				(width 0.05)
				(type default)
			)
			(fill no)
			(layer "B.CrtYd")
		)
		(fp_line
			(start -0.494 -0.248)
			(end -0.494 0.25)
			(stroke
				(width 0.15)
				(type solid)
			)
			(layer "B.Fab")
		)
		(fp_line
			(start -0.494 0.25)
			(end 0.504 0.25)
			(stroke
				(width 0.15)
				(type solid)
			)
			(layer "B.Fab")
		)
		(fp_line
			(start 0.504 -0.248)
			(end -0.494 -0.248)
			(stroke
				(width 0.15)
				(type solid)
			)
			(layer "B.Fab")
		)
		(fp_line
			(start 0.504 0.25)
			(end 0.504 -0.248)
			(stroke
				(width 0.15)
				(type solid)
			)
			(layer "B.Fab")
		)
		(pad "1" smd roundrect
			(at -0.48 0)
			(size 0.59 0.64)
			(layers "B.Cu" "B.Mask" "B.Paste")
			(roundrect_rratio 0.25)
			(net 1 "GND")
			(pintype "passive")
		)
		(pad "2" smd roundrect
			(at 0.48 0)
			(size 0.59 0.64)
			(layers "B.Cu" "B.Mask" "B.Paste")
			(roundrect_rratio 0.25)
			(net 339 "VCC1V2")
			(pintype "passive")
		)
	)
	(footprint "antmicro-footprints:C_0402_1005Metric"
		(layer "B.Cu")
		(at 96.69 95.94)
		(descr "Capacitor SMD 0402")
		(tags "capacitor SMD 0402")
		(property "Reference" "C202"
			(at -9.2 0.2 0)
			(layer "B.SilkS")
			(effects
				(font
					(size 0.7 0.7)
					(thickness 0.15)
				)
				(justify right bottom mirror)
			)
		)
		(property "Value" "C_470n_0402"
			(at 0 -1.4 0)
			(layer "B.Fab")
			(effects
				(font
					(size 0.7 0.7)
					(thickness 0.15)
				)
				(justify right bottom mirror)
			)
		)
		(property "Datasheet" "https://product.tdk.com/en/search/capacitor/ceramic/mlcc/info?part_no=C1005X5R1E474M050BB"
			(at 0 0 0)
			(layer "F.Fab")
			(hide yes)
			(effects
				(font
					(size 1.27 1.27)
					(thickness 0.15)
				)
			)
		)
		(property "Description" "SMD Multilayer Ceramic Capacitor, 0.47 µF, 25 V, 0402 [1005 Metric], ± 20%, X5R, C"
			(at 0 0 0)
			(layer "F.Fab")
			(hide yes)
			(effects
				(font
					(size 1.27 1.27)
					(thickness 0.15)
				)
			)
		)
		(property "Author" "Antmicro"
			(at 0 0 0)
			(layer "B.Fab")
			(hide yes)
			(effects
				(font
					(size 1 1)
					(thickness 0.15)
				)
				(justify mirror)
			)
		)
		(property "Dielectric" ""
			(at 0 0 0)
			(layer "B.Fab")
			(hide yes)
			(effects
				(font
					(size 1 1)
					(thickness 0.15)
				)
				(justify mirror)
			)
		)
		(property "License" "Apache-2.0"
			(at 0 0 0)
			(layer "B.Fab")
			(hide yes)
			(effects
				(font
					(size 1 1)
					(thickness 0.15)
				)
				(justify mirror)
			)
		)
		(property "MPN" "C1005X5R1E474M050BB"
			(at 0 0 0)
			(layer "B.Fab")
			(hide yes)
			(effects
				(font
					(size 1 1)
					(thickness 0.15)
				)
				(justify mirror)
			)
		)
		(property "Manufacturer" "TDK"
			(at 0 0 0)
			(layer "B.Fab")
			(hide yes)
			(effects
				(font
					(size 1 1)
					(thickness 0.15)
				)
				(justify mirror)
			)
		)
		(property "Val" "470n"
			(at 0 0 0)
			(layer "B.Fab")
			(hide yes)
			(effects
				(font
					(size 1 1)
					(thickness 0.15)
				)
				(justify mirror)
			)
		)
		(property "Voltage" ""
			(at 0 0 0)
			(layer "B.Fab")
			(hide yes)
			(effects
				(font
					(size 1 1)
					(thickness 0.15)
				)
				(justify mirror)
			)
		)
		(sheetname "/Ethernet/")
		(sheetfile "ethernet.kicad_sch")
		(attr smd)
		(fp_rect
			(start -0.925 0.47)
			(end 0.925 -0.47)
			(stroke
				(width 0.05)
				(type default)
			)
			(fill no)
			(layer "B.CrtYd")
		)
		(fp_line
			(start -0.494 -0.248)
			(end -0.494 0.25)
			(stroke
				(width 0.15)
				(type solid)
			)
			(layer "B.Fab")
		)
		(fp_line
			(start -0.494 0.25)
			(end 0.504 0.25)
			(stroke
				(width 0.15)
				(type solid)
			)
			(layer "B.Fab")
		)
		(fp_line
			(start 0.504 -0.248)
			(end -0.494 -0.248)
			(stroke
				(width 0.15)
				(type solid)
			)
			(layer "B.Fab")
		)
		(fp_line
			(start 0.504 0.25)
			(end 0.504 -0.248)
			(stroke
				(width 0.15)
				(type solid)
			)
			(layer "B.Fab")
		)
		(pad "1" smd roundrect
			(at -0.48 0)
			(size 0.59 0.64)
			(layers "B.Cu" "B.Mask" "B.Paste")
			(roundrect_rratio 0.25)
			(net 1 "GND")
			(pintype "passive")
		)
		(pad "2" smd roundrect
			(at 0.48 0)
			(size 0.59 0.64)
			(layers "B.Cu" "B.Mask" "B.Paste")
			(roundrect_rratio 0.25)
			(net 2 "VCC3V3")
			(pintype "passive")
		)
	)
	(footprint "antmicro-footprints:C_0402_1005Metric"
		(layer "B.Cu")
		(at 96.69 98.477)
		(descr "Capacitor SMD 0402")
		(tags "capacitor SMD 0402")
		(property "Reference" "C210"
			(at -9.19 -0.077 0)
			(layer "B.SilkS")
			(effects
				(font
					(size 0.7 0.7)
					(thickness 0.15)
				)
				(justify right bottom mirror)
			)
		)
		(property "Value" "C_10n_0402"
			(at 0 -1.4 0)
			(layer "B.Fab")
			(effects
				(font
					(size 0.7 0.7)
					(thickness 0.15)
				)
				(justify right bottom mirror)
			)
		)
		(property "Datasheet" "https://www.murata.com/products/productdetail?partno=GRM155R71H103KA88%23"
			(at 0 0 0)
			(layer "F.Fab")
			(hide yes)
			(effects
				(font
					(size 1.27 1.27)
					(thickness 0.15)
				)
			)
		)
		(property "Description" "SMD Multilayer Ceramic Capacitor, 10000 pF, 50 V, 0402 [1005 Metric], ± 10%, X7R, GRM Series"
			(at 0 0 0)
			(layer "F.Fab")
			(hide yes)
			(effects
				(font
					(size 1.27 1.27)
					(thickness 0.15)
				)
			)
		)
		(property "Author" "Antmicro"
			(at 0 0 0)
			(layer "B.Fab")
			(hide yes)
			(effects
				(font
					(size 1 1)
					(thickness 0.15)
				)
				(justify mirror)
			)
		)
		(property "Dielectric" "X7R"
			(at 0 0 0)
			(layer "B.Fab")
			(hide yes)
			(effects
				(font
					(size 1 1)
					(thickness 0.15)
				)
				(justify mirror)
			)
		)
		(property "License" "Apache-2.0"
			(at 0 0 0)
			(layer "B.Fab")
			(hide yes)
			(effects
				(font
					(size 1 1)
					(thickness 0.15)
				)
				(justify mirror)
			)
		)
		(property "MPN" "GRM155R71H103KA88D"
			(at 0 0 0)
			(layer "B.Fab")
			(hide yes)
			(effects
				(font
					(size 1 1)
					(thickness 0.15)
				)
				(justify mirror)
			)
		)
		(property "Manufacturer" "Murata"
			(at 0 0 0)
			(layer "B.Fab")
			(hide yes)
			(effects
				(font
					(size 1 1)
					(thickness 0.15)
				)
				(justify mirror)
			)
		)
		(property "Val" "10n"
			(at 0 0 0)
			(layer "B.Fab")
			(hide yes)
			(effects
				(font
					(size 1 1)
					(thickness 0.15)
				)
				(justify mirror)
			)
		)
		(property "Voltage" "50V"
			(at 0 0 0)
			(layer "B.Fab")
			(hide yes)
			(effects
				(font
					(size 1 1)
					(thickness 0.15)
				)
				(justify mirror)
			)
		)
		(sheetname "/Ethernet/")
		(sheetfile "ethernet.kicad_sch")
		(attr smd)
		(fp_rect
			(start -0.925 0.47)
			(end 0.925 -0.47)
			(stroke
				(width 0.05)
				(type default)
			)
			(fill no)
			(layer "B.CrtYd")
		)
		(fp_line
			(start -0.494 -0.248)
			(end -0.494 0.25)
			(stroke
				(width 0.15)
				(type solid)
			)
			(layer "B.Fab")
		)
		(fp_line
			(start -0.494 0.25)
			(end 0.504 0.25)
			(stroke
				(width 0.15)
				(type solid)
			)
			(layer "B.Fab")
		)
		(fp_line
			(start 0.504 -0.248)
			(end -0.494 -0.248)
			(stroke
				(width 0.15)
				(type solid)
			)
			(layer "B.Fab")
		)
		(fp_line
			(start 0.504 0.25)
			(end 0.504 -0.248)
			(stroke
				(width 0.15)
				(type solid)
			)
			(layer "B.Fab")
		)
		(pad "1" smd roundrect
			(at -0.48 0)
			(size 0.59 0.64)
			(layers "B.Cu" "B.Mask" "B.Paste")
			(roundrect_rratio 0.25)
			(net 1 "GND")
			(pintype "passive")
		)
		(pad "2" smd roundrect
			(at 0.48 0)
			(size 0.59 0.64)
			(layers "B.Cu" "B.Mask" "B.Paste")
			(roundrect_rratio 0.25)
			(net 339 "VCC1V2")
			(pintype "passive")
		)
	)
	(footprint "antmicro-footprints:C_0402_1005Metric"
		(layer "B.Cu")
		(at 96.7 95)
		(descr "Capacitor SMD 0402")
		(tags "capacitor SMD 0402")
		(property "Reference" "C216"
			(at -9.2 0.2 0)
			(layer "B.SilkS")
			(effects
				(font
					(size 0.7 0.7)
					(thickness 0.15)
				)
				(justify right bottom mirror)
			)
		)
		(property "Value" "C_10n_0402"
			(at 0 -1.4 0)
			(layer "B.Fab")
			(effects
				(font
					(size 0.7 0.7)
					(thickness 0.15)
				)
				(justify right bottom mirror)
			)
		)
		(property "Datasheet" "https://www.murata.com/products/productdetail?partno=GRM155R71H103KA88%23"
			(at 0 0 0)
			(layer "F.Fab")
			(hide yes)
			(effects
				(font
					(size 1.27 1.27)
					(thickness 0.15)
				)
			)
		)
		(property "Description" "SMD Multilayer Ceramic Capacitor, 10000 pF, 50 V, 0402 [1005 Metric], ± 10%, X7R, GRM Series"
			(at 0 0 0)
			(layer "F.Fab")
			(hide yes)
			(effects
				(font
					(size 1.27 1.27)
					(thickness 0.15)
				)
			)
		)
		(property "Author" "Antmicro"
			(at 0 0 0)
			(layer "B.Fab")
			(hide yes)
			(effects
				(font
					(size 1 1)
					(thickness 0.15)
				)
				(justify mirror)
			)
		)
		(property "Dielectric" "X7R"
			(at 0 0 0)
			(layer "B.Fab")
			(hide yes)
			(effects
				(font
					(size 1 1)
					(thickness 0.15)
				)
				(justify mirror)
			)
		)
		(property "License" "Apache-2.0"
			(at 0 0 0)
			(layer "B.Fab")
			(hide yes)
			(effects
				(font
					(size 1 1)
					(thickness 0.15)
				)
				(justify mirror)
			)
		)
		(property "MPN" "GRM155R71H103KA88D"
			(at 0 0 0)
			(layer "B.Fab")
			(hide yes)
			(effects
				(font
					(size 1 1)
					(thickness 0.15)
				)
				(justify mirror)
			)
		)
		(property "Manufacturer" "Murata"
			(at 0 0 0)
			(layer "B.Fab")
			(hide yes)
			(effects
				(font
					(size 1 1)
					(thickness 0.15)
				)
				(justify mirror)
			)
		)
		(property "Val" "10n"
			(at 0 0 0)
			(layer "B.Fab")
			(hide yes)
			(effects
				(font
					(size 1 1)
					(thickness 0.15)
				)
				(justify mirror)
			)
		)
		(property "Voltage" "50V"
			(at 0 0 0)
			(layer "B.Fab")
			(hide yes)
			(effects
				(font
					(size 1 1)
					(thickness 0.15)
				)
				(justify mirror)
			)
		)
		(sheetname "/Ethernet/")
		(sheetfile "ethernet.kicad_sch")
		(attr smd)
		(fp_rect
			(start -0.925 0.47)
			(end 0.925 -0.47)
			(stroke
				(width 0.05)
				(type default)
			)
			(fill no)
			(layer "B.CrtYd")
		)
		(fp_line
			(start -0.494 -0.248)
			(end -0.494 0.25)
			(stroke
				(width 0.15)
				(type solid)
			)
			(layer "B.Fab")
		)
		(fp_line
			(start -0.494 0.25)
			(end 0.504 0.25)
			(stroke
				(width 0.15)
				(type solid)
			)
			(layer "B.Fab")
		)
		(fp_line
			(start 0.504 -0.248)
			(end -0.494 -0.248)
			(stroke
				(width 0.15)
				(type solid)
			)
			(layer "B.Fab")
		)
		(fp_line
			(start 0.504 0.25)
			(end 0.504 -0.248)
			(stroke
				(width 0.15)
				(type solid)
			)
			(layer "B.Fab")
		)
		(pad "1" smd roundrect
			(at -0.48 0)
			(size 0.59 0.64)
			(layers "B.Cu" "B.Mask" "B.Paste")
			(roundrect_rratio 0.25)
			(net 1 "GND")
			(pintype "passive")
		)
		(pad "2" smd roundrect
			(at 0.48 0)
			(size 0.59 0.64)
			(layers "B.Cu" "B.Mask" "B.Paste")
			(roundrect_rratio 0.25)
			(net 2 "VCC3V3")
			(pintype "passive")
		)
	)
	(footprint "antmicro-footprints:C_0402_1005Metric"
		(layer "B.Cu")
		(at 96.7 96.955)
		(descr "Capacitor SMD 0402")
		(tags "capacitor SMD 0402")
		(property "Reference" "C219"
			(at -9.2 0.2 0)
			(layer "B.SilkS")
			(effects
				(font
					(size 0.7 0.7)
					(thickness 0.15)
				)
				(justify right bottom mirror)
			)
		)
		(property "Value" "C_10n_0402"
			(at 0 -1.4 0)
			(layer "B.Fab")
			(effects
				(font
					(size 0.7 0.7)
					(thickness 0.15)
				)
				(justify right bottom mirror)
			)
		)
		(property "Datasheet" "https://www.murata.com/products/productdetail?partno=GRM155R71H103KA88%23"
			(at 0 0 0)
			(layer "F.Fab")
			(hide yes)
			(effects
				(font
					(size 1.27 1.27)
					(thickness 0.15)
				)
			)
		)
		(property "Description" "SMD Multilayer Ceramic Capacitor, 10000 pF, 50 V, 0402 [1005 Metric], ± 10%, X7R, GRM Series"
			(at 0 0 0)
			(layer "F.Fab")
			(hide yes)
			(effects
				(font
					(size 1.27 1.27)
					(thickness 0.15)
				)
			)
		)
		(property "Author" "Antmicro"
			(at 0 0 0)
			(layer "B.Fab")
			(hide yes)
			(effects
				(font
					(size 1 1)
					(thickness 0.15)
				)
				(justify mirror)
			)
		)
		(property "Dielectric" "X7R"
			(at 0 0 0)
			(layer "B.Fab")
			(hide yes)
			(effects
				(font
					(size 1 1)
					(thickness 0.15)
				)
				(justify mirror)
			)
		)
		(property "License" "Apache-2.0"
			(at 0 0 0)
			(layer "B.Fab")
			(hide yes)
			(effects
				(font
					(size 1 1)
					(thickness 0.15)
				)
				(justify mirror)
			)
		)
		(property "MPN" "GRM155R71H103KA88D"
			(at 0 0 0)
			(layer "B.Fab")
			(hide yes)
			(effects
				(font
					(size 1 1)
					(thickness 0.15)
				)
				(justify mirror)
			)
		)
		(property "Manufacturer" "Murata"
			(at 0 0 0)
			(layer "B.Fab")
			(hide yes)
			(effects
				(font
					(size 1 1)
					(thickness 0.15)
				)
				(justify mirror)
			)
		)
		(property "Val" "10n"
			(at 0 0 0)
			(layer "B.Fab")
			(hide yes)
			(effects
				(font
					(size 1 1)
					(thickness 0.15)
				)
				(justify mirror)
			)
		)
		(property "Voltage" "50V"
			(at 0 0 0)
			(layer "B.Fab")
			(hide yes)
			(effects
				(font
					(size 1 1)
					(thickness 0.15)
				)
				(justify mirror)
			)
		)
		(sheetname "/Ethernet/")
		(sheetfile "ethernet.kicad_sch")
		(attr smd)
		(fp_rect
			(start -0.925 0.47)
			(end 0.925 -0.47)
			(stroke
				(width 0.05)
				(type default)
			)
			(fill no)
			(layer "B.CrtYd")
		)
		(fp_line
			(start -0.494 -0.248)
			(end -0.494 0.25)
			(stroke
				(width 0.15)
				(type solid)
			)
			(layer "B.Fab")
		)
		(fp_line
			(start -0.494 0.25)
			(end 0.504 0.25)
			(stroke
				(width 0.15)
				(type solid)
			)
			(layer "B.Fab")
		)
		(fp_line
			(start 0.504 -0.248)
			(end -0.494 -0.248)
			(stroke
				(width 0.15)
				(type solid)
			)
			(layer "B.Fab")
		)
		(fp_line
			(start 0.504 0.25)
			(end 0.504 -0.248)
			(stroke
				(width 0.15)
				(type solid)
			)
			(layer "B.Fab")
		)
		(pad "1" smd roundrect
			(at -0.48 0)
			(size 0.59 0.64)
			(layers "B.Cu" "B.Mask" "B.Paste")
			(roundrect_rratio 0.25)
			(net 1 "GND")
			(pintype "passive")
		)
		(pad "2" smd roundrect
			(at 0.48 0)
			(size 0.59 0.64)
			(layers "B.Cu" "B.Mask" "B.Paste")
			(roundrect_rratio 0.25)
			(net 339 "VCC1V2")
			(pintype "passive")
		)
	)
	(footprint "antmicro-footprints:C_0201"
		(layer "B.Cu")
		(at 102.275 120.675)
		(descr "Capacitor SMD 0201")
		(tags "capacitor SMD 0201")
		(property "Reference" "C165"
			(at -20.575 0.625 0)
			(layer "B.SilkS")
			(effects
				(font
					(size 0.7 0.7)
					(thickness 0.15)
				)
				(justify right bottom mirror)
			)
		)
		(property "Value" "C_470n_0201"
			(at 0 -1.4 0)
			(layer "B.Fab")
			(effects
				(font
					(size 0.7 0.7)
					(thickness 0.15)
				)
				(justify right bottom mirror)
			)
		)
		(property "Datasheet" "https://product.tdk.com/en/search/capacitor/ceramic/mlcc/info?part_no=C0603X5R1A474M030BC"
			(at 0 0 0)
			(layer "F.Fab")
			(hide yes)
			(effects
				(font
					(size 1.27 1.27)
					(thickness 0.15)
				)
			)
		)
		(property "Description" "SMD Multilayer Ceramic Capacitor, 0.47 µF, 10 V, 0201 [0603 Metric], ± 20%, X5R, C"
			(at 0 0 0)
			(layer "F.Fab")
			(hide yes)
			(effects
				(font
					(size 1.27 1.27)
					(thickness 0.15)
				)
			)
		)
		(property "Author" "Antmicro"
			(at 0 0 0)
			(layer "B.Fab")
			(hide yes)
			(effects
				(font
					(size 1 1)
					(thickness 0.15)
				)
				(justify mirror)
			)
		)
		(property "Dielectric" ""
			(at 0 0 0)
			(layer "B.Fab")
			(hide yes)
			(effects
				(font
					(size 1 1)
					(thickness 0.15)
				)
				(justify mirror)
			)
		)
		(property "License" "Apache-2.0"
			(at 0 0 0)
			(layer "B.Fab")
			(hide yes)
			(effects
				(font
					(size 1 1)
					(thickness 0.15)
				)
				(justify mirror)
			)
		)
		(property "MPN" "C0603X5R1A474M030BC"
			(at 0 0 0)
			(layer "B.Fab")
			(hide yes)
			(effects
				(font
					(size 1 1)
					(thickness 0.15)
				)
				(justify mirror)
			)
		)
		(property "Manufacturer" "TDK"
			(at 0 0 0)
			(layer "B.Fab")
			(hide yes)
			(effects
				(font
					(size 1 1)
					(thickness 0.15)
				)
				(justify mirror)
			)
		)
		(property "Public" "False"
			(at 0 0 0)
			(layer "B.Fab")
			(hide yes)
			(effects
				(font
					(size 1 1)
					(thickness 0.15)
				)
				(justify mirror)
			)
		)
		(property "Val" "470n"
			(at 0 0 0)
			(layer "B.Fab")
			(hide yes)
			(effects
				(font
					(size 1 1)
					(thickness 0.15)
				)
				(justify mirror)
			)
		)
		(property "Voltage" ""
			(at 0 0 0)
			(layer "B.Fab")
			(hide yes)
			(effects
				(font
					(size 1 1)
					(thickness 0.15)
				)
				(justify mirror)
			)
		)
		(property "DNP" ""
			(at 0 0 0)
			(unlocked yes)
			(layer "B.Fab")
			(hide yes)
			(effects
				(font
					(size 1 1)
					(thickness 0.15)
				)
				(justify mirror)
			)
		)
		(sheetname "/FPGA power supply/")
		(sheetfile "fpga-power-supply.kicad_sch")
		(attr smd)
		(fp_rect
			(start -0.7 0.35)
			(end 0.7 -0.35)
			(stroke
				(width 0.05)
				(type default)
			)
			(fill no)
			(layer "B.CrtYd")
		)
		(fp_rect
			(start 0.3 -0.15)
			(end -0.301 0.149)
			(stroke
				(width 0.15)
				(type solid)
			)
			(fill no)
			(layer "B.Fab")
		)
		(pad "" smd roundrect
			(at -0.349 0.002)
			(size 0.318 0.36)
			(layers "B.Paste")
			(roundrect_rratio 0.25)
		)
		(pad "" smd roundrect
			(at 0.341 0.002)
			(size 0.318 0.36)
			(layers "B.Paste")
			(roundrect_rratio 0.25)
		)
		(pad "1" smd roundrect
			(at -0.321 0.002)
			(size 0.46 0.4)
			(layers "B.Cu" "B.Mask")
			(roundrect_rratio 0.25)
			(net 1 "GND")
			(pintype "passive")
		)
		(pad "2" smd roundrect
			(at 0.32 0.002)
			(size 0.46 0.4)
			(layers "B.Cu" "B.Mask")
			(roundrect_rratio 0.25)
			(net 6 "VCC1V0")
			(pintype "passive")
		)
	)
	(footprint "antmicro-footprints:C_0201"
		(layer "B.Cu")
		(at 104.325 120.675)
		(descr "Capacitor SMD 0201")
		(tags "capacitor SMD 0201")
		(property "Reference" "C242"
			(at -19.725 0.625 0)
			(layer "B.SilkS")
			(effects
				(font
					(size 0.7 0.7)
					(thickness 0.15)
				)
				(justify right bottom mirror)
			)
		)
		(property "Value" "C_470n_0201"
			(at 0 -1.4 0)
			(layer "B.Fab")
			(effects
				(font
					(size 0.7 0.7)
					(thickness 0.15)
				)
				(justify right bottom mirror)
			)
		)
		(property "Datasheet" "https://product.tdk.com/en/search/capacitor/ceramic/mlcc/info?part_no=C0603X5R1A474M030BC"
			(at 0 0 0)
			(layer "F.Fab")
			(hide yes)
			(effects
				(font
					(size 1.27 1.27)
					(thickness 0.15)
				)
			)
		)
		(property "Description" "SMD Multilayer Ceramic Capacitor, 0.47 µF, 10 V, 0201 [0603 Metric], ± 20%, X5R, C"
			(at 0 0 0)
			(layer "F.Fab")
			(hide yes)
			(effects
				(font
					(size 1.27 1.27)
					(thickness 0.15)
				)
			)
		)
		(property "Author" "Antmicro"
			(at 0 0 0)
			(layer "B.Fab")
			(hide yes)
			(effects
				(font
					(size 1 1)
					(thickness 0.15)
				)
				(justify mirror)
			)
		)
		(property "Dielectric" ""
			(at 0 0 0)
			(layer "B.Fab")
			(hide yes)
			(effects
				(font
					(size 1 1)
					(thickness 0.15)
				)
				(justify mirror)
			)
		)
		(property "License" "Apache-2.0"
			(at 0 0 0)
			(layer "B.Fab")
			(hide yes)
			(effects
				(font
					(size 1 1)
					(thickness 0.15)
				)
				(justify mirror)
			)
		)
		(property "MPN" "C0603X5R1A474M030BC"
			(at 0 0 0)
			(layer "B.Fab")
			(hide yes)
			(effects
				(font
					(size 1 1)
					(thickness 0.15)
				)
				(justify mirror)
			)
		)
		(property "Manufacturer" "TDK"
			(at 0 0 0)
			(layer "B.Fab")
			(hide yes)
			(effects
				(font
					(size 1 1)
					(thickness 0.15)
				)
				(justify mirror)
			)
		)
		(property "Public" "False"
			(at 0 0 0)
			(layer "B.Fab")
			(hide yes)
			(effects
				(font
					(size 1 1)
					(thickness 0.15)
				)
				(justify mirror)
			)
		)
		(property "Val" "470n"
			(at 0 0 0)
			(layer "B.Fab")
			(hide yes)
			(effects
				(font
					(size 1 1)
					(thickness 0.15)
				)
				(justify mirror)
			)
		)
		(property "Voltage" ""
			(at 0 0 0)
			(layer "B.Fab")
			(hide yes)
			(effects
				(font
					(size 1 1)
					(thickness 0.15)
				)
				(justify mirror)
			)
		)
		(sheetname "/FPGA power supply/")
		(sheetfile "fpga-power-supply.kicad_sch")
		(attr smd)
		(fp_rect
			(start -0.7 0.35)
			(end 0.7 -0.35)
			(stroke
				(width 0.05)
				(type default)
			)
			(fill no)
			(layer "B.CrtYd")
		)
		(fp_rect
			(start 0.3 -0.15)
			(end -0.301 0.149)
			(stroke
				(width 0.15)
				(type solid)
			)
			(fill no)
			(layer "B.Fab")
		)
		(pad "" smd roundrect
			(at -0.349 0.002)
			(size 0.318 0.36)
			(layers "B.Paste")
			(roundrect_rratio 0.25)
		)
		(pad "" smd roundrect
			(at 0.341 0.002)
			(size 0.318 0.36)
			(layers "B.Paste")
			(roundrect_rratio 0.25)
		)
		(pad "1" smd roundrect
			(at -0.321 0.002)
			(size 0.46 0.4)
			(layers "B.Cu" "B.Mask")
			(roundrect_rratio 0.25)
			(net 1 "GND")
			(pintype "passive")
		)
		(pad "2" smd roundrect
			(at 0.32 0.002)
			(size 0.46 0.4)
			(layers "B.Cu" "B.Mask")
			(roundrect_rratio 0.25)
			(net 5 "VCC1V8")
			(pintype "passive")
		)
	)
	(footprint "antmicro-footprints:C_0402_1005Metric"
		(layer "B.Cu")
		(at 123.355 129.665 -90)
		(descr "Capacitor SMD 0402")
		(tags "capacitor SMD 0402")
		(property "Reference" "C177"
			(at 0.835 -0.385 90)
			(layer "B.SilkS")
			(effects
				(font
					(size 0.7 0.7)
					(thickness 0.15)
				)
				(justify left bottom mirror)
			)
		)
		(property "Value" "C_4u7_0402"
			(at 0 -1.4 90)
			(layer "B.Fab")
			(effects
				(font
					(size 0.7 0.7)
					(thickness 0.15)
				)
				(justify left bottom mirror)
			)
		)
		(property "Datasheet" "https://www.murata.com/products/productdetail?partno=GRM155R61A475MEAA%23"
			(at 0 0 270)
			(layer "F.Fab")
			(hide yes)
			(effects
				(font
					(size 1.27 1.27)
					(thickness 0.15)
				)
			)
		)
		(property "Description" "SMD Multilayer Ceramic Capacitor, 4.7 µF, 10 V, 0402 [1005 Metric], ± 20%, X5R, GRM Series"
			(at 0 0 270)
			(layer "F.Fab")
			(hide yes)
			(effects
				(font
					(size 1.27 1.27)
					(thickness 0.15)
				)
			)
		)
		(property "Author" "Antmicro"
			(at -6.31 253.02 0)
			(layer "B.Fab")
			(hide yes)
			(effects
				(font
					(size 1 1)
					(thickness 0.15)
				)
				(justify mirror)
			)
		)
		(property "Dielectric" ""
			(at -6.31 253.02 0)
			(layer "B.Fab")
			(hide yes)
			(effects
				(font
					(size 1 1)
					(thickness 0.15)
				)
				(justify mirror)
			)
		)
		(property "License" "Apache-2.0"
			(at -6.31 253.02 0)
			(layer "B.Fab")
			(hide yes)
			(effects
				(font
					(size 1 1)
					(thickness 0.15)
				)
				(justify mirror)
			)
		)
		(property "MPN" "GRM155R61A475MEAAD"
			(at -6.31 253.02 0)
			(layer "B.Fab")
			(hide yes)
			(effects
				(font
					(size 1 1)
					(thickness 0.15)
				)
				(justify mirror)
			)
		)
		(property "Manufacturer" "Murata"
			(at -6.31 253.02 0)
			(layer "B.Fab")
			(hide yes)
			(effects
				(font
					(size 1 1)
					(thickness 0.15)
				)
				(justify mirror)
			)
		)
		(property "Val" "4u7"
			(at -6.31 253.02 0)
			(layer "B.Fab")
			(hide yes)
			(effects
				(font
					(size 1 1)
					(thickness 0.15)
				)
				(justify mirror)
			)
		)
		(property "Voltage" ""
			(at -6.31 253.02 0)
			(layer "B.Fab")
			(hide yes)
			(effects
				(font
					(size 1 1)
					(thickness 0.15)
				)
				(justify mirror)
			)
		)
		(sheetname "/Interfaces/")
		(sheetfile "interfaces.kicad_sch")
		(attr smd)
		(fp_rect
			(start -0.925 0.47)
			(end 0.925 -0.47)
			(stroke
				(width 0.05)
				(type default)
			)
			(fill no)
			(layer "B.CrtYd")
		)
		(fp_line
			(start -0.494 0.25)
			(end 0.504 0.25)
			(stroke
				(width 0.15)
				(type solid)
			)
			(layer "B.Fab")
		)
		(fp_line
			(start 0.504 0.25)
			(end 0.504 -0.248)
			(stroke
				(width 0.15)
				(type solid)
			)
			(layer "B.Fab")
		)
		(fp_line
			(start -0.494 -0.248)
			(end -0.494 0.25)
			(stroke
				(width 0.15)
				(type solid)
			)
			(layer "B.Fab")
		)
		(fp_line
			(start 0.504 -0.248)
			(end -0.494 -0.248)
			(stroke
				(width 0.15)
				(type solid)
			)
			(layer "B.Fab")
		)
		(pad "1" smd roundrect
			(at -0.48 0 270)
			(size 0.59 0.64)
			(layers "B.Cu" "B.Mask" "B.Paste")
			(roundrect_rratio 0.25)
			(net 1 "GND")
			(pintype "passive")
		)
		(pad "2" smd roundrect
			(at 0.48 0 270)
			(size 0.59 0.64)
			(layers "B.Cu" "B.Mask" "B.Paste")
			(roundrect_rratio 0.25)
			(net 108 "Net-(C177-Pad2)")
			(pintype "passive")
		)
	)
	(footprint "antmicro-footprints:C_0402_1005Metric"
		(layer "B.Cu")
		(at 126.415 129.665 -90)
		(descr "Capacitor SMD 0402")
		(tags "capacitor SMD 0402")
		(property "Reference" "C245"
			(at 0.835 -0.385 90)
			(layer "B.SilkS")
			(effects
				(font
					(size 0.7 0.7)
					(thickness 0.15)
				)
				(justify left bottom mirror)
			)
		)
		(property "Value" "C_4u7_0402"
			(at 0 -1.4 90)
			(layer "B.Fab")
			(effects
				(font
					(size 0.7 0.7)
					(thickness 0.15)
				)
				(justify left bottom mirror)
			)
		)
		(property "Datasheet" "https://www.murata.com/products/productdetail?partno=GRM155R61A475MEAA%23"
			(at 0 0 270)
			(layer "F.Fab")
			(hide yes)
			(effects
				(font
					(size 1.27 1.27)
					(thickness 0.15)
				)
			)
		)
		(property "Description" "SMD Multilayer Ceramic Capacitor, 4.7 µF, 10 V, 0402 [1005 Metric], ± 20%, X5R, GRM Series"
			(at 0 0 270)
			(layer "F.Fab")
			(hide yes)
			(effects
				(font
					(size 1.27 1.27)
					(thickness 0.15)
				)
			)
		)
		(property "Author" "Antmicro"
			(at -3.25 256.08 0)
			(layer "B.Fab")
			(hide yes)
			(effects
				(font
					(size 1 1)
					(thickness 0.15)
				)
				(justify mirror)
			)
		)
		(property "Dielectric" ""
			(at -3.25 256.08 0)
			(layer "B.Fab")
			(hide yes)
			(effects
				(font
					(size 1 1)
					(thickness 0.15)
				)
				(justify mirror)
			)
		)
		(property "License" "Apache-2.0"
			(at -3.25 256.08 0)
			(layer "B.Fab")
			(hide yes)
			(effects
				(font
					(size 1 1)
					(thickness 0.15)
				)
				(justify mirror)
			)
		)
		(property "MPN" "GRM155R61A475MEAAD"
			(at -3.25 256.08 0)
			(layer "B.Fab")
			(hide yes)
			(effects
				(font
					(size 1 1)
					(thickness 0.15)
				)
				(justify mirror)
			)
		)
		(property "Manufacturer" "Murata"
			(at -3.25 256.08 0)
			(layer "B.Fab")
			(hide yes)
			(effects
				(font
					(size 1 1)
					(thickness 0.15)
				)
				(justify mirror)
			)
		)
		(property "Val" "4u7"
			(at -3.25 256.08 0)
			(layer "B.Fab")
			(hide yes)
			(effects
				(font
					(size 1 1)
					(thickness 0.15)
				)
				(justify mirror)
			)
		)
		(property "Voltage" ""
			(at -3.25 256.08 0)
			(layer "B.Fab")
			(hide yes)
			(effects
				(font
					(size 1 1)
					(thickness 0.15)
				)
				(justify mirror)
			)
		)
		(sheetname "/Interfaces/")
		(sheetfile "interfaces.kicad_sch")
		(attr smd)
		(fp_rect
			(start -0.925 0.47)
			(end 0.925 -0.47)
			(stroke
				(width 0.05)
				(type default)
			)
			(fill no)
			(layer "B.CrtYd")
		)
		(fp_line
			(start -0.494 0.25)
			(end 0.504 0.25)
			(stroke
				(width 0.15)
				(type solid)
			)
			(layer "B.Fab")
		)
		(fp_line
			(start 0.504 0.25)
			(end 0.504 -0.248)
			(stroke
				(width 0.15)
				(type solid)
			)
			(layer "B.Fab")
		)
		(fp_line
			(start -0.494 -0.248)
			(end -0.494 0.25)
			(stroke
				(width 0.15)
				(type solid)
			)
			(layer "B.Fab")
		)
		(fp_line
			(start 0.504 -0.248)
			(end -0.494 -0.248)
			(stroke
				(width 0.15)
				(type solid)
			)
			(layer "B.Fab")
		)
		(pad "1" smd roundrect
			(at -0.48 0 270)
			(size 0.59 0.64)
			(layers "B.Cu" "B.Mask" "B.Paste")
			(roundrect_rratio 0.25)
			(net 1 "GND")
			(pintype "passive")
		)
		(pad "2" smd roundrect
			(at 0.48 0 270)
			(size 0.59 0.64)
			(layers "B.Cu" "B.Mask" "B.Paste")
			(roundrect_rratio 0.25)
			(net 11 "Net-(U18-VDDA1.8)")
			(pintype "passive")
		)
	)
	(footprint "antmicro-footprints:C_0402_1005Metric"
		(layer "B.Cu")
		(at 125.92875 113.465 -90)
		(descr "Capacitor SMD 0402")
		(tags "capacitor SMD 0402")
		(property "Reference" "C246"
			(at 0.825 -0.31375 90)
			(layer "B.SilkS")
			(effects
				(font
					(size 0.7 0.7)
					(thickness 0.15)
				)
				(justify left bottom mirror)
			)
		)
		(property "Value" "C_4u7_0402"
			(at 0 -1.4 90)
			(layer "B.Fab")
			(effects
				(font
					(size 0.7 0.7)
					(thickness 0.15)
				)
				(justify left bottom mirror)
			)
		)
		(property "Datasheet" "https://www.murata.com/products/productdetail?partno=GRM155R61A475MEAA%23"
			(at 0 0 270)
			(layer "F.Fab")
			(hide yes)
			(effects
				(font
					(size 1.27 1.27)
					(thickness 0.15)
				)
			)
		)
		(property "Description" "SMD Multilayer Ceramic Capacitor, 4.7 µF, 10 V, 0402 [1005 Metric], ± 20%, X5R, GRM Series"
			(at 0 0 270)
			(layer "F.Fab")
			(hide yes)
			(effects
				(font
					(size 1.27 1.27)
					(thickness 0.15)
				)
			)
		)
		(property "Author" "Antmicro"
			(at 12.46375 239.39375 0)
			(layer "B.Fab")
			(hide yes)
			(effects
				(font
					(size 1 1)
					(thickness 0.15)
				)
				(justify mirror)
			)
		)
		(property "Dielectric" ""
			(at 12.46375 239.39375 0)
			(layer "B.Fab")
			(hide yes)
			(effects
				(font
					(size 1 1)
					(thickness 0.15)
				)
				(justify mirror)
			)
		)
		(property "License" "Apache-2.0"
			(at 12.46375 239.39375 0)
			(layer "B.Fab")
			(hide yes)
			(effects
				(font
					(size 1 1)
					(thickness 0.15)
				)
				(justify mirror)
			)
		)
		(property "MPN" "GRM155R61A475MEAAD"
			(at 12.46375 239.39375 0)
			(layer "B.Fab")
			(hide yes)
			(effects
				(font
					(size 1 1)
					(thickness 0.15)
				)
				(justify mirror)
			)
		)
		(property "Manufacturer" "Murata"
			(at 12.46375 239.39375 0)
			(layer "B.Fab")
			(hide yes)
			(effects
				(font
					(size 1 1)
					(thickness 0.15)
				)
				(justify mirror)
			)
		)
		(property "Val" "4u7"
			(at 12.46375 239.39375 0)
			(layer "B.Fab")
			(hide yes)
			(effects
				(font
					(size 1 1)
					(thickness 0.15)
				)
				(justify mirror)
			)
		)
		(property "Voltage" ""
			(at 12.46375 239.39375 0)
			(layer "B.Fab")
			(hide yes)
			(effects
				(font
					(size 1 1)
					(thickness 0.15)
				)
				(justify mirror)
			)
		)
		(sheetname "/Interfaces/")
		(sheetfile "interfaces.kicad_sch")
		(attr smd)
		(fp_rect
			(start -0.925 0.47)
			(end 0.925 -0.47)
			(stroke
				(width 0.05)
				(type default)
			)
			(fill no)
			(layer "B.CrtYd")
		)
		(fp_line
			(start -0.494 0.25)
			(end 0.504 0.25)
			(stroke
				(width 0.15)
				(type solid)
			)
			(layer "B.Fab")
		)
		(fp_line
			(start 0.504 0.25)
			(end 0.504 -0.248)
			(stroke
				(width 0.15)
				(type solid)
			)
			(layer "B.Fab")
		)
		(fp_line
			(start -0.494 -0.248)
			(end -0.494 0.25)
			(stroke
				(width 0.15)
				(type solid)
			)
			(layer "B.Fab")
		)
		(fp_line
			(start 0.504 -0.248)
			(end -0.494 -0.248)
			(stroke
				(width 0.15)
				(type solid)
			)
			(layer "B.Fab")
		)
		(pad "1" smd roundrect
			(at -0.48 0 270)
			(size 0.59 0.64)
			(layers "B.Cu" "B.Mask" "B.Paste")
			(roundrect_rratio 0.25)
			(net 1 "GND")
			(pintype "passive")
		)
		(pad "2" smd roundrect
			(at 0.48 0 270)
			(size 0.59 0.64)
			(layers "B.Cu" "B.Mask" "B.Paste")
			(roundrect_rratio 0.25)
			(net 12 "Net-(U17-VDDA1.8)")
			(pintype "passive")
		)
	)
	(footprint "antmicro-footprints:C_0402_1005Metric"
		(layer "B.Cu")
		(at 122.865 113.465 -90)
		(descr "Capacitor SMD 0402")
		(tags "capacitor SMD 0402")
		(property "Reference" "C247"
			(at 0.825 -0.31375 90)
			(layer "B.SilkS")
			(effects
				(font
					(size 0.7 0.7)
					(thickness 0.15)
				)
				(justify left bottom mirror)
			)
		)
		(property "Value" "C_4u7_0402"
			(at 0 -1.4 90)
			(layer "B.Fab")
			(effects
				(font
					(size 0.7 0.7)
					(thickness 0.15)
				)
				(justify left bottom mirror)
			)
		)
		(property "Datasheet" "https://www.murata.com/products/productdetail?partno=GRM155R61A475MEAA%23"
			(at 0 0 270)
			(layer "F.Fab")
			(hide yes)
			(effects
				(font
					(size 1.27 1.27)
					(thickness 0.15)
				)
			)
		)
		(property "Description" "SMD Multilayer Ceramic Capacitor, 4.7 µF, 10 V, 0402 [1005 Metric], ± 20%, X5R, GRM Series"
			(at 0 0 270)
			(layer "F.Fab")
			(hide yes)
			(effects
				(font
					(size 1.27 1.27)
					(thickness 0.15)
				)
			)
		)
		(property "Author" "Antmicro"
			(at 9.4 236.33 0)
			(layer "B.Fab")
			(hide yes)
			(effects
				(font
					(size 1 1)
					(thickness 0.15)
				)
				(justify mirror)
			)
		)
		(property "Dielectric" ""
			(at 9.4 236.33 0)
			(layer "B.Fab")
			(hide yes)
			(effects
				(font
					(size 1 1)
					(thickness 0.15)
				)
				(justify mirror)
			)
		)
		(property "License" "Apache-2.0"
			(at 9.4 236.33 0)
			(layer "B.Fab")
			(hide yes)
			(effects
				(font
					(size 1 1)
					(thickness 0.15)
				)
				(justify mirror)
			)
		)
		(property "MPN" "GRM155R61A475MEAAD"
			(at 9.4 236.33 0)
			(layer "B.Fab")
			(hide yes)
			(effects
				(font
					(size 1 1)
					(thickness 0.15)
				)
				(justify mirror)
			)
		)
		(property "Manufacturer" "Murata"
			(at 9.4 236.33 0)
			(layer "B.Fab")
			(hide yes)
			(effects
				(font
					(size 1 1)
					(thickness 0.15)
				)
				(justify mirror)
			)
		)
		(property "Val" "4u7"
			(at 9.4 236.33 0)
			(layer "B.Fab")
			(hide yes)
			(effects
				(font
					(size 1 1)
					(thickness 0.15)
				)
				(justify mirror)
			)
		)
		(property "Voltage" ""
			(at 9.4 236.33 0)
			(layer "B.Fab")
			(hide yes)
			(effects
				(font
					(size 1 1)
					(thickness 0.15)
				)
				(justify mirror)
			)
		)
		(sheetname "/Interfaces/")
		(sheetfile "interfaces.kicad_sch")
		(attr smd)
		(fp_rect
			(start -0.925 0.47)
			(end 0.925 -0.47)
			(stroke
				(width 0.05)
				(type default)
			)
			(fill no)
			(layer "B.CrtYd")
		)
		(fp_line
			(start -0.494 0.25)
			(end 0.504 0.25)
			(stroke
				(width 0.15)
				(type solid)
			)
			(layer "B.Fab")
		)
		(fp_line
			(start 0.504 0.25)
			(end 0.504 -0.248)
			(stroke
				(width 0.15)
				(type solid)
			)
			(layer "B.Fab")
		)
		(fp_line
			(start -0.494 -0.248)
			(end -0.494 0.25)
			(stroke
				(width 0.15)
				(type solid)
			)
			(layer "B.Fab")
		)
		(fp_line
			(start 0.504 -0.248)
			(end -0.494 -0.248)
			(stroke
				(width 0.15)
				(type solid)
			)
			(layer "B.Fab")
		)
		(pad "1" smd roundrect
			(at -0.48 0 270)
			(size 0.59 0.64)
			(layers "B.Cu" "B.Mask" "B.Paste")
			(roundrect_rratio 0.25)
			(net 1 "GND")
			(pintype "passive")
		)
		(pad "2" smd roundrect
			(at 0.48 0 270)
			(size 0.59 0.64)
			(layers "B.Cu" "B.Mask" "B.Paste")
			(roundrect_rratio 0.25)
			(net 105 "Net-(C20-Pad2)")
			(pintype "passive")
		)
	)
	(footprint "antmicro-footprints:C_0402_1005Metric"
		(layer "B.Cu")
		(at 106.025 125.19 -90)
		(descr "Capacitor SMD 0402")
		(tags "capacitor SMD 0402")
		(property "Reference" "C130"
			(at 2.01 -0.375 90)
			(layer "B.SilkS")
			(effects
				(font
					(size 0.7 0.7)
					(thickness 0.15)
				)
				(justify left bottom mirror)
			)
		)
		(property "Value" "C_470n_0402"
			(at 0 -1.4 90)
			(layer "B.Fab")
			(effects
				(font
					(size 0.7 0.7)
					(thickness 0.15)
				)
				(justify left bottom mirror)
			)
		)
		(property "Datasheet" "https://product.tdk.com/en/search/capacitor/ceramic/mlcc/info?part_no=C1005X5R1E474M050BB"
			(at 0 0 270)
			(layer "F.Fab")
			(hide yes)
			(effects
				(font
					(size 1.27 1.27)
					(thickness 0.15)
				)
			)
		)
		(property "Description" "SMD Multilayer Ceramic Capacitor, 0.47 µF, 25 V, 0402 [1005 Metric], ± 20%, X5R, C"
			(at 0 0 270)
			(layer "F.Fab")
			(hide yes)
			(effects
				(font
					(size 1.27 1.27)
					(thickness 0.15)
				)
			)
		)
		(property "Author" "Antmicro"
			(at -19.165 231.215 0)
			(layer "B.Fab")
			(hide yes)
			(effects
				(font
					(size 1 1)
					(thickness 0.15)
				)
				(justify mirror)
			)
		)
		(property "Dielectric" ""
			(at -19.165 231.215 0)
			(layer "B.Fab")
			(hide yes)
			(effects
				(font
					(size 1 1)
					(thickness 0.15)
				)
				(justify mirror)
			)
		)
		(property "License" "Apache-2.0"
			(at -19.165 231.215 0)
			(layer "B.Fab")
			(hide yes)
			(effects
				(font
					(size 1 1)
					(thickness 0.15)
				)
				(justify mirror)
			)
		)
		(property "MPN" "C1005X5R1E474M050BB"
			(at -19.165 231.215 0)
			(layer "B.Fab")
			(hide yes)
			(effects
				(font
					(size 1 1)
					(thickness 0.15)
				)
				(justify mirror)
			)
		)
		(property "Manufacturer" "TDK"
			(at -19.165 231.215 0)
			(layer "B.Fab")
			(hide yes)
			(effects
				(font
					(size 1 1)
					(thickness 0.15)
				)
				(justify mirror)
			)
		)
		(property "Val" "470n"
			(at -19.165 231.215 0)
			(layer "B.Fab")
			(hide yes)
			(effects
				(font
					(size 1 1)
					(thickness 0.15)
				)
				(justify mirror)
			)
		)
		(property "Voltage" ""
			(at -19.165 231.215 0)
			(layer "B.Fab")
			(hide yes)
			(effects
				(font
					(size 1 1)
					(thickness 0.15)
				)
				(justify mirror)
			)
		)
		(property "DNP" ""
			(at 0 0 270)
			(unlocked yes)
			(layer "B.Fab")
			(hide yes)
			(effects
				(font
					(size 1 1)
					(thickness 0.15)
				)
				(justify mirror)
			)
		)
		(sheetname "/FPGA banks 13-16/")
		(sheetfile "fpga-banks-13-16.kicad_sch")
		(attr smd)
		(fp_rect
			(start -0.925 0.47)
			(end 0.925 -0.47)
			(stroke
				(width 0.05)
				(type default)
			)
			(fill no)
			(layer "B.CrtYd")
		)
		(fp_line
			(start -0.494 0.25)
			(end 0.504 0.25)
			(stroke
				(width 0.15)
				(type solid)
			)
			(layer "B.Fab")
		)
		(fp_line
			(start 0.504 0.25)
			(end 0.504 -0.248)
			(stroke
				(width 0.15)
				(type solid)
			)
			(layer "B.Fab")
		)
		(fp_line
			(start -0.494 -0.248)
			(end -0.494 0.25)
			(stroke
				(width 0.15)
				(type solid)
			)
			(layer "B.Fab")
		)
		(fp_line
			(start 0.504 -0.248)
			(end -0.494 -0.248)
			(stroke
				(width 0.15)
				(type solid)
			)
			(layer "B.Fab")
		)
		(pad "1" smd roundrect
			(at -0.48 0 270)
			(size 0.59 0.64)
			(layers "B.Cu" "B.Mask" "B.Paste")
			(roundrect_rratio 0.25)
			(net 1 "GND")
			(pintype "passive")
		)
		(pad "2" smd roundrect
			(at 0.48 0 270)
			(size 0.59 0.64)
			(layers "B.Cu" "B.Mask" "B.Paste")
			(roundrect_rratio 0.25)
			(net 2 "VCC3V3")
			(pintype "passive")
		)
	)
	(footprint "antmicro-footprints:R_0402_1005Metric"
		(layer "B.Cu")
		(at 107.275 123.225 90)
		(descr "Resistor SMD 0402")
		(tags "resistor SMD 0402")
		(property "Reference" "R85"
			(at -1.075 1.225 90)
			(layer "B.SilkS")
			(effects
				(font
					(size 0.7 0.7)
					(thickness 0.15)
				)
				(justify right bottom mirror)
			)
		)
		(property "Value" "R_4k7_0402"
			(at 0 -1.4 90)
			(layer "B.Fab")
			(effects
				(font
					(size 0.7 0.7)
					(thickness 0.15)
				)
				(justify right bottom mirror)
			)
		)
		(property "Datasheet" "https://www.bourns.com/docs/product-datasheets/cr.pdf"
			(at 0 0 90)
			(layer "F.Fab")
			(hide yes)
			(effects
				(font
					(size 1.27 1.27)
					(thickness 0.15)
				)
			)
		)
		(property "Description" "SMD Chip Resistor, 4.7 kohm, ± 1%, 62.5 mW, 0402 [1005 Metric], Thick Film, General Purpose"
			(at 0 0 90)
			(layer "F.Fab")
			(hide yes)
			(effects
				(font
					(size 1.27 1.27)
					(thickness 0.15)
				)
			)
		)
		(property "Author" "Antmicro"
			(at 230.5 15.95 0)
			(layer "B.Fab")
			(hide yes)
			(effects
				(font
					(size 1 1)
					(thickness 0.15)
				)
				(justify mirror)
			)
		)
		(property "License" "Apache-2.0"
			(at 230.5 15.95 0)
			(layer "B.Fab")
			(hide yes)
			(effects
				(font
					(size 1 1)
					(thickness 0.15)
				)
				(justify mirror)
			)
		)
		(property "MPN" "CR0402-FX-4701GLF"
			(at 230.5 15.95 0)
			(layer "B.Fab")
			(hide yes)
			(effects
				(font
					(size 1 1)
					(thickness 0.15)
				)
				(justify mirror)
			)
		)
		(property "Manufacturer" "Bourns"
			(at 230.5 15.95 0)
			(layer "B.Fab")
			(hide yes)
			(effects
				(font
					(size 1 1)
					(thickness 0.15)
				)
				(justify mirror)
			)
		)
		(property "Tolerance" "1%"
			(at 230.5 15.95 0)
			(layer "B.Fab")
			(hide yes)
			(effects
				(font
					(size 1 1)
					(thickness 0.15)
				)
				(justify mirror)
			)
		)
		(property "Val" "4k7"
			(at 230.5 15.95 0)
			(layer "B.Fab")
			(hide yes)
			(effects
				(font
					(size 1 1)
					(thickness 0.15)
				)
				(justify mirror)
			)
		)
		(sheetname "/FPGA banks 34-35 & CFG/")
		(sheetfile "fpga-banks-34-25-cfg.kicad_sch")
		(attr smd)
		(fp_rect
			(start -0.925 0.47)
			(end 0.925 -0.47)
			(stroke
				(width 0.05)
				(type default)
			)
			(fill no)
			(layer "B.CrtYd")
		)
		(fp_rect
			(start -0.5 0.25)
			(end 0.5 -0.25)
			(stroke
				(width 0.15)
				(type solid)
			)
			(fill no)
			(layer "B.Fab")
		)
		(pad "1" smd roundrect
			(at -0.48 0 90)
			(size 0.59 0.64)
			(layers "B.Cu" "B.Mask" "B.Paste")
			(roundrect_rratio 0.25)
			(net 2 "VCC3V3")
			(pintype "passive")
		)
		(pad "2" smd roundrect
			(at 0.48 0 90)
			(size 0.59 0.64)
			(layers "B.Cu" "B.Mask" "B.Paste")
			(roundrect_rratio 0.25)
			(net 342 "Net-(U14D-CFGBVS_0)")
			(pintype "passive")
		)
	)
	(footprint "antmicro-footprints:C_0402_1005Metric"
		(layer "B.Cu")
		(at 109.925 124.175 -90)
		(descr "Capacitor SMD 0402")
		(tags "capacitor SMD 0402")
		(property "Reference" "C119"
			(at -1.475 -1.375 90)
			(layer "B.SilkS")
			(effects
				(font
					(size 0.7 0.7)
					(thickness 0.15)
				)
				(justify left bottom mirror)
			)
		)
		(property "Value" "C_470n_0402"
			(at 0 -1.4 90)
			(layer "B.Fab")
			(effects
				(font
					(size 0.7 0.7)
					(thickness 0.15)
				)
				(justify left bottom mirror)
			)
		)
		(property "Datasheet" "https://product.tdk.com/en/search/capacitor/ceramic/mlcc/info?part_no=C1005X5R1E474M050BB"
			(at 0 0 270)
			(layer "F.Fab")
			(hide yes)
			(effects
				(font
					(size 1.27 1.27)
					(thickness 0.15)
				)
			)
		)
		(property "Description" "SMD Multilayer Ceramic Capacitor, 0.47 µF, 25 V, 0402 [1005 Metric], ± 20%, X5R, C"
			(at 0 0 270)
			(layer "F.Fab")
			(hide yes)
			(effects
				(font
					(size 1.27 1.27)
					(thickness 0.15)
				)
			)
		)
		(property "Author" "Antmicro"
			(at -14.25 234.1 0)
			(layer "B.Fab")
			(hide yes)
			(effects
				(font
					(size 1 1)
					(thickness 0.15)
				)
				(justify mirror)
			)
		)
		(property "Dielectric" ""
			(at -14.25 234.1 0)
			(layer "B.Fab")
			(hide yes)
			(effects
				(font
					(size 1 1)
					(thickness 0.15)
				)
				(justify mirror)
			)
		)
		(property "License" "Apache-2.0"
			(at -14.25 234.1 0)
			(layer "B.Fab")
			(hide yes)
			(effects
				(font
					(size 1 1)
					(thickness 0.15)
				)
				(justify mirror)
			)
		)
		(property "MPN" "C1005X5R1E474M050BB"
			(at -14.25 234.1 0)
			(layer "B.Fab")
			(hide yes)
			(effects
				(font
					(size 1 1)
					(thickness 0.15)
				)
				(justify mirror)
			)
		)
		(property "Manufacturer" "TDK"
			(at -14.25 234.1 0)
			(layer "B.Fab")
			(hide yes)
			(effects
				(font
					(size 1 1)
					(thickness 0.15)
				)
				(justify mirror)
			)
		)
		(property "Val" "470n"
			(at -14.25 234.1 0)
			(layer "B.Fab")
			(hide yes)
			(effects
				(font
					(size 1 1)
					(thickness 0.15)
				)
				(justify mirror)
			)
		)
		(property "Voltage" ""
			(at -14.25 234.1 0)
			(layer "B.Fab")
			(hide yes)
			(effects
				(font
					(size 1 1)
					(thickness 0.15)
				)
				(justify mirror)
			)
		)
		(sheetname "/FPGA banks 13-16/")
		(sheetfile "fpga-banks-13-16.kicad_sch")
		(attr smd)
		(fp_rect
			(start -0.925 0.47)
			(end 0.925 -0.47)
			(stroke
				(width 0.05)
				(type default)
			)
			(fill no)
			(layer "B.CrtYd")
		)
		(fp_line
			(start -0.494 0.25)
			(end 0.504 0.25)
			(stroke
				(width 0.15)
				(type solid)
			)
			(layer "B.Fab")
		)
		(fp_line
			(start 0.504 0.25)
			(end 0.504 -0.248)
			(stroke
				(width 0.15)
				(type solid)
			)
			(layer "B.Fab")
		)
		(fp_line
			(start -0.494 -0.248)
			(end -0.494 0.25)
			(stroke
				(width 0.15)
				(type solid)
			)
			(layer "B.Fab")
		)
		(fp_line
			(start 0.504 -0.248)
			(end -0.494 -0.248)
			(stroke
				(width 0.15)
				(type solid)
			)
			(layer "B.Fab")
		)
		(pad "1" smd roundrect
			(at -0.48 0 270)
			(size 0.59 0.64)
			(layers "B.Cu" "B.Mask" "B.Paste")
			(roundrect_rratio 0.25)
			(net 1 "GND")
			(pintype "passive")
		)
		(pad "2" smd roundrect
			(at 0.48 0 270)
			(size 0.59 0.64)
			(layers "B.Cu" "B.Mask" "B.Paste")
			(roundrect_rratio 0.25)
			(net 2 "VCC3V3")
			(pintype "passive")
		)
	)
	(footprint "antmicro-footprints:C_0402_1005Metric"
		(layer "B.Cu")
		(at 124.375 129.665 -90)
		(descr "Capacitor SMD 0402")
		(tags "capacitor SMD 0402")
		(property "Reference" "C248"
			(at 0.835 -0.385 90)
			(layer "B.SilkS")
			(effects
				(font
					(size 0.7 0.7)
					(thickness 0.15)
				)
				(justify left bottom mirror)
			)
		)
		(property "Value" "C_100n_0402"
			(at 0 -1.4 90)
			(layer "B.Fab")
			(effects
				(font
					(size 0.7 0.7)
					(thickness 0.15)
				)
				(justify left bottom mirror)
			)
		)
		(property "Datasheet" "https://www.murata.com/products/productdetail?partno=GRM155R61H104KE14%23"
			(at 0 0 270)
			(layer "F.Fab")
			(hide yes)
			(effects
				(font
					(size 1.27 1.27)
					(thickness 0.15)
				)
			)
		)
		(property "Description" "SMD Multilayer Ceramic Capacitor, 0.1 µF, 50 V, 0402 [1005 Metric], ± 10%, X5R, GRM Series"
			(at 0 0 270)
			(layer "F.Fab")
			(hide yes)
			(effects
				(font
					(size 1.27 1.27)
					(thickness 0.15)
				)
			)
		)
		(property "Author" "Antmicro"
			(at -5.29 254.04 0)
			(layer "B.Fab")
			(hide yes)
			(effects
				(font
					(size 1 1)
					(thickness 0.15)
				)
				(justify mirror)
			)
		)
		(property "Dielectric" "X5R"
			(at -5.29 254.04 0)
			(layer "B.Fab")
			(hide yes)
			(effects
				(font
					(size 1 1)
					(thickness 0.15)
				)
				(justify mirror)
			)
		)
		(property "License" "Apache-2.0"
			(at -5.29 254.04 0)
			(layer "B.Fab")
			(hide yes)
			(effects
				(font
					(size 1 1)
					(thickness 0.15)
				)
				(justify mirror)
			)
		)
		(property "MPN" "GRM155R61H104KE14D"
			(at -5.29 254.04 0)
			(layer "B.Fab")
			(hide yes)
			(effects
				(font
					(size 1 1)
					(thickness 0.15)
				)
				(justify mirror)
			)
		)
		(property "Manufacturer" "Murata"
			(at -5.29 254.04 0)
			(layer "B.Fab")
			(hide yes)
			(effects
				(font
					(size 1 1)
					(thickness 0.15)
				)
				(justify mirror)
			)
		)
		(property "Val" "100n"
			(at -5.29 254.04 0)
			(layer "B.Fab")
			(hide yes)
			(effects
				(font
					(size 1 1)
					(thickness 0.15)
				)
				(justify mirror)
			)
		)
		(property "Voltage" "50V"
			(at -5.29 254.04 0)
			(layer "B.Fab")
			(hide yes)
			(effects
				(font
					(size 1 1)
					(thickness 0.15)
				)
				(justify mirror)
			)
		)
		(sheetname "/Interfaces/")
		(sheetfile "interfaces.kicad_sch")
		(attr smd)
		(fp_rect
			(start -0.925 0.47)
			(end 0.925 -0.47)
			(stroke
				(width 0.05)
				(type default)
			)
			(fill no)
			(layer "B.CrtYd")
		)
		(fp_line
			(start -0.494 0.25)
			(end 0.504 0.25)
			(stroke
				(width 0.15)
				(type solid)
			)
			(layer "B.Fab")
		)
		(fp_line
			(start 0.504 0.25)
			(end 0.504 -0.248)
			(stroke
				(width 0.15)
				(type solid)
			)
			(layer "B.Fab")
		)
		(fp_line
			(start -0.494 -0.248)
			(end -0.494 0.25)
			(stroke
				(width 0.15)
				(type solid)
			)
			(layer "B.Fab")
		)
		(fp_line
			(start 0.504 -0.248)
			(end -0.494 -0.248)
			(stroke
				(width 0.15)
				(type solid)
			)
			(layer "B.Fab")
		)
		(pad "1" smd roundrect
			(at -0.48 0 270)
			(size 0.59 0.64)
			(layers "B.Cu" "B.Mask" "B.Paste")
			(roundrect_rratio 0.25)
			(net 1 "GND")
			(pintype "passive")
		)
		(pad "2" smd roundrect
			(at 0.48 0 270)
			(size 0.59 0.64)
			(layers "B.Cu" "B.Mask" "B.Paste")
			(roundrect_rratio 0.25)
			(net 108 "Net-(C177-Pad2)")
			(pintype "passive")
		)
	)
	(footprint "antmicro-footprints:C_0402_1005Metric"
		(layer "B.Cu")
		(at 124.065 109.365 90)
		(descr "Capacitor SMD 0402")
		(tags "capacitor SMD 0402")
		(property "Reference" "C249"
			(at 0.86 0.425 90)
			(layer "B.SilkS")
			(effects
				(font
					(size 0.7 0.7)
					(thickness 0.15)
				)
				(justify right bottom mirror)
			)
		)
		(property "Value" "C_100n_0402"
			(at 0 -1.4 90)
			(layer "B.Fab")
			(effects
				(font
					(size 0.7 0.7)
					(thickness 0.15)
				)
				(justify right bottom mirror)
			)
		)
		(property "Datasheet" "https://www.murata.com/products/productdetail?partno=GRM155R61H104KE14%23"
			(at 0 0 90)
			(layer "F.Fab")
			(hide yes)
			(effects
				(font
					(size 1.27 1.27)
					(thickness 0.15)
				)
			)
		)
		(property "Description" "SMD Multilayer Ceramic Capacitor, 0.1 µF, 50 V, 0402 [1005 Metric], ± 10%, X5R, GRM Series"
			(at 0 0 90)
			(layer "F.Fab")
			(hide yes)
			(effects
				(font
					(size 1.27 1.27)
					(thickness 0.15)
				)
			)
		)
		(property "Author" "Antmicro"
			(at 233.43 -14.7 0)
			(layer "B.Fab")
			(hide yes)
			(effects
				(font
					(size 1 1)
					(thickness 0.15)
				)
				(justify mirror)
			)
		)
		(property "Dielectric" "X5R"
			(at 233.43 -14.7 0)
			(layer "B.Fab")
			(hide yes)
			(effects
				(font
					(size 1 1)
					(thickness 0.15)
				)
				(justify mirror)
			)
		)
		(property "License" "Apache-2.0"
			(at 233.43 -14.7 0)
			(layer "B.Fab")
			(hide yes)
			(effects
				(font
					(size 1 1)
					(thickness 0.15)
				)
				(justify mirror)
			)
		)
		(property "MPN" "GRM155R61H104KE14D"
			(at 233.43 -14.7 0)
			(layer "B.Fab")
			(hide yes)
			(effects
				(font
					(size 1 1)
					(thickness 0.15)
				)
				(justify mirror)
			)
		)
		(property "Manufacturer" "Murata"
			(at 233.43 -14.7 0)
			(layer "B.Fab")
			(hide yes)
			(effects
				(font
					(size 1 1)
					(thickness 0.15)
				)
				(justify mirror)
			)
		)
		(property "Val" "100n"
			(at 233.43 -14.7 0)
			(layer "B.Fab")
			(hide yes)
			(effects
				(font
					(size 1 1)
					(thickness 0.15)
				)
				(justify mirror)
			)
		)
		(property "Voltage" "50V"
			(at 233.43 -14.7 0)
			(layer "B.Fab")
			(hide yes)
			(effects
				(font
					(size 1 1)
					(thickness 0.15)
				)
				(justify mirror)
			)
		)
		(sheetname "/Interfaces/")
		(sheetfile "interfaces.kicad_sch")
		(attr smd)
		(fp_rect
			(start -0.925 0.47)
			(end 0.925 -0.47)
			(stroke
				(width 0.05)
				(type default)
			)
			(fill no)
			(layer "B.CrtYd")
		)
		(fp_line
			(start 0.504 -0.248)
			(end -0.494 -0.248)
			(stroke
				(width 0.15)
				(type solid)
			)
			(layer "B.Fab")
		)
		(fp_line
			(start -0.494 -0.248)
			(end -0.494 0.25)
			(stroke
				(width 0.15)
				(type solid)
			)
			(layer "B.Fab")
		)
		(fp_line
			(start 0.504 0.25)
			(end 0.504 -0.248)
			(stroke
				(width 0.15)
				(type solid)
			)
			(layer "B.Fab")
		)
		(fp_line
			(start -0.494 0.25)
			(end 0.504 0.25)
			(stroke
				(width 0.15)
				(type solid)
			)
			(layer "B.Fab")
		)
		(pad "1" smd roundrect
			(at -0.48 0 90)
			(size 0.59 0.64)
			(layers "B.Cu" "B.Mask" "B.Paste")
			(roundrect_rratio 0.25)
			(net 1 "GND")
			(pintype "passive")
		)
		(pad "2" smd roundrect
			(at 0.48 0 90)
			(size 0.59 0.64)
			(layers "B.Cu" "B.Mask" "B.Paste")
			(roundrect_rratio 0.25)
			(net 105 "Net-(C20-Pad2)")
			(pintype "passive")
		)
	)
	(footprint "antmicro-footprints:R_0402_1005Metric"
		(layer "B.Cu")
		(at 137.84 118.565 180)
		(descr "Resistor SMD 0402")
		(tags "resistor SMD 0402")
		(property "Reference" "R9"
			(at -0.76 0.465 0)
			(layer "B.SilkS")
			(effects
				(font
					(size 0.7 0.7)
					(thickness 0.15)
				)
				(justify left bottom mirror)
			)
		)
		(property "Value" "R_22R_0402"
			(at 0 -1.4 0)
			(layer "B.Fab")
			(effects
				(font
					(size 0.7 0.7)
					(thickness 0.15)
				)
				(justify left bottom mirror)
			)
		)
		(property "Datasheet" "https://www.bourns.com/docs/product-datasheets/cr.pdf"
			(at 0 0 180)
			(layer "F.Fab")
			(hide yes)
			(effects
				(font
					(size 1.27 1.27)
					(thickness 0.15)
				)
			)
		)
		(property "Description" "SMD Chip Resistor, 22 ohm, ± 1%, 62.5 mW, 0402 [1005 Metric], Thick Film, General Purpose"
			(at 0 0 180)
			(layer "F.Fab")
			(hide yes)
			(effects
				(font
					(size 1.27 1.27)
					(thickness 0.15)
				)
			)
		)
		(property "Author" "Antmicro"
			(at 275.68 237.13 0)
			(layer "B.Fab")
			(hide yes)
			(effects
				(font
					(size 1 1)
					(thickness 0.15)
				)
				(justify mirror)
			)
		)
		(property "License" "Apache-2.0"
			(at 275.68 237.13 0)
			(layer "B.Fab")
			(hide yes)
			(effects
				(font
					(size 1 1)
					(thickness 0.15)
				)
				(justify mirror)
			)
		)
		(property "MPN" "CR0402-FX-22R0GLF"
			(at 275.68 237.13 0)
			(layer "B.Fab")
			(hide yes)
			(effects
				(font
					(size 1 1)
					(thickness 0.15)
				)
				(justify mirror)
			)
		)
		(property "Manufacturer" "Bourns"
			(at 275.68 237.13 0)
			(layer "B.Fab")
			(hide yes)
			(effects
				(font
					(size 1 1)
					(thickness 0.15)
				)
				(justify mirror)
			)
		)
		(property "Tolerance" "1%"
			(at 275.68 237.13 0)
			(layer "B.Fab")
			(hide yes)
			(effects
				(font
					(size 1 1)
					(thickness 0.15)
				)
				(justify mirror)
			)
		)
		(property "Val" "22R"
			(at 275.68 237.13 0)
			(layer "B.Fab")
			(hide yes)
			(effects
				(font
					(size 1 1)
					(thickness 0.15)
				)
				(justify mirror)
			)
		)
		(sheetname "/Interfaces/")
		(sheetfile "interfaces.kicad_sch")
		(attr smd)
		(fp_rect
			(start -0.925 0.47)
			(end 0.925 -0.47)
			(stroke
				(width 0.05)
				(type default)
			)
			(fill no)
			(layer "B.CrtYd")
		)
		(fp_rect
			(start -0.5 0.25)
			(end 0.5 -0.25)
			(stroke
				(width 0.15)
				(type solid)
			)
			(fill no)
			(layer "B.Fab")
		)
		(pad "1" smd roundrect
			(at -0.48 0 180)
			(size 0.59 0.64)
			(layers "B.Cu" "B.Mask" "B.Paste")
			(roundrect_rratio 0.25)
			(net 306 "Net-(U1-CLK)")
			(pintype "passive")
		)
		(pad "2" smd roundrect
			(at 0.48 0 180)
			(size 0.59 0.64)
			(layers "B.Cu" "B.Mask" "B.Paste")
			(roundrect_rratio 0.25)
			(net 330 "MMC_CLK")
			(pintype "passive")
		)
	)
	(footprint "antmicro-footprints:C_0402_1005Metric"
		(layer "B.Cu")
		(at 101.825 128.825)
		(descr "Capacitor SMD 0402")
		(tags "capacitor SMD 0402")
		(property "Reference" "C243"
			(at -1.525 1.375 0)
			(layer "B.SilkS")
			(effects
				(font
					(size 0.7 0.7)
					(thickness 0.15)
				)
				(justify right bottom mirror)
			)
		)
		(property "Value" "C_470n_0402"
			(at 0 -1.4 0)
			(layer "B.Fab")
			(effects
				(font
					(size 0.7 0.7)
					(thickness 0.15)
				)
				(justify right bottom mirror)
			)
		)
		(property "Datasheet" "https://product.tdk.com/en/search/capacitor/ceramic/mlcc/info?part_no=C1005X5R1E474M050BB"
			(at 0 0 0)
			(layer "F.Fab")
			(hide yes)
			(effects
				(font
					(size 1.27 1.27)
					(thickness 0.15)
				)
			)
		)
		(property "Description" "SMD Multilayer Ceramic Capacitor, 0.47 µF, 25 V, 0402 [1005 Metric], ± 20%, X5R, C"
			(at 0 0 0)
			(layer "F.Fab")
			(hide yes)
			(effects
				(font
					(size 1.27 1.27)
					(thickness 0.15)
				)
			)
		)
		(property "Author" "Antmicro"
			(at 0 0 0)
			(layer "B.Fab")
			(hide yes)
			(effects
				(font
					(size 1 1)
					(thickness 0.15)
				)
				(justify mirror)
			)
		)
		(property "Dielectric" ""
			(at 0 0 0)
			(layer "B.Fab")
			(hide yes)
			(effects
				(font
					(size 1 1)
					(thickness 0.15)
				)
				(justify mirror)
			)
		)
		(property "License" "Apache-2.0"
			(at 0 0 0)
			(layer "B.Fab")
			(hide yes)
			(effects
				(font
					(size 1 1)
					(thickness 0.15)
				)
				(justify mirror)
			)
		)
		(property "MPN" "C1005X5R1E474M050BB"
			(at 0 0 0)
			(layer "B.Fab")
			(hide yes)
			(effects
				(font
					(size 1 1)
					(thickness 0.15)
				)
				(justify mirror)
			)
		)
		(property "Manufacturer" "TDK"
			(at 0 0 0)
			(layer "B.Fab")
			(hide yes)
			(effects
				(font
					(size 1 1)
					(thickness 0.15)
				)
				(justify mirror)
			)
		)
		(property "Val" "470n"
			(at 0 0 0)
			(layer "B.Fab")
			(hide yes)
			(effects
				(font
					(size 1 1)
					(thickness 0.15)
				)
				(justify mirror)
			)
		)
		(property "Voltage" ""
			(at 0 0 0)
			(layer "B.Fab")
			(hide yes)
			(effects
				(font
					(size 1 1)
					(thickness 0.15)
				)
				(justify mirror)
			)
		)
		(property "DNP" ""
			(at 0 0 0)
			(unlocked yes)
			(layer "B.Fab")
			(hide yes)
			(effects
				(font
					(size 1 1)
					(thickness 0.15)
				)
				(justify mirror)
			)
		)
		(sheetname "/FPGA banks 34-35 & CFG/")
		(sheetfile "fpga-banks-34-25-cfg.kicad_sch")
		(attr smd)
		(fp_rect
			(start -0.925 0.47)
			(end 0.925 -0.47)
			(stroke
				(width 0.05)
				(type default)
			)
			(fill no)
			(layer "B.CrtYd")
		)
		(fp_line
			(start -0.494 -0.248)
			(end -0.494 0.25)
			(stroke
				(width 0.15)
				(type solid)
			)
			(layer "B.Fab")
		)
		(fp_line
			(start -0.494 0.25)
			(end 0.504 0.25)
			(stroke
				(width 0.15)
				(type solid)
			)
			(layer "B.Fab")
		)
		(fp_line
			(start 0.504 -0.248)
			(end -0.494 -0.248)
			(stroke
				(width 0.15)
				(type solid)
			)
			(layer "B.Fab")
		)
		(fp_line
			(start 0.504 0.25)
			(end 0.504 -0.248)
			(stroke
				(width 0.15)
				(type solid)
			)
			(layer "B.Fab")
		)
		(pad "1" smd roundrect
			(at -0.48 0)
			(size 0.59 0.64)
			(layers "B.Cu" "B.Mask" "B.Paste")
			(roundrect_rratio 0.25)
			(net 1 "GND")
			(pintype "passive")
		)
		(pad "2" smd roundrect
			(at 0.48 0)
			(size 0.59 0.64)
			(layers "B.Cu" "B.Mask" "B.Paste")
			(roundrect_rratio 0.25)
			(net 3 "VCC1V35")
			(pintype "passive")
		)
	)
	(footprint "antmicro-footprints:C_0402_1005Metric"
		(layer "B.Cu")
		(at 99.025 128.175 -90)
		(descr "Capacitor SMD 0402")
		(tags "capacitor SMD 0402")
		(property "Reference" "C244"
			(at 0.825 -0.375 90)
			(layer "B.SilkS")
			(effects
				(font
					(size 0.7 0.7)
					(thickness 0.15)
				)
				(justify left bottom mirror)
			)
		)
		(property "Value" "C_470n_0402"
			(at 0 -1.4 90)
			(layer "B.Fab")
			(effects
				(font
					(size 0.7 0.7)
					(thickness 0.15)
				)
				(justify left bottom mirror)
			)
		)
		(property "Datasheet" "https://product.tdk.com/en/search/capacitor/ceramic/mlcc/info?part_no=C1005X5R1E474M050BB"
			(at 0 0 270)
			(layer "F.Fab")
			(hide yes)
			(effects
				(font
					(size 1.27 1.27)
					(thickness 0.15)
				)
			)
		)
		(property "Description" "SMD Multilayer Ceramic Capacitor, 0.47 µF, 25 V, 0402 [1005 Metric], ± 20%, X5R, C"
			(at 0 0 270)
			(layer "F.Fab")
			(hide yes)
			(effects
				(font
					(size 1.27 1.27)
					(thickness 0.15)
				)
			)
		)
		(property "Author" "Antmicro"
			(at -29.15 227.2 0)
			(layer "B.Fab")
			(hide yes)
			(effects
				(font
					(size 1 1)
					(thickness 0.15)
				)
				(justify mirror)
			)
		)
		(property "Dielectric" ""
			(at -29.15 227.2 0)
			(layer "B.Fab")
			(hide yes)
			(effects
				(font
					(size 1 1)
					(thickness 0.15)
				)
				(justify mirror)
			)
		)
		(property "License" "Apache-2.0"
			(at -29.15 227.2 0)
			(layer "B.Fab")
			(hide yes)
			(effects
				(font
					(size 1 1)
					(thickness 0.15)
				)
				(justify mirror)
			)
		)
		(property "MPN" "C1005X5R1E474M050BB"
			(at -29.15 227.2 0)
			(layer "B.Fab")
			(hide yes)
			(effects
				(font
					(size 1 1)
					(thickness 0.15)
				)
				(justify mirror)
			)
		)
		(property "Manufacturer" "TDK"
			(at -29.15 227.2 0)
			(layer "B.Fab")
			(hide yes)
			(effects
				(font
					(size 1 1)
					(thickness 0.15)
				)
				(justify mirror)
			)
		)
		(property "Val" "470n"
			(at -29.15 227.2 0)
			(layer "B.Fab")
			(hide yes)
			(effects
				(font
					(size 1 1)
					(thickness 0.15)
				)
				(justify mirror)
			)
		)
		(property "Voltage" ""
			(at -29.15 227.2 0)
			(layer "B.Fab")
			(hide yes)
			(effects
				(font
					(size 1 1)
					(thickness 0.15)
				)
				(justify mirror)
			)
		)
		(property "DNP" ""
			(at 0 0 270)
			(unlocked yes)
			(layer "B.Fab")
			(hide yes)
			(effects
				(font
					(size 1 1)
					(thickness 0.15)
				)
				(justify mirror)
			)
		)
		(sheetname "/FPGA banks 34-35 & CFG/")
		(sheetfile "fpga-banks-34-25-cfg.kicad_sch")
		(attr smd)
		(fp_rect
			(start -0.925 0.47)
			(end 0.925 -0.47)
			(stroke
				(width 0.05)
				(type default)
			)
			(fill no)
			(layer "B.CrtYd")
		)
		(fp_line
			(start -0.494 0.25)
			(end 0.504 0.25)
			(stroke
				(width 0.15)
				(type solid)
			)
			(layer "B.Fab")
		)
		(fp_line
			(start 0.504 0.25)
			(end 0.504 -0.248)
			(stroke
				(width 0.15)
				(type solid)
			)
			(layer "B.Fab")
		)
		(fp_line
			(start -0.494 -0.248)
			(end -0.494 0.25)
			(stroke
				(width 0.15)
				(type solid)
			)
			(layer "B.Fab")
		)
		(fp_line
			(start 0.504 -0.248)
			(end -0.494 -0.248)
			(stroke
				(width 0.15)
				(type solid)
			)
			(layer "B.Fab")
		)
		(pad "1" smd roundrect
			(at -0.48 0 270)
			(size 0.59 0.64)
			(layers "B.Cu" "B.Mask" "B.Paste")
			(roundrect_rratio 0.25)
			(net 1 "GND")
			(pintype "passive")
		)
		(pad "2" smd roundrect
			(at 0.48 0 270)
			(size 0.59 0.64)
			(layers "B.Cu" "B.Mask" "B.Paste")
			(roundrect_rratio 0.25)
			(net 3 "VCC1V35")
			(pintype "passive")
		)
	)
	(footprint "antmicro-footprints:C_0402_1005Metric"
		(layer "B.Cu")
		(at 121.315 129.665 -90)
		(descr "Capacitor SMD 0402")
		(tags "capacitor SMD 0402")
		(property "Reference" "C222"
			(at 0.835 -0.385 90)
			(layer "B.SilkS")
			(effects
				(font
					(size 0.7 0.7)
					(thickness 0.15)
				)
				(justify left bottom mirror)
			)
		)
		(property "Value" "C_4u7_0402"
			(at 0 -1.4 90)
			(layer "B.Fab")
			(effects
				(font
					(size 0.7 0.7)
					(thickness 0.15)
				)
				(justify left bottom mirror)
			)
		)
		(property "Datasheet" "https://www.murata.com/products/productdetail?partno=GRM155R61A475MEAA%23"
			(at 0 0 270)
			(layer "F.Fab")
			(hide yes)
			(effects
				(font
					(size 1.27 1.27)
					(thickness 0.15)
				)
			)
		)
		(property "Description" "SMD Multilayer Ceramic Capacitor, 4.7 µF, 10 V, 0402 [1005 Metric], ± 20%, X5R, GRM Series"
			(at 0 0 270)
			(layer "F.Fab")
			(hide yes)
			(effects
				(font
					(size 1.27 1.27)
					(thickness 0.15)
				)
			)
		)
		(property "Author" "Antmicro"
			(at -8.35 250.98 0)
			(layer "B.Fab")
			(hide yes)
			(effects
				(font
					(size 1 1)
					(thickness 0.15)
				)
				(justify mirror)
			)
		)
		(property "Dielectric" ""
			(at -8.35 250.98 0)
			(layer "B.Fab")
			(hide yes)
			(effects
				(font
					(size 1 1)
					(thickness 0.15)
				)
				(justify mirror)
			)
		)
		(property "License" "Apache-2.0"
			(at -8.35 250.98 0)
			(layer "B.Fab")
			(hide yes)
			(effects
				(font
					(size 1 1)
					(thickness 0.15)
				)
				(justify mirror)
			)
		)
		(property "MPN" "GRM155R61A475MEAAD"
			(at -8.35 250.98 0)
			(layer "B.Fab")
			(hide yes)
			(effects
				(font
					(size 1 1)
					(thickness 0.15)
				)
				(justify mirror)
			)
		)
		(property "Manufacturer" "Murata"
			(at -8.35 250.98 0)
			(layer "B.Fab")
			(hide yes)
			(effects
				(font
					(size 1 1)
					(thickness 0.15)
				)
				(justify mirror)
			)
		)
		(property "Val" "4u7"
			(at -8.35 250.98 0)
			(layer "B.Fab")
			(hide yes)
			(effects
				(font
					(size 1 1)
					(thickness 0.15)
				)
				(justify mirror)
			)
		)
		(property "Voltage" ""
			(at -8.35 250.98 0)
			(layer "B.Fab")
			(hide yes)
			(effects
				(font
					(size 1 1)
					(thickness 0.15)
				)
				(justify mirror)
			)
		)
		(sheetname "/Interfaces/")
		(sheetfile "interfaces.kicad_sch")
		(attr smd)
		(fp_rect
			(start -0.925 0.47)
			(end 0.925 -0.47)
			(stroke
				(width 0.05)
				(type default)
			)
			(fill no)
			(layer "B.CrtYd")
		)
		(fp_line
			(start -0.494 0.25)
			(end 0.504 0.25)
			(stroke
				(width 0.15)
				(type solid)
			)
			(layer "B.Fab")
		)
		(fp_line
			(start 0.504 0.25)
			(end 0.504 -0.248)
			(stroke
				(width 0.15)
				(type solid)
			)
			(layer "B.Fab")
		)
		(fp_line
			(start -0.494 -0.248)
			(end -0.494 0.25)
			(stroke
				(width 0.15)
				(type solid)
			)
			(layer "B.Fab")
		)
		(fp_line
			(start 0.504 -0.248)
			(end -0.494 -0.248)
			(stroke
				(width 0.15)
				(type solid)
			)
			(layer "B.Fab")
		)
		(pad "1" smd roundrect
			(at -0.48 0 270)
			(size 0.59 0.64)
			(layers "B.Cu" "B.Mask" "B.Paste")
			(roundrect_rratio 0.25)
			(net 1 "GND")
			(pintype "passive")
		)
		(pad "2" smd roundrect
			(at 0.48 0 270)
			(size 0.59 0.64)
			(layers "B.Cu" "B.Mask" "B.Paste")
			(roundrect_rratio 0.25)
			(net 2 "VCC3V3")
			(pintype "passive")
		)
	)
	(footprint "antmicro-footprints:R_0402_1005Metric"
		(layer "B.Cu")
		(at 117.54 152.665)
		(descr "Resistor SMD 0402")
		(tags "resistor SMD 0402")
		(property "Reference" "R116"
			(at 0.805 0.425 0)
			(layer "B.SilkS")
			(effects
				(font
					(size 0.7 0.7)
					(thickness 0.15)
				)
				(justify right bottom mirror)
			)
		)
		(property "Value" "R_0R_0402"
			(at 0 -1.4 0)
			(layer "B.Fab")
			(effects
				(font
					(size 0.7 0.7)
					(thickness 0.15)
				)
				(justify right bottom mirror)
			)
		)
		(property "Datasheet" "https://industrial.panasonic.com/cdbs/www-data/pdf/RDA0000/AOA0000C301.pdf"
			(at 0 0 0)
			(layer "F.Fab")
			(hide yes)
			(effects
				(font
					(size 1.27 1.27)
					(thickness 0.15)
				)
			)
		)
		(property "Description" "SMD Chip Resistor, Jumper, 0 ohm, 100 mW, 0402 [1005 Metric], Thick Film, General Purpose"
			(at 0 0 0)
			(layer "F.Fab")
			(hide yes)
			(effects
				(font
					(size 1.27 1.27)
					(thickness 0.15)
				)
			)
		)
		(property "Author" "Antmicro"
			(at 0 0 0)
			(layer "B.Fab")
			(hide yes)
			(effects
				(font
					(size 1 1)
					(thickness 0.15)
				)
				(justify mirror)
			)
		)
		(property "Current" "1A"
			(at 0 0 0)
			(layer "B.Fab")
			(hide yes)
			(effects
				(font
					(size 1 1)
					(thickness 0.15)
				)
				(justify mirror)
			)
		)
		(property "License" "Apache-2.0"
			(at 0 0 0)
			(layer "B.Fab")
			(hide yes)
			(effects
				(font
					(size 1 1)
					(thickness 0.15)
				)
				(justify mirror)
			)
		)
		(property "MPN" "ERJ2GE0R00X"
			(at 0 0 0)
			(layer "B.Fab")
			(hide yes)
			(effects
				(font
					(size 1 1)
					(thickness 0.15)
				)
				(justify mirror)
			)
		)
		(property "Manufacturer" "Panasonic"
			(at 0 0 0)
			(layer "B.Fab")
			(hide yes)
			(effects
				(font
					(size 1 1)
					(thickness 0.15)
				)
				(justify mirror)
			)
		)
		(property "Tolerance" "~"
			(at 0 0 0)
			(layer "B.Fab")
			(hide yes)
			(effects
				(font
					(size 1 1)
					(thickness 0.15)
				)
				(justify mirror)
			)
		)
		(property "Val" "0R"
			(at 0 0 0)
			(layer "B.Fab")
			(hide yes)
			(effects
				(font
					(size 1 1)
					(thickness 0.15)
				)
				(justify mirror)
			)
		)
		(sheetname "/Edge connector/")
		(sheetfile "edge-connector.kicad_sch")
		(attr smd)
		(fp_rect
			(start -0.925 0.47)
			(end 0.925 -0.47)
			(stroke
				(width 0.05)
				(type default)
			)
			(fill no)
			(layer "B.CrtYd")
		)
		(fp_rect
			(start -0.5 0.25)
			(end 0.5 -0.25)
			(stroke
				(width 0.15)
				(type solid)
			)
			(fill no)
			(layer "B.Fab")
		)
		(pad "1" smd roundrect
			(at -0.48 0)
			(size 0.59 0.64)
			(layers "B.Cu" "B.Mask" "B.Paste")
			(roundrect_rratio 0.25)
			(net 585 "HPM_STBY_EN_R")
			(pintype "passive")
		)
		(pad "2" smd roundrect
			(at 0.48 0)
			(size 0.59 0.64)
			(layers "B.Cu" "B.Mask" "B.Paste")
			(roundrect_rratio 0.25)
			(net 256 "/Edge connector/HPM_STBY_EN")
			(pintype "passive")
		)
	)
	(footprint "antmicro-footprints:R_0402_1005Metric"
		(layer "B.Cu")
		(at 117.54 153.665)
		(descr "Resistor SMD 0402")
		(tags "resistor SMD 0402")
		(property "Reference" "R154"
			(at 0.805 0.425 0)
			(layer "B.SilkS")
			(effects
				(font
					(size 0.7 0.7)
					(thickness 0.15)
				)
				(justify right bottom mirror)
			)
		)
		(property "Value" "R_0R_0402"
			(at 0 -1.4 0)
			(layer "B.Fab")
			(effects
				(font
					(size 0.7 0.7)
					(thickness 0.15)
				)
				(justify right bottom mirror)
			)
		)
		(property "Datasheet" "https://industrial.panasonic.com/cdbs/www-data/pdf/RDA0000/AOA0000C301.pdf"
			(at 0 0 0)
			(layer "F.Fab")
			(hide yes)
			(effects
				(font
					(size 1.27 1.27)
					(thickness 0.15)
				)
			)
		)
		(property "Description" "SMD Chip Resistor, Jumper, 0 ohm, 100 mW, 0402 [1005 Metric], Thick Film, General Purpose"
			(at 0 0 0)
			(layer "F.Fab")
			(hide yes)
			(effects
				(font
					(size 1.27 1.27)
					(thickness 0.15)
				)
			)
		)
		(property "Author" "Antmicro"
			(at 0 0 0)
			(layer "B.Fab")
			(hide yes)
			(effects
				(font
					(size 1 1)
					(thickness 0.15)
				)
				(justify mirror)
			)
		)
		(property "Current" "1A"
			(at 0 0 0)
			(layer "B.Fab")
			(hide yes)
			(effects
				(font
					(size 1 1)
					(thickness 0.15)
				)
				(justify mirror)
			)
		)
		(property "License" "Apache-2.0"
			(at 0 0 0)
			(layer "B.Fab")
			(hide yes)
			(effects
				(font
					(size 1 1)
					(thickness 0.15)
				)
				(justify mirror)
			)
		)
		(property "MPN" "ERJ2GE0R00X"
			(at 0 0 0)
			(layer "B.Fab")
			(hide yes)
			(effects
				(font
					(size 1 1)
					(thickness 0.15)
				)
				(justify mirror)
			)
		)
		(property "Manufacturer" "Panasonic"
			(at 0 0 0)
			(layer "B.Fab")
			(hide yes)
			(effects
				(font
					(size 1 1)
					(thickness 0.15)
				)
				(justify mirror)
			)
		)
		(property "Tolerance" "~"
			(at 0 0 0)
			(layer "B.Fab")
			(hide yes)
			(effects
				(font
					(size 1 1)
					(thickness 0.15)
				)
				(justify mirror)
			)
		)
		(property "Val" "0R"
			(at 0 0 0)
			(layer "B.Fab")
			(hide yes)
			(effects
				(font
					(size 1 1)
					(thickness 0.15)
				)
				(justify mirror)
			)
		)
		(sheetname "/Edge connector/")
		(sheetfile "edge-connector.kicad_sch")
		(attr smd)
		(fp_rect
			(start -0.925 0.47)
			(end 0.925 -0.47)
			(stroke
				(width 0.05)
				(type default)
			)
			(fill no)
			(layer "B.CrtYd")
		)
		(fp_rect
			(start -0.5 0.25)
			(end 0.5 -0.25)
			(stroke
				(width 0.15)
				(type solid)
			)
			(fill no)
			(layer "B.Fab")
		)
		(pad "1" smd roundrect
			(at -0.48 0)
			(size 0.59 0.64)
			(layers "B.Cu" "B.Mask" "B.Paste")
			(roundrect_rratio 0.25)
			(net 586 "HPM_STBY_RDY_R")
			(pintype "passive")
		)
		(pad "2" smd roundrect
			(at 0.48 0)
			(size 0.59 0.64)
			(layers "B.Cu" "B.Mask" "B.Paste")
			(roundrect_rratio 0.25)
			(net 257 "/Edge connector/HPM_STBY_RDY")
			(pintype "passive")
		)
	)
	(footprint "antmicro-footprints:R_0402_1005Metric"
		(layer "B.Cu")
		(at 117.54 154.665)
		(descr "Resistor SMD 0402")
		(tags "resistor SMD 0402")
		(property "Reference" "R101"
			(at 0.805 0.425 0)
			(layer "B.SilkS")
			(effects
				(font
					(size 0.7 0.7)
					(thickness 0.15)
				)
				(justify right bottom mirror)
			)
		)
		(property "Value" "R_0R_0402"
			(at 0 -1.4 0)
			(layer "B.Fab")
			(effects
				(font
					(size 0.7 0.7)
					(thickness 0.15)
				)
				(justify right bottom mirror)
			)
		)
		(property "Datasheet" "https://industrial.panasonic.com/cdbs/www-data/pdf/RDA0000/AOA0000C301.pdf"
			(at 0 0 0)
			(layer "F.Fab")
			(hide yes)
			(effects
				(font
					(size 1.27 1.27)
					(thickness 0.15)
				)
			)
		)
		(property "Description" "SMD Chip Resistor, Jumper, 0 ohm, 100 mW, 0402 [1005 Metric], Thick Film, General Purpose"
			(at 0 0 0)
			(layer "F.Fab")
			(hide yes)
			(effects
				(font
					(size 1.27 1.27)
					(thickness 0.15)
				)
			)
		)
		(property "Author" "Antmicro"
			(at 0 0 0)
			(layer "B.Fab")
			(hide yes)
			(effects
				(font
					(size 1 1)
					(thickness 0.15)
				)
				(justify mirror)
			)
		)
		(property "Current" "1A"
			(at 0 0 0)
			(layer "B.Fab")
			(hide yes)
			(effects
				(font
					(size 1 1)
					(thickness 0.15)
				)
				(justify mirror)
			)
		)
		(property "License" "Apache-2.0"
			(at 0 0 0)
			(layer "B.Fab")
			(hide yes)
			(effects
				(font
					(size 1 1)
					(thickness 0.15)
				)
				(justify mirror)
			)
		)
		(property "MPN" "ERJ2GE0R00X"
			(at 0 0 0)
			(layer "B.Fab")
			(hide yes)
			(effects
				(font
					(size 1 1)
					(thickness 0.15)
				)
				(justify mirror)
			)
		)
		(property "Manufacturer" "Panasonic"
			(at 0 0 0)
			(layer "B.Fab")
			(hide yes)
			(effects
				(font
					(size 1 1)
					(thickness 0.15)
				)
				(justify mirror)
			)
		)
		(property "Tolerance" "~"
			(at 0 0 0)
			(layer "B.Fab")
			(hide yes)
			(effects
				(font
					(size 1 1)
					(thickness 0.15)
				)
				(justify mirror)
			)
		)
		(property "Val" "0R"
			(at 0 0 0)
			(layer "B.Fab")
			(hide yes)
			(effects
				(font
					(size 1 1)
					(thickness 0.15)
				)
				(justify mirror)
			)
		)
		(sheetname "/Edge connector/")
		(sheetfile "edge-connector.kicad_sch")
		(attr smd)
		(fp_rect
			(start -0.925 0.47)
			(end 0.925 -0.47)
			(stroke
				(width 0.05)
				(type default)
			)
			(fill no)
			(layer "B.CrtYd")
		)
		(fp_rect
			(start -0.5 0.25)
			(end 0.5 -0.25)
			(stroke
				(width 0.15)
				(type solid)
			)
			(fill no)
			(layer "B.Fab")
		)
		(pad "1" smd roundrect
			(at -0.48 0)
			(size 0.59 0.64)
			(layers "B.Cu" "B.Mask" "B.Paste")
			(roundrect_rratio 0.25)
			(net 387 "HPM_FW_RECOVERY_R")
			(pintype "passive")
		)
		(pad "2" smd roundrect
			(at 0.48 0)
			(size 0.59 0.64)
			(layers "B.Cu" "B.Mask" "B.Paste")
			(roundrect_rratio 0.25)
			(net 258 "/Edge connector/HPM_FW_RECOVERY")
			(pintype "passive")
		)
	)
	(footprint "antmicro-footprints:R_0402_1005Metric"
		(layer "B.Cu")
		(at 117.545 150.675)
		(descr "Resistor SMD 0402")
		(tags "resistor SMD 0402")
		(property "Reference" "R103"
			(at 0.805 0.425 0)
			(layer "B.SilkS")
			(effects
				(font
					(size 0.7 0.7)
					(thickness 0.15)
				)
				(justify right bottom mirror)
			)
		)
		(property "Value" "R_0R_0402"
			(at 0 -1.4 0)
			(layer "B.Fab")
			(effects
				(font
					(size 0.7 0.7)
					(thickness 0.15)
				)
				(justify right bottom mirror)
			)
		)
		(property "Datasheet" "https://industrial.panasonic.com/cdbs/www-data/pdf/RDA0000/AOA0000C301.pdf"
			(at 0 0 0)
			(layer "F.Fab")
			(hide yes)
			(effects
				(font
					(size 1.27 1.27)
					(thickness 0.15)
				)
			)
		)
		(property "Description" "SMD Chip Resistor, Jumper, 0 ohm, 100 mW, 0402 [1005 Metric], Thick Film, General Purpose"
			(at 0 0 0)
			(layer "F.Fab")
			(hide yes)
			(effects
				(font
					(size 1.27 1.27)
					(thickness 0.15)
				)
			)
		)
		(property "Author" "Antmicro"
			(at 0 0 0)
			(layer "B.Fab")
			(hide yes)
			(effects
				(font
					(size 1 1)
					(thickness 0.15)
				)
				(justify mirror)
			)
		)
		(property "Current" "1A"
			(at 0 0 0)
			(layer "B.Fab")
			(hide yes)
			(effects
				(font
					(size 1 1)
					(thickness 0.15)
				)
				(justify mirror)
			)
		)
		(property "License" "Apache-2.0"
			(at 0 0 0)
			(layer "B.Fab")
			(hide yes)
			(effects
				(font
					(size 1 1)
					(thickness 0.15)
				)
				(justify mirror)
			)
		)
		(property "MPN" "ERJ2GE0R00X"
			(at 0 0 0)
			(layer "B.Fab")
			(hide yes)
			(effects
				(font
					(size 1 1)
					(thickness 0.15)
				)
				(justify mirror)
			)
		)
		(property "Manufacturer" "Panasonic"
			(at 0 0 0)
			(layer "B.Fab")
			(hide yes)
			(effects
				(font
					(size 1 1)
					(thickness 0.15)
				)
				(justify mirror)
			)
		)
		(property "Tolerance" "~"
			(at 0 0 0)
			(layer "B.Fab")
			(hide yes)
			(effects
				(font
					(size 1 1)
					(thickness 0.15)
				)
				(justify mirror)
			)
		)
		(property "Val" "0R"
			(at 0 0 0)
			(layer "B.Fab")
			(hide yes)
			(effects
				(font
					(size 1 1)
					(thickness 0.15)
				)
				(justify mirror)
			)
		)
		(sheetname "/Edge connector/")
		(sheetfile "edge-connector.kicad_sch")
		(attr smd)
		(fp_rect
			(start -0.925 0.47)
			(end 0.925 -0.47)
			(stroke
				(width 0.05)
				(type default)
			)
			(fill no)
			(layer "B.CrtYd")
		)
		(fp_rect
			(start -0.5 0.25)
			(end 0.5 -0.25)
			(stroke
				(width 0.15)
				(type solid)
			)
			(fill no)
			(layer "B.Fab")
		)
		(pad "1" smd roundrect
			(at -0.48 0)
			(size 0.59 0.64)
			(layers "B.Cu" "B.Mask" "B.Paste")
			(roundrect_rratio 0.25)
			(net 389 "SYS_PWRBTN_N_R")
			(pintype "passive")
		)
		(pad "2" smd roundrect
			(at 0.48 0)
			(size 0.59 0.64)
			(layers "B.Cu" "B.Mask" "B.Paste")
			(roundrect_rratio 0.25)
			(net 254 "/Edge connector/SYS_PWRBTN_N")
			(pintype "passive")
		)
	)
	(footprint "antmicro-footprints:R_0402_1005Metric"
		(layer "B.Cu")
		(at 117.545 151.675)
		(descr "Resistor SMD 0402")
		(tags "resistor SMD 0402")
		(property "Reference" "R102"
			(at 0.805 0.425 0)
			(layer "B.SilkS")
			(effects
				(font
					(size 0.7 0.7)
					(thickness 0.15)
				)
				(justify right bottom mirror)
			)
		)
		(property "Value" "R_0R_0402"
			(at 0 -1.4 0)
			(layer "B.Fab")
			(effects
				(font
					(size 0.7 0.7)
					(thickness 0.15)
				)
				(justify right bottom mirror)
			)
		)
		(property "Datasheet" "https://industrial.panasonic.com/cdbs/www-data/pdf/RDA0000/AOA0000C301.pdf"
			(at 0 0 0)
			(layer "F.Fab")
			(hide yes)
			(effects
				(font
					(size 1.27 1.27)
					(thickness 0.15)
				)
			)
		)
		(property "Description" "SMD Chip Resistor, Jumper, 0 ohm, 100 mW, 0402 [1005 Metric], Thick Film, General Purpose"
			(at 0 0 0)
			(layer "F.Fab")
			(hide yes)
			(effects
				(font
					(size 1.27 1.27)
					(thickness 0.15)
				)
			)
		)
		(property "Author" "Antmicro"
			(at 0 0 0)
			(layer "B.Fab")
			(hide yes)
			(effects
				(font
					(size 1 1)
					(thickness 0.15)
				)
				(justify mirror)
			)
		)
		(property "Current" "1A"
			(at 0 0 0)
			(layer "B.Fab")
			(hide yes)
			(effects
				(font
					(size 1 1)
					(thickness 0.15)
				)
				(justify mirror)
			)
		)
		(property "License" "Apache-2.0"
			(at 0 0 0)
			(layer "B.Fab")
			(hide yes)
			(effects
				(font
					(size 1 1)
					(thickness 0.15)
				)
				(justify mirror)
			)
		)
		(property "MPN" "ERJ2GE0R00X"
			(at 0 0 0)
			(layer "B.Fab")
			(hide yes)
			(effects
				(font
					(size 1 1)
					(thickness 0.15)
				)
				(justify mirror)
			)
		)
		(property "Manufacturer" "Panasonic"
			(at 0 0 0)
			(layer "B.Fab")
			(hide yes)
			(effects
				(font
					(size 1 1)
					(thickness 0.15)
				)
				(justify mirror)
			)
		)
		(property "Tolerance" "~"
			(at 0 0 0)
			(layer "B.Fab")
			(hide yes)
			(effects
				(font
					(size 1 1)
					(thickness 0.15)
				)
				(justify mirror)
			)
		)
		(property "Val" "0R"
			(at 0 0 0)
			(layer "B.Fab")
			(hide yes)
			(effects
				(font
					(size 1 1)
					(thickness 0.15)
				)
				(justify mirror)
			)
		)
		(sheetname "/Edge connector/")
		(sheetfile "edge-connector.kicad_sch")
		(attr smd)
		(fp_rect
			(start -0.925 0.47)
			(end 0.925 -0.47)
			(stroke
				(width 0.05)
				(type default)
			)
			(fill no)
			(layer "B.CrtYd")
		)
		(fp_rect
			(start -0.5 0.25)
			(end 0.5 -0.25)
			(stroke
				(width 0.15)
				(type solid)
			)
			(fill no)
			(layer "B.Fab")
		)
		(pad "1" smd roundrect
			(at -0.48 0)
			(size 0.59 0.64)
			(layers "B.Cu" "B.Mask" "B.Paste")
			(roundrect_rratio 0.25)
			(net 388 "HPM_STBY_RST_N_R")
			(pintype "passive")
		)
		(pad "2" smd roundrect
			(at 0.48 0)
			(size 0.59 0.64)
			(layers "B.Cu" "B.Mask" "B.Paste")
			(roundrect_rratio 0.25)
			(net 255 "/Edge connector/HPM_STBY_RST_N")
			(pintype "passive")
		)
	)
	(footprint "antmicro-footprints:R_0402_1005Metric"
		(layer "B.Cu")
		(at 117.495 142.675 180)
		(descr "Resistor SMD 0402")
		(tags "resistor SMD 0402")
		(property "Reference" "R111"
			(at -0.805 -0.425 0)
			(layer "B.SilkS")
			(effects
				(font
					(size 0.7 0.7)
					(thickness 0.15)
				)
				(justify right bottom mirror)
			)
		)
		(property "Value" "R_0R_0402"
			(at 0 -1.4 0)
			(layer "B.Fab")
			(effects
				(font
					(size 0.7 0.7)
					(thickness 0.15)
				)
				(justify left bottom mirror)
			)
		)
		(property "Datasheet" "https://industrial.panasonic.com/cdbs/www-data/pdf/RDA0000/AOA0000C301.pdf"
			(at 0 0 180)
			(layer "F.Fab")
			(hide yes)
			(effects
				(font
					(size 1.27 1.27)
					(thickness 0.15)
				)
			)
		)
		(property "Description" "SMD Chip Resistor, Jumper, 0 ohm, 100 mW, 0402 [1005 Metric], Thick Film, General Purpose"
			(at 0 0 180)
			(layer "F.Fab")
			(hide yes)
			(effects
				(font
					(size 1.27 1.27)
					(thickness 0.15)
				)
			)
		)
		(property "Author" "Antmicro"
			(at 234.99 285.35 0)
			(layer "B.Fab")
			(hide yes)
			(effects
				(font
					(size 1 1)
					(thickness 0.15)
				)
				(justify mirror)
			)
		)
		(property "Current" "1A"
			(at 234.99 285.35 0)
			(layer "B.Fab")
			(hide yes)
			(effects
				(font
					(size 1 1)
					(thickness 0.15)
				)
				(justify mirror)
			)
		)
		(property "License" "Apache-2.0"
			(at 234.99 285.35 0)
			(layer "B.Fab")
			(hide yes)
			(effects
				(font
					(size 1 1)
					(thickness 0.15)
				)
				(justify mirror)
			)
		)
		(property "MPN" "ERJ2GE0R00X"
			(at 234.99 285.35 0)
			(layer "B.Fab")
			(hide yes)
			(effects
				(font
					(size 1 1)
					(thickness 0.15)
				)
				(justify mirror)
			)
		)
		(property "Manufacturer" "Panasonic"
			(at 234.99 285.35 0)
			(layer "B.Fab")
			(hide yes)
			(effects
				(font
					(size 1 1)
					(thickness 0.15)
				)
				(justify mirror)
			)
		)
		(property "Tolerance" "~"
			(at 234.99 285.35 0)
			(layer "B.Fab")
			(hide yes)
			(effects
				(font
					(size 1 1)
					(thickness 0.15)
				)
				(justify mirror)
			)
		)
		(property "Val" "0R"
			(at 234.99 285.35 0)
			(layer "B.Fab")
			(hide yes)
			(effects
				(font
					(size 1 1)
					(thickness 0.15)
				)
				(justify mirror)
			)
		)
		(sheetname "/Edge connector/")
		(sheetfile "edge-connector.kicad_sch")
		(attr smd)
		(fp_rect
			(start -0.925 0.47)
			(end 0.925 -0.47)
			(stroke
				(width 0.05)
				(type default)
			)
			(fill no)
			(layer "B.CrtYd")
		)
		(fp_rect
			(start -0.5 0.25)
			(end 0.5 -0.25)
			(stroke
				(width 0.15)
				(type solid)
			)
			(fill no)
			(layer "B.Fab")
		)
		(pad "1" smd roundrect
			(at -0.48 0 180)
			(size 0.59 0.64)
			(layers "B.Cu" "B.Mask" "B.Paste")
			(roundrect_rratio 0.25)
			(net 246 "/Edge connector/SPARE0")
			(pintype "passive")
		)
		(pad "2" smd roundrect
			(at 0.48 0 180)
			(size 0.59 0.64)
			(layers "B.Cu" "B.Mask" "B.Paste")
			(roundrect_rratio 0.25)
			(net 397 "SPARE0_R")
			(pintype "passive")
		)
	)
	(footprint "antmicro-footprints:R_0402_1005Metric"
		(layer "B.Cu")
		(at 117.495 144.675)
		(descr "Resistor SMD 0402")
		(tags "resistor SMD 0402")
		(property "Reference" "R109"
			(at 0.805 0.425 0)
			(layer "B.SilkS")
			(effects
				(font
					(size 0.7 0.7)
					(thickness 0.15)
				)
				(justify right bottom mirror)
			)
		)
		(property "Value" "R_0R_0402"
			(at 0 -1.4 0)
			(layer "B.Fab")
			(effects
				(font
					(size 0.7 0.7)
					(thickness 0.15)
				)
				(justify right bottom mirror)
			)
		)
		(property "Datasheet" "https://industrial.panasonic.com/cdbs/www-data/pdf/RDA0000/AOA0000C301.pdf"
			(at 0 0 0)
			(layer "F.Fab")
			(hide yes)
			(effects
				(font
					(size 1.27 1.27)
					(thickness 0.15)
				)
			)
		)
		(property "Description" "SMD Chip Resistor, Jumper, 0 ohm, 100 mW, 0402 [1005 Metric], Thick Film, General Purpose"
			(at 0 0 0)
			(layer "F.Fab")
			(hide yes)
			(effects
				(font
					(size 1.27 1.27)
					(thickness 0.15)
				)
			)
		)
		(property "Author" "Antmicro"
			(at 0 0 0)
			(layer "B.Fab")
			(hide yes)
			(effects
				(font
					(size 1 1)
					(thickness 0.15)
				)
				(justify mirror)
			)
		)
		(property "Current" "1A"
			(at 0 0 0)
			(layer "B.Fab")
			(hide yes)
			(effects
				(font
					(size 1 1)
					(thickness 0.15)
				)
				(justify mirror)
			)
		)
		(property "License" "Apache-2.0"
			(at 0 0 0)
			(layer "B.Fab")
			(hide yes)
			(effects
				(font
					(size 1 1)
					(thickness 0.15)
				)
				(justify mirror)
			)
		)
		(property "MPN" "ERJ2GE0R00X"
			(at 0 0 0)
			(layer "B.Fab")
			(hide yes)
			(effects
				(font
					(size 1 1)
					(thickness 0.15)
				)
				(justify mirror)
			)
		)
		(property "Manufacturer" "Panasonic"
			(at 0 0 0)
			(layer "B.Fab")
			(hide yes)
			(effects
				(font
					(size 1 1)
					(thickness 0.15)
				)
				(justify mirror)
			)
		)
		(property "Tolerance" "~"
			(at 0 0 0)
			(layer "B.Fab")
			(hide yes)
			(effects
				(font
					(size 1 1)
					(thickness 0.15)
				)
				(justify mirror)
			)
		)
		(property "Val" "0R"
			(at 0 0 0)
			(layer "B.Fab")
			(hide yes)
			(effects
				(font
					(size 1 1)
					(thickness 0.15)
				)
				(justify mirror)
			)
		)
		(sheetname "/Edge connector/")
		(sheetfile "edge-connector.kicad_sch")
		(attr smd)
		(fp_rect
			(start -0.925 0.47)
			(end 0.925 -0.47)
			(stroke
				(width 0.05)
				(type default)
			)
			(fill no)
			(layer "B.CrtYd")
		)
		(fp_rect
			(start -0.5 0.25)
			(end 0.5 -0.25)
			(stroke
				(width 0.15)
				(type solid)
			)
			(fill no)
			(layer "B.Fab")
		)
		(pad "1" smd roundrect
			(at -0.48 0)
			(size 0.59 0.64)
			(layers "B.Cu" "B.Mask" "B.Paste")
			(roundrect_rratio 0.25)
			(net 395 "RoT_CPU_RST_N_R")
			(pintype "passive")
		)
		(pad "2" smd roundrect
			(at 0.48 0)
			(size 0.59 0.64)
			(layers "B.Cu" "B.Mask" "B.Paste")
			(roundrect_rratio 0.25)
			(net 250 "/Edge connector/RoT_CPU_RST_N")
			(pintype "passive")
		)
	)
	(footprint "antmicro-footprints:R_0402_1005Metric"
		(layer "B.Cu")
		(at 117.495 147.675)
		(descr "Resistor SMD 0402")
		(tags "resistor SMD 0402")
		(property "Reference" "R106"
			(at 0.805 0.425 0)
			(layer "B.SilkS")
			(effects
				(font
					(size 0.7 0.7)
					(thickness 0.15)
				)
				(justify right bottom mirror)
			)
		)
		(property "Value" "R_0R_0402"
			(at 0 -1.4 0)
			(layer "B.Fab")
			(effects
				(font
					(size 0.7 0.7)
					(thickness 0.15)
				)
				(justify right bottom mirror)
			)
		)
		(property "Datasheet" "https://industrial.panasonic.com/cdbs/www-data/pdf/RDA0000/AOA0000C301.pdf"
			(at 0 0 0)
			(layer "F.Fab")
			(hide yes)
			(effects
				(font
					(size 1.27 1.27)
					(thickness 0.15)
				)
			)
		)
		(property "Description" "SMD Chip Resistor, Jumper, 0 ohm, 100 mW, 0402 [1005 Metric], Thick Film, General Purpose"
			(at 0 0 0)
			(layer "F.Fab")
			(hide yes)
			(effects
				(font
					(size 1.27 1.27)
					(thickness 0.15)
				)
			)
		)
		(property "Author" "Antmicro"
			(at 0 0 0)
			(layer "B.Fab")
			(hide yes)
			(effects
				(font
					(size 1 1)
					(thickness 0.15)
				)
				(justify mirror)
			)
		)
		(property "Current" "1A"
			(at 0 0 0)
			(layer "B.Fab")
			(hide yes)
			(effects
				(font
					(size 1 1)
					(thickness 0.15)
				)
				(justify mirror)
			)
		)
		(property "License" "Apache-2.0"
			(at 0 0 0)
			(layer "B.Fab")
			(hide yes)
			(effects
				(font
					(size 1 1)
					(thickness 0.15)
				)
				(justify mirror)
			)
		)
		(property "MPN" "ERJ2GE0R00X"
			(at 0 0 0)
			(layer "B.Fab")
			(hide yes)
			(effects
				(font
					(size 1 1)
					(thickness 0.15)
				)
				(justify mirror)
			)
		)
		(property "Manufacturer" "Panasonic"
			(at 0 0 0)
			(layer "B.Fab")
			(hide yes)
			(effects
				(font
					(size 1 1)
					(thickness 0.15)
				)
				(justify mirror)
			)
		)
		(property "Tolerance" "~"
			(at 0 0 0)
			(layer "B.Fab")
			(hide yes)
			(effects
				(font
					(size 1 1)
					(thickness 0.15)
				)
				(justify mirror)
			)
		)
		(property "Val" "0R"
			(at 0 0 0)
			(layer "B.Fab")
			(hide yes)
			(effects
				(font
					(size 1 1)
					(thickness 0.15)
				)
				(justify mirror)
			)
		)
		(sheetname "/Edge connector/")
		(sheetfile "edge-connector.kicad_sch")
		(attr smd)
		(fp_rect
			(start -0.925 0.47)
			(end 0.925 -0.47)
			(stroke
				(width 0.05)
				(type default)
			)
			(fill no)
			(layer "B.CrtYd")
		)
		(fp_rect
			(start -0.5 0.25)
			(end 0.5 -0.25)
			(stroke
				(width 0.15)
				(type solid)
			)
			(fill no)
			(layer "B.Fab")
		)
		(pad "1" smd roundrect
			(at -0.48 0)
			(size 0.59 0.64)
			(layers "B.Cu" "B.Mask" "B.Paste")
			(roundrect_rratio 0.25)
			(net 392 "DBP_PRDY_N_R")
			(pintype "passive")
		)
		(pad "2" smd roundrect
			(at 0.48 0)
			(size 0.59 0.64)
			(layers "B.Cu" "B.Mask" "B.Paste")
			(roundrect_rratio 0.25)
			(net 251 "/Edge connector/DBP_PRDY_N")
			(pintype "passive")
		)
	)
	(footprint "antmicro-footprints:R_0402_1005Metric"
		(layer "B.Cu")
		(at 117.495 145.675 180)
		(descr "Resistor SMD 0402")
		(tags "resistor SMD 0402")
		(property "Reference" "R108"
			(at -0.805 -0.425 0)
			(layer "B.SilkS")
			(effects
				(font
					(size 0.7 0.7)
					(thickness 0.15)
				)
				(justify right bottom mirror)
			)
		)
		(property "Value" "R_0R_0402"
			(at 0 -1.4 0)
			(layer "B.Fab")
			(effects
				(font
					(size 0.7 0.7)
					(thickness 0.15)
				)
				(justify left bottom mirror)
			)
		)
		(property "Datasheet" "https://industrial.panasonic.com/cdbs/www-data/pdf/RDA0000/AOA0000C301.pdf"
			(at 0 0 180)
			(layer "F.Fab")
			(hide yes)
			(effects
				(font
					(size 1.27 1.27)
					(thickness 0.15)
				)
			)
		)
		(property "Description" "SMD Chip Resistor, Jumper, 0 ohm, 100 mW, 0402 [1005 Metric], Thick Film, General Purpose"
			(at 0 0 180)
			(layer "F.Fab")
			(hide yes)
			(effects
				(font
					(size 1.27 1.27)
					(thickness 0.15)
				)
			)
		)
		(property "Author" "Antmicro"
			(at 234.99 291.35 0)
			(layer "B.Fab")
			(hide yes)
			(effects
				(font
					(size 1 1)
					(thickness 0.15)
				)
				(justify mirror)
			)
		)
		(property "Current" "1A"
			(at 234.99 291.35 0)
			(layer "B.Fab")
			(hide yes)
			(effects
				(font
					(size 1 1)
					(thickness 0.15)
				)
				(justify mirror)
			)
		)
		(property "License" "Apache-2.0"
			(at 234.99 291.35 0)
			(layer "B.Fab")
			(hide yes)
			(effects
				(font
					(size 1 1)
					(thickness 0.15)
				)
				(justify mirror)
			)
		)
		(property "MPN" "ERJ2GE0R00X"
			(at 234.99 291.35 0)
			(layer "B.Fab")
			(hide yes)
			(effects
				(font
					(size 1 1)
					(thickness 0.15)
				)
				(justify mirror)
			)
		)
		(property "Manufacturer" "Panasonic"
			(at 234.99 291.35 0)
			(layer "B.Fab")
			(hide yes)
			(effects
				(font
					(size 1 1)
					(thickness 0.15)
				)
				(justify mirror)
			)
		)
		(property "Tolerance" "~"
			(at 234.99 291.35 0)
			(layer "B.Fab")
			(hide yes)
			(effects
				(font
					(size 1 1)
					(thickness 0.15)
				)
				(justify mirror)
			)
		)
		(property "Val" "0R"
			(at 234.99 291.35 0)
			(layer "B.Fab")
			(hide yes)
			(effects
				(font
					(size 1 1)
					(thickness 0.15)
				)
				(justify mirror)
			)
		)
		(sheetname "/Edge connector/")
		(sheetfile "edge-connector.kicad_sch")
		(attr smd)
		(fp_rect
			(start -0.925 0.47)
			(end 0.925 -0.47)
			(stroke
				(width 0.05)
				(type default)
			)
			(fill no)
			(layer "B.CrtYd")
		)
		(fp_rect
			(start -0.5 0.25)
			(end 0.5 -0.25)
			(stroke
				(width 0.15)
				(type solid)
			)
			(fill no)
			(layer "B.Fab")
		)
		(pad "1" smd roundrect
			(at -0.48 0 180)
			(size 0.59 0.64)
			(layers "B.Cu" "B.Mask" "B.Paste")
			(roundrect_rratio 0.25)
			(net 249 "/Edge connector/SPARE1")
			(pintype "passive")
		)
		(pad "2" smd roundrect
			(at 0.48 0 180)
			(size 0.59 0.64)
			(layers "B.Cu" "B.Mask" "B.Paste")
			(roundrect_rratio 0.25)
			(net 394 "SPARE1_R")
			(pintype "passive")
		)
	)
	(footprint "antmicro-footprints:R_0402_1005Metric"
		(layer "B.Cu")
		(at 117.495 146.675)
		(descr "Resistor SMD 0402")
		(tags "resistor SMD 0402")
		(property "Reference" "R107"
			(at 0.805 0.425 0)
			(layer "B.SilkS")
			(effects
				(font
					(size 0.7 0.7)
					(thickness 0.15)
				)
				(justify right bottom mirror)
			)
		)
		(property "Value" "R_0R_0402"
			(at 0 -1.4 0)
			(layer "B.Fab")
			(effects
				(font
					(size 0.7 0.7)
					(thickness 0.15)
				)
				(justify right bottom mirror)
			)
		)
		(property "Datasheet" "https://industrial.panasonic.com/cdbs/www-data/pdf/RDA0000/AOA0000C301.pdf"
			(at 0 0 0)
			(layer "F.Fab")
			(hide yes)
			(effects
				(font
					(size 1.27 1.27)
					(thickness 0.15)
				)
			)
		)
		(property "Description" "SMD Chip Resistor, Jumper, 0 ohm, 100 mW, 0402 [1005 Metric], Thick Film, General Purpose"
			(at 0 0 0)
			(layer "F.Fab")
			(hide yes)
			(effects
				(font
					(size 1.27 1.27)
					(thickness 0.15)
				)
			)
		)
		(property "Author" "Antmicro"
			(at 0 0 0)
			(layer "B.Fab")
			(hide yes)
			(effects
				(font
					(size 1 1)
					(thickness 0.15)
				)
				(justify mirror)
			)
		)
		(property "Current" "1A"
			(at 0 0 0)
			(layer "B.Fab")
			(hide yes)
			(effects
				(font
					(size 1 1)
					(thickness 0.15)
				)
				(justify mirror)
			)
		)
		(property "License" "Apache-2.0"
			(at 0 0 0)
			(layer "B.Fab")
			(hide yes)
			(effects
				(font
					(size 1 1)
					(thickness 0.15)
				)
				(justify mirror)
			)
		)
		(property "MPN" "ERJ2GE0R00X"
			(at 0 0 0)
			(layer "B.Fab")
			(hide yes)
			(effects
				(font
					(size 1 1)
					(thickness 0.15)
				)
				(justify mirror)
			)
		)
		(property "Manufacturer" "Panasonic"
			(at 0 0 0)
			(layer "B.Fab")
			(hide yes)
			(effects
				(font
					(size 1 1)
					(thickness 0.15)
				)
				(justify mirror)
			)
		)
		(property "Tolerance" "~"
			(at 0 0 0)
			(layer "B.Fab")
			(hide yes)
			(effects
				(font
					(size 1 1)
					(thickness 0.15)
				)
				(justify mirror)
			)
		)
		(property "Val" "0R"
			(at 0 0 0)
			(layer "B.Fab")
			(hide yes)
			(effects
				(font
					(size 1 1)
					(thickness 0.15)
				)
				(justify mirror)
			)
		)
		(sheetname "/Edge connector/")
		(sheetfile "edge-connector.kicad_sch")
		(attr smd)
		(fp_rect
			(start -0.925 0.47)
			(end 0.925 -0.47)
			(stroke
				(width 0.05)
				(type default)
			)
			(fill no)
			(layer "B.CrtYd")
		)
		(fp_rect
			(start -0.5 0.25)
			(end 0.5 -0.25)
			(stroke
				(width 0.15)
				(type solid)
			)
			(fill no)
			(layer "B.Fab")
		)
		(pad "1" smd roundrect
			(at -0.48 0)
			(size 0.59 0.64)
			(layers "B.Cu" "B.Mask" "B.Paste")
			(roundrect_rratio 0.25)
			(net 393 "RST_PLTRST_BUF_N_R")
			(pintype "passive")
		)
		(pad "2" smd roundrect
			(at 0.48 0)
			(size 0.59 0.64)
			(layers "B.Cu" "B.Mask" "B.Paste")
			(roundrect_rratio 0.25)
			(net 248 "/Edge connector/RST_PLTRST_BUF_N")
			(pintype "passive")
		)
	)
	(footprint "antmicro-footprints:R_0402_1005Metric"
		(layer "B.Cu")
		(at 117.495 141.675)
		(descr "Resistor SMD 0402")
		(tags "resistor SMD 0402")
		(property "Reference" "R112"
			(at 0.805 0.425 0)
			(layer "B.SilkS")
			(effects
				(font
					(size 0.7 0.7)
					(thickness 0.15)
				)
				(justify right bottom mirror)
			)
		)
		(property "Value" "R_0R_0402"
			(at 0 -1.4 0)
			(layer "B.Fab")
			(effects
				(font
					(size 0.7 0.7)
					(thickness 0.15)
				)
				(justify right bottom mirror)
			)
		)
		(property "Datasheet" "https://industrial.panasonic.com/cdbs/www-data/pdf/RDA0000/AOA0000C301.pdf"
			(at 0 0 0)
			(layer "F.Fab")
			(hide yes)
			(effects
				(font
					(size 1.27 1.27)
					(thickness 0.15)
				)
			)
		)
		(property "Description" "SMD Chip Resistor, Jumper, 0 ohm, 100 mW, 0402 [1005 Metric], Thick Film, General Purpose"
			(at 0 0 0)
			(layer "F.Fab")
			(hide yes)
			(effects
				(font
					(size 1.27 1.27)
					(thickness 0.15)
				)
			)
		)
		(property "Author" "Antmicro"
			(at 0 0 0)
			(layer "B.Fab")
			(hide yes)
			(effects
				(font
					(size 1 1)
					(thickness 0.15)
				)
				(justify mirror)
			)
		)
		(property "Current" "1A"
			(at 0 0 0)
			(layer "B.Fab")
			(hide yes)
			(effects
				(font
					(size 1 1)
					(thickness 0.15)
				)
				(justify mirror)
			)
		)
		(property "License" "Apache-2.0"
			(at 0 0 0)
			(layer "B.Fab")
			(hide yes)
			(effects
				(font
					(size 1 1)
					(thickness 0.15)
				)
				(justify mirror)
			)
		)
		(property "MPN" "ERJ2GE0R00X"
			(at 0 0 0)
			(layer "B.Fab")
			(hide yes)
			(effects
				(font
					(size 1 1)
					(thickness 0.15)
				)
				(justify mirror)
			)
		)
		(property "Manufacturer" "Panasonic"
			(at 0 0 0)
			(layer "B.Fab")
			(hide yes)
			(effects
				(font
					(size 1 1)
					(thickness 0.15)
				)
				(justify mirror)
			)
		)
		(property "Tolerance" "~"
			(at 0 0 0)
			(layer "B.Fab")
			(hide yes)
			(effects
				(font
					(size 1 1)
					(thickness 0.15)
				)
				(justify mirror)
			)
		)
		(property "Val" "0R"
			(at 0 0 0)
			(layer "B.Fab")
			(hide yes)
			(effects
				(font
					(size 1 1)
					(thickness 0.15)
				)
				(justify mirror)
			)
		)
		(sheetname "/Edge connector/")
		(sheetfile "edge-connector.kicad_sch")
		(attr smd)
		(fp_rect
			(start -0.925 0.47)
			(end 0.925 -0.47)
			(stroke
				(width 0.05)
				(type default)
			)
			(fill no)
			(layer "B.CrtYd")
		)
		(fp_rect
			(start -0.5 0.25)
			(end 0.5 -0.25)
			(stroke
				(width 0.15)
				(type solid)
			)
			(fill no)
			(layer "B.Fab")
		)
		(pad "1" smd roundrect
			(at -0.48 0)
			(size 0.59 0.64)
			(layers "B.Cu" "B.Mask" "B.Paste")
			(roundrect_rratio 0.25)
			(net 398 "IRQ_N_R")
			(pintype "passive")
		)
		(pad "2" smd roundrect
			(at 0.48 0)
			(size 0.59 0.64)
			(layers "B.Cu" "B.Mask" "B.Paste")
			(roundrect_rratio 0.25)
			(net 245 "/Edge connector/IRQ_N")
			(pintype "passive")
		)
	)
	(footprint "antmicro-footprints:R_0402_1005Metric"
		(layer "B.Cu")
		(at 117.495 143.675 180)
		(descr "Resistor SMD 0402")
		(tags "resistor SMD 0402")
		(property "Reference" "R110"
			(at -0.805 -0.425 0)
			(layer "B.SilkS")
			(effects
				(font
					(size 0.7 0.7)
					(thickness 0.15)
				)
				(justify right bottom mirror)
			)
		)
		(property "Value" "R_0R_0402"
			(at 0 -1.4 0)
			(layer "B.Fab")
			(effects
				(font
					(size 0.7 0.7)
					(thickness 0.15)
				)
				(justify left bottom mirror)
			)
		)
		(property "Datasheet" "https://industrial.panasonic.com/cdbs/www-data/pdf/RDA0000/AOA0000C301.pdf"
			(at 0 0 180)
			(layer "F.Fab")
			(hide yes)
			(effects
				(font
					(size 1.27 1.27)
					(thickness 0.15)
				)
			)
		)
		(property "Description" "SMD Chip Resistor, Jumper, 0 ohm, 100 mW, 0402 [1005 Metric], Thick Film, General Purpose"
			(at 0 0 180)
			(layer "F.Fab")
			(hide yes)
			(effects
				(font
					(size 1.27 1.27)
					(thickness 0.15)
				)
			)
		)
		(property "Author" "Antmicro"
			(at 234.99 287.35 0)
			(layer "B.Fab")
			(hide yes)
			(effects
				(font
					(size 1 1)
					(thickness 0.15)
				)
				(justify mirror)
			)
		)
		(property "Current" "1A"
			(at 234.99 287.35 0)
			(layer "B.Fab")
			(hide yes)
			(effects
				(font
					(size 1 1)
					(thickness 0.15)
				)
				(justify mirror)
			)
		)
		(property "License" "Apache-2.0"
			(at 234.99 287.35 0)
			(layer "B.Fab")
			(hide yes)
			(effects
				(font
					(size 1 1)
					(thickness 0.15)
				)
				(justify mirror)
			)
		)
		(property "MPN" "ERJ2GE0R00X"
			(at 234.99 287.35 0)
			(layer "B.Fab")
			(hide yes)
			(effects
				(font
					(size 1 1)
					(thickness 0.15)
				)
				(justify mirror)
			)
		)
		(property "Manufacturer" "Panasonic"
			(at 234.99 287.35 0)
			(layer "B.Fab")
			(hide yes)
			(effects
				(font
					(size 1 1)
					(thickness 0.15)
				)
				(justify mirror)
			)
		)
		(property "Tolerance" "~"
			(at 234.99 287.35 0)
			(layer "B.Fab")
			(hide yes)
			(effects
				(font
					(size 1 1)
					(thickness 0.15)
				)
				(justify mirror)
			)
		)
		(property "Val" "0R"
			(at 234.99 287.35 0)
			(layer "B.Fab")
			(hide yes)
			(effects
				(font
					(size 1 1)
					(thickness 0.15)
				)
				(justify mirror)
			)
		)
		(sheetname "/Edge connector/")
		(sheetfile "edge-connector.kicad_sch")
		(attr smd)
		(fp_rect
			(start -0.925 0.47)
			(end 0.925 -0.47)
			(stroke
				(width 0.05)
				(type default)
			)
			(fill no)
			(layer "B.CrtYd")
		)
		(fp_rect
			(start -0.5 0.25)
			(end 0.5 -0.25)
			(stroke
				(width 0.15)
				(type solid)
			)
			(fill no)
			(layer "B.Fab")
		)
		(pad "1" smd roundrect
			(at -0.48 0 180)
			(size 0.59 0.64)
			(layers "B.Cu" "B.Mask" "B.Paste")
			(roundrect_rratio 0.25)
			(net 247 "/Edge connector/CHASI#")
			(pintype "passive")
		)
		(pad "2" smd roundrect
			(at 0.48 0 180)
			(size 0.59 0.64)
			(layers "B.Cu" "B.Mask" "B.Paste")
			(roundrect_rratio 0.25)
			(net 396 "CHASI#_R")
			(pintype "passive")
		)
	)
	(footprint "antmicro-footprints:R_0402_1005Metric"
		(layer "B.Cu")
		(at 117.495 148.675)
		(descr "Resistor SMD 0402")
		(tags "resistor SMD 0402")
		(property "Reference" "R105"
			(at 0.805 0.425 0)
			(layer "B.SilkS")
			(effects
				(font
					(size 0.7 0.7)
					(thickness 0.15)
				)
				(justify right bottom mirror)
			)
		)
		(property "Value" "R_0R_0402"
			(at 0 -1.4 0)
			(layer "B.Fab")
			(effects
				(font
					(size 0.7 0.7)
					(thickness 0.15)
				)
				(justify right bottom mirror)
			)
		)
		(property "Datasheet" "https://industrial.panasonic.com/cdbs/www-data/pdf/RDA0000/AOA0000C301.pdf"
			(at 0 0 0)
			(layer "F.Fab")
			(hide yes)
			(effects
				(font
					(size 1.27 1.27)
					(thickness 0.15)
				)
			)
		)
		(property "Description" "SMD Chip Resistor, Jumper, 0 ohm, 100 mW, 0402 [1005 Metric], Thick Film, General Purpose"
			(at 0 0 0)
			(layer "F.Fab")
			(hide yes)
			(effects
				(font
					(size 1.27 1.27)
					(thickness 0.15)
				)
			)
		)
		(property "Author" "Antmicro"
			(at 0 0 0)
			(layer "B.Fab")
			(hide yes)
			(effects
				(font
					(size 1 1)
					(thickness 0.15)
				)
				(justify mirror)
			)
		)
		(property "Current" "1A"
			(at 0 0 0)
			(layer "B.Fab")
			(hide yes)
			(effects
				(font
					(size 1 1)
					(thickness 0.15)
				)
				(justify mirror)
			)
		)
		(property "License" "Apache-2.0"
			(at 0 0 0)
			(layer "B.Fab")
			(hide yes)
			(effects
				(font
					(size 1 1)
					(thickness 0.15)
				)
				(justify mirror)
			)
		)
		(property "MPN" "ERJ2GE0R00X"
			(at 0 0 0)
			(layer "B.Fab")
			(hide yes)
			(effects
				(font
					(size 1 1)
					(thickness 0.15)
				)
				(justify mirror)
			)
		)
		(property "Manufacturer" "Panasonic"
			(at 0 0 0)
			(layer "B.Fab")
			(hide yes)
			(effects
				(font
					(size 1 1)
					(thickness 0.15)
				)
				(justify mirror)
			)
		)
		(property "Tolerance" "~"
			(at 0 0 0)
			(layer "B.Fab")
			(hide yes)
			(effects
				(font
					(size 1 1)
					(thickness 0.15)
				)
				(justify mirror)
			)
		)
		(property "Val" "0R"
			(at 0 0 0)
			(layer "B.Fab")
			(hide yes)
			(effects
				(font
					(size 1 1)
					(thickness 0.15)
				)
				(justify mirror)
			)
		)
		(sheetname "/Edge connector/")
		(sheetfile "edge-connector.kicad_sch")
		(attr smd)
		(fp_rect
			(start -0.925 0.47)
			(end 0.925 -0.47)
			(stroke
				(width 0.05)
				(type default)
			)
			(fill no)
			(layer "B.CrtYd")
		)
		(fp_rect
			(start -0.5 0.25)
			(end 0.5 -0.25)
			(stroke
				(width 0.15)
				(type solid)
			)
			(fill no)
			(layer "B.Fab")
		)
		(pad "1" smd roundrect
			(at -0.48 0)
			(size 0.59 0.64)
			(layers "B.Cu" "B.Mask" "B.Paste")
			(roundrect_rratio 0.25)
			(net 391 "DBP_PREQ_N_R")
			(pintype "passive")
		)
		(pad "2" smd roundrect
			(at 0.48 0)
			(size 0.59 0.64)
			(layers "B.Cu" "B.Mask" "B.Paste")
			(roundrect_rratio 0.25)
			(net 252 "/Edge connector/DBP_PREQ_N")
			(pintype "passive")
		)
	)
	(footprint "antmicro-footprints:R_0402_1005Metric"
		(layer "B.Cu")
		(at 117.495 149.675)
		(descr "Resistor SMD 0402")
		(tags "resistor SMD 0402")
		(property "Reference" "R104"
			(at 0.805 0.425 0)
			(layer "B.SilkS")
			(effects
				(font
					(size 0.7 0.7)
					(thickness 0.15)
				)
				(justify right bottom mirror)
			)
		)
		(property "Value" "R_0R_0402"
			(at 0 -1.4 0)
			(layer "B.Fab")
			(effects
				(font
					(size 0.7 0.7)
					(thickness 0.15)
				)
				(justify right bottom mirror)
			)
		)
		(property "Datasheet" "https://industrial.panasonic.com/cdbs/www-data/pdf/RDA0000/AOA0000C301.pdf"
			(at 0 0 0)
			(layer "F.Fab")
			(hide yes)
			(effects
				(font
					(size 1.27 1.27)
					(thickness 0.15)
				)
			)
		)
		(property "Description" "SMD Chip Resistor, Jumper, 0 ohm, 100 mW, 0402 [1005 Metric], Thick Film, General Purpose"
			(at 0 0 0)
			(layer "F.Fab")
			(hide yes)
			(effects
				(font
					(size 1.27 1.27)
					(thickness 0.15)
				)
			)
		)
		(property "Author" "Antmicro"
			(at 0 0 0)
			(layer "B.Fab")
			(hide yes)
			(effects
				(font
					(size 1 1)
					(thickness 0.15)
				)
				(justify mirror)
			)
		)
		(property "Current" "1A"
			(at 0 0 0)
			(layer "B.Fab")
			(hide yes)
			(effects
				(font
					(size 1 1)
					(thickness 0.15)
				)
				(justify mirror)
			)
		)
		(property "License" "Apache-2.0"
			(at 0 0 0)
			(layer "B.Fab")
			(hide yes)
			(effects
				(font
					(size 1 1)
					(thickness 0.15)
				)
				(justify mirror)
			)
		)
		(property "MPN" "ERJ2GE0R00X"
			(at 0 0 0)
			(layer "B.Fab")
			(hide yes)
			(effects
				(font
					(size 1 1)
					(thickness 0.15)
				)
				(justify mirror)
			)
		)
		(property "Manufacturer" "Panasonic"
			(at 0 0 0)
			(layer "B.Fab")
			(hide yes)
			(effects
				(font
					(size 1 1)
					(thickness 0.15)
				)
				(justify mirror)
			)
		)
		(property "Tolerance" "~"
			(at 0 0 0)
			(layer "B.Fab")
			(hide yes)
			(effects
				(font
					(size 1 1)
					(thickness 0.15)
				)
				(justify mirror)
			)
		)
		(property "Val" "0R"
			(at 0 0 0)
			(layer "B.Fab")
			(hide yes)
			(effects
				(font
					(size 1 1)
					(thickness 0.15)
				)
				(justify mirror)
			)
		)
		(sheetname "/Edge connector/")
		(sheetfile "edge-connector.kicad_sch")
		(attr smd)
		(fp_rect
			(start -0.925 0.47)
			(end 0.925 -0.47)
			(stroke
				(width 0.05)
				(type default)
			)
			(fill no)
			(layer "B.CrtYd")
		)
		(fp_rect
			(start -0.5 0.25)
			(end 0.5 -0.25)
			(stroke
				(width 0.15)
				(type solid)
			)
			(fill no)
			(layer "B.Fab")
		)
		(pad "1" smd roundrect
			(at -0.48 0)
			(size 0.59 0.64)
			(layers "B.Cu" "B.Mask" "B.Paste")
			(roundrect_rratio 0.25)
			(net 390 "SYS_PWROK_R")
			(pintype "passive")
		)
		(pad "2" smd roundrect
			(at 0.48 0)
			(size 0.59 0.64)
			(layers "B.Cu" "B.Mask" "B.Paste")
			(roundrect_rratio 0.25)
			(net 253 "/Edge connector/SYS_PWROK")
			(pintype "passive")
		)
	)
	(footprint "antmicro-footprints:C_0402_1005Metric"
		(layer "B.Cu")
		(at 133.35 90.8125 180)
		(descr "Capacitor SMD 0402")
		(tags "capacitor SMD 0402")
		(property "Reference" "C135"
			(at 0.75 -0.3875 0)
			(layer "B.SilkS")
			(effects
				(font
					(size 0.7 0.7)
					(thickness 0.15)
				)
				(justify left bottom mirror)
			)
		)
		(property "Value" "C_100n_0402"
			(at 0 -1.4 0)
			(layer "B.Fab")
			(effects
				(font
					(size 0.7 0.7)
					(thickness 0.15)
				)
				(justify left bottom mirror)
			)
		)
		(property "Datasheet" "https://www.murata.com/products/productdetail?partno=GRM155R61H104KE14%23"
			(at 0 0 180)
			(layer "F.Fab")
			(hide yes)
			(effects
				(font
					(size 1.27 1.27)
					(thickness 0.15)
				)
			)
		)
		(property "Description" "SMD Multilayer Ceramic Capacitor, 0.1 µF, 50 V, 0402 [1005 Metric], ± 10%, X5R, GRM Series"
			(at 0 0 180)
			(layer "F.Fab")
			(hide yes)
			(effects
				(font
					(size 1.27 1.27)
					(thickness 0.15)
				)
			)
		)
		(property "Author" "Antmicro"
			(at 266.7 181.625 0)
			(layer "B.Fab")
			(hide yes)
			(effects
				(font
					(size 1 1)
					(thickness 0.15)
				)
				(justify mirror)
			)
		)
		(property "Dielectric" "X5R"
			(at 266.7 181.625 0)
			(layer "B.Fab")
			(hide yes)
			(effects
				(font
					(size 1 1)
					(thickness 0.15)
				)
				(justify mirror)
			)
		)
		(property "License" "Apache-2.0"
			(at 266.7 181.625 0)
			(layer "B.Fab")
			(hide yes)
			(effects
				(font
					(size 1 1)
					(thickness 0.15)
				)
				(justify mirror)
			)
		)
		(property "MPN" "GRM155R61H104KE14D"
			(at 266.7 181.625 0)
			(layer "B.Fab")
			(hide yes)
			(effects
				(font
					(size 1 1)
					(thickness 0.15)
				)
				(justify mirror)
			)
		)
		(property "Manufacturer" "Murata"
			(at 266.7 181.625 0)
			(layer "B.Fab")
			(hide yes)
			(effects
				(font
					(size 1 1)
					(thickness 0.15)
				)
				(justify mirror)
			)
		)
		(property "Val" "100n"
			(at 266.7 181.625 0)
			(layer "B.Fab")
			(hide yes)
			(effects
				(font
					(size 1 1)
					(thickness 0.15)
				)
				(justify mirror)
			)
		)
		(property "Voltage" "50V"
			(at 266.7 181.625 0)
			(layer "B.Fab")
			(hide yes)
			(effects
				(font
					(size 1 1)
					(thickness 0.15)
				)
				(justify mirror)
			)
		)
		(sheetname "/Interfaces/")
		(sheetfile "interfaces.kicad_sch")
		(attr smd)
		(fp_rect
			(start -0.925 0.47)
			(end 0.925 -0.47)
			(stroke
				(width 0.05)
				(type default)
			)
			(fill no)
			(layer "B.CrtYd")
		)
		(fp_line
			(start 0.504 0.25)
			(end 0.504 -0.248)
			(stroke
				(width 0.15)
				(type solid)
			)
			(layer "B.Fab")
		)
		(fp_line
			(start 0.504 -0.248)
			(end -0.494 -0.248)
			(stroke
				(width 0.15)
				(type solid)
			)
			(layer "B.Fab")
		)
		(fp_line
			(start -0.494 0.25)
			(end 0.504 0.25)
			(stroke
				(width 0.15)
				(type solid)
			)
			(layer "B.Fab")
		)
		(fp_line
			(start -0.494 -0.248)
			(end -0.494 0.25)
			(stroke
				(width 0.15)
				(type solid)
			)
			(layer "B.Fab")
		)
		(pad "1" smd roundrect
			(at -0.48 0 180)
			(size 0.59 0.64)
			(layers "B.Cu" "B.Mask" "B.Paste")
			(roundrect_rratio 0.25)
			(net 1 "GND")
			(pintype "passive")
		)
		(pad "2" smd roundrect
			(at 0.48 0 180)
			(size 0.59 0.64)
			(layers "B.Cu" "B.Mask" "B.Paste")
			(roundrect_rratio 0.25)
			(net 597 "1V8_FT")
			(pintype "passive")
		)
	)
	(footprint "antmicro-footprints:C_0402_1005Metric"
		(layer "B.Cu")
		(at 136.85 88.9125 -90)
		(descr "Capacitor SMD 0402")
		(tags "capacitor SMD 0402")
		(property "Reference" "C139"
			(at 0.7875 -0.35 90)
			(layer "B.SilkS")
			(effects
				(font
					(size 0.7 0.7)
					(thickness 0.15)
				)
				(justify left bottom mirror)
			)
		)
		(property "Value" "C_100n_0402"
			(at 0 -1.4 90)
			(layer "B.Fab")
			(effects
				(font
					(size 0.7 0.7)
					(thickness 0.15)
				)
				(justify left bottom mirror)
			)
		)
		(property "Datasheet" "https://www.murata.com/products/productdetail?partno=GRM155R61H104KE14%23"
			(at 0 0 270)
			(layer "F.Fab")
			(hide yes)
			(effects
				(font
					(size 1.27 1.27)
					(thickness 0.15)
				)
			)
		)
		(property "Description" "SMD Multilayer Ceramic Capacitor, 0.1 µF, 50 V, 0402 [1005 Metric], ± 10%, X5R, GRM Series"
			(at 0 0 270)
			(layer "F.Fab")
			(hide yes)
			(effects
				(font
					(size 1.27 1.27)
					(thickness 0.15)
				)
			)
		)
		(property "Author" "Antmicro"
			(at 47.9375 225.7625 0)
			(layer "B.Fab")
			(hide yes)
			(effects
				(font
					(size 1 1)
					(thickness 0.15)
				)
				(justify mirror)
			)
		)
		(property "Dielectric" "X5R"
			(at 47.9375 225.7625 0)
			(layer "B.Fab")
			(hide yes)
			(effects
				(font
					(size 1 1)
					(thickness 0.15)
				)
				(justify mirror)
			)
		)
		(property "License" "Apache-2.0"
			(at 47.9375 225.7625 0)
			(layer "B.Fab")
			(hide yes)
			(effects
				(font
					(size 1 1)
					(thickness 0.15)
				)
				(justify mirror)
			)
		)
		(property "MPN" "GRM155R61H104KE14D"
			(at 47.9375 225.7625 0)
			(layer "B.Fab")
			(hide yes)
			(effects
				(font
					(size 1 1)
					(thickness 0.15)
				)
				(justify mirror)
			)
		)
		(property "Manufacturer" "Murata"
			(at 47.9375 225.7625 0)
			(layer "B.Fab")
			(hide yes)
			(effects
				(font
					(size 1 1)
					(thickness 0.15)
				)
				(justify mirror)
			)
		)
		(property "Val" "100n"
			(at 47.9375 225.7625 0)
			(layer "B.Fab")
			(hide yes)
			(effects
				(font
					(size 1 1)
					(thickness 0.15)
				)
				(justify mirror)
			)
		)
		(property "Voltage" "50V"
			(at 47.9375 225.7625 0)
			(layer "B.Fab")
			(hide yes)
			(effects
				(font
					(size 1 1)
					(thickness 0.15)
				)
				(justify mirror)
			)
		)
		(sheetname "/Interfaces/")
		(sheetfile "interfaces.kicad_sch")
		(attr smd)
		(fp_rect
			(start -0.925 0.47)
			(end 0.925 -0.47)
			(stroke
				(width 0.05)
				(type default)
			)
			(fill no)
			(layer "B.CrtYd")
		)
		(fp_line
			(start -0.494 0.25)
			(end 0.504 0.25)
			(stroke
				(width 0.15)
				(type solid)
			)
			(layer "B.Fab")
		)
		(fp_line
			(start 0.504 0.25)
			(end 0.504 -0.248)
			(stroke
				(width 0.15)
				(type solid)
			)
			(layer "B.Fab")
		)
		(fp_line
			(start -0.494 -0.248)
			(end -0.494 0.25)
			(stroke
				(width 0.15)
				(type solid)
			)
			(layer "B.Fab")
		)
		(fp_line
			(start 0.504 -0.248)
			(end -0.494 -0.248)
			(stroke
				(width 0.15)
				(type solid)
			)
			(layer "B.Fab")
		)
		(pad "1" smd roundrect
			(at -0.48 0 270)
			(size 0.59 0.64)
			(layers "B.Cu" "B.Mask" "B.Paste")
			(roundrect_rratio 0.25)
			(net 1 "GND")
			(pintype "passive")
		)
		(pad "2" smd roundrect
			(at 0.48 0 270)
			(size 0.59 0.64)
			(layers "B.Cu" "B.Mask" "B.Paste")
			(roundrect_rratio 0.25)
			(net 115 "/Interfaces/FT_VPHY")
			(pintype "passive")
		)
	)
	(footprint "antmicro-footprints:C_0402_1005Metric"
		(layer "B.Cu")
		(at 137.85 88.9125 -90)
		(descr "Capacitor SMD 0402")
		(tags "capacitor SMD 0402")
		(property "Reference" "C162"
			(at 0.7875 -0.35 90)
			(layer "B.SilkS")
			(effects
				(font
					(size 0.7 0.7)
					(thickness 0.15)
				)
				(justify left bottom mirror)
			)
		)
		(property "Value" "C_4u7_0402"
			(at 0 -1.4 90)
			(layer "B.Fab")
			(effects
				(font
					(size 0.7 0.7)
					(thickness 0.15)
				)
				(justify left bottom mirror)
			)
		)
		(property "Datasheet" "https://www.murata.com/products/productdetail?partno=GRM155R61A475MEAA%23"
			(at 0 0 270)
			(layer "F.Fab")
			(hide yes)
			(effects
				(font
					(size 1.27 1.27)
					(thickness 0.15)
				)
			)
		)
		(property "Description" "SMD Multilayer Ceramic Capacitor, 4.7 µF, 10 V, 0402 [1005 Metric], ± 20%, X5R, GRM Series"
			(at 0 0 270)
			(layer "F.Fab")
			(hide yes)
			(effects
				(font
					(size 1.27 1.27)
					(thickness 0.15)
				)
			)
		)
		(property "Author" "Antmicro"
			(at 48.9375 226.7625 0)
			(layer "B.Fab")
			(hide yes)
			(effects
				(font
					(size 1 1)
					(thickness 0.15)
				)
				(justify mirror)
			)
		)
		(property "Dielectric" ""
			(at 48.9375 226.7625 0)
			(layer "B.Fab")
			(hide yes)
			(effects
				(font
					(size 1 1)
					(thickness 0.15)
				)
				(justify mirror)
			)
		)
		(property "License" "Apache-2.0"
			(at 48.9375 226.7625 0)
			(layer "B.Fab")
			(hide yes)
			(effects
				(font
					(size 1 1)
					(thickness 0.15)
				)
				(justify mirror)
			)
		)
		(property "MPN" "GRM155R61A475MEAAD"
			(at 48.9375 226.7625 0)
			(layer "B.Fab")
			(hide yes)
			(effects
				(font
					(size 1 1)
					(thickness 0.15)
				)
				(justify mirror)
			)
		)
		(property "Manufacturer" "Murata"
			(at 48.9375 226.7625 0)
			(layer "B.Fab")
			(hide yes)
			(effects
				(font
					(size 1 1)
					(thickness 0.15)
				)
				(justify mirror)
			)
		)
		(property "Val" "4u7"
			(at 48.9375 226.7625 0)
			(layer "B.Fab")
			(hide yes)
			(effects
				(font
					(size 1 1)
					(thickness 0.15)
				)
				(justify mirror)
			)
		)
		(property "Voltage" ""
			(at 48.9375 226.7625 0)
			(layer "B.Fab")
			(hide yes)
			(effects
				(font
					(size 1 1)
					(thickness 0.15)
				)
				(justify mirror)
			)
		)
		(sheetname "/Interfaces/")
		(sheetfile "interfaces.kicad_sch")
		(attr smd)
		(fp_rect
			(start -0.925 0.47)
			(end 0.925 -0.47)
			(stroke
				(width 0.05)
				(type default)
			)
			(fill no)
			(layer "B.CrtYd")
		)
		(fp_line
			(start -0.494 0.25)
			(end 0.504 0.25)
			(stroke
				(width 0.15)
				(type solid)
			)
			(layer "B.Fab")
		)
		(fp_line
			(start 0.504 0.25)
			(end 0.504 -0.248)
			(stroke
				(width 0.15)
				(type solid)
			)
			(layer "B.Fab")
		)
		(fp_line
			(start -0.494 -0.248)
			(end -0.494 0.25)
			(stroke
				(width 0.15)
				(type solid)
			)
			(layer "B.Fab")
		)
		(fp_line
			(start 0.504 -0.248)
			(end -0.494 -0.248)
			(stroke
				(width 0.15)
				(type solid)
			)
			(layer "B.Fab")
		)
		(pad "1" smd roundrect
			(at -0.48 0 270)
			(size 0.59 0.64)
			(layers "B.Cu" "B.Mask" "B.Paste")
			(roundrect_rratio 0.25)
			(net 1 "GND")
			(pintype "passive")
		)
		(pad "2" smd roundrect
			(at 0.48 0 270)
			(size 0.59 0.64)
			(layers "B.Cu" "B.Mask" "B.Paste")
			(roundrect_rratio 0.25)
			(net 115 "/Interfaces/FT_VPHY")
			(pintype "passive")
		)
	)
	(footprint "antmicro-footprints:FB_0402_1005Metric"
		(layer "B.Cu")
		(at 139.35 89.4125 180)
		(descr "Ferrite Bead SMD 0402")
		(tags "ferrite bead SMD 0402")
		(property "Reference" "FB2"
			(at -1.05 0.5125 0)
			(layer "B.SilkS")
			(effects
				(font
					(size 0.7 0.7)
					(thickness 0.15)
				)
				(justify left bottom mirror)
			)
		)
		(property "Value" "FB_600Z_0.3A_Murata-BLM15AG_0402"
			(at 0 -1.4 0)
			(layer "B.Fab")
			(effects
				(font
					(size 0.7 0.7)
					(thickness 0.15)
				)
				(justify left bottom mirror)
			)
		)
		(property "Datasheet" "https://www.murata.com/en-us/products/productdata/8796740059166/ENFA0018.pdf"
			(at 0 0 180)
			(layer "F.Fab")
			(hide yes)
			(effects
				(font
					(size 1.27 1.27)
					(thickness 0.15)
				)
			)
		)
		(property "Description" "Ferrite Bead, 0402 [1005 Metric], 600 ohm, 300 mA, BLM15AG_SN, 0.6 ohm, ± 25%, General use"
			(at 0 0 180)
			(layer "F.Fab")
			(hide yes)
			(effects
				(font
					(size 1.27 1.27)
					(thickness 0.15)
				)
			)
		)
		(property "Author" "Antmicro"
			(at 278.7 178.825 0)
			(layer "B.Fab")
			(hide yes)
			(effects
				(font
					(size 1 1)
					(thickness 0.15)
				)
				(justify mirror)
			)
		)
		(property "Current" ""
			(at 278.7 178.825 0)
			(layer "B.Fab")
			(hide yes)
			(effects
				(font
					(size 1 1)
					(thickness 0.15)
				)
				(justify mirror)
			)
		)
		(property "License" "Apache-2.0"
			(at 278.7 178.825 0)
			(layer "B.Fab")
			(hide yes)
			(effects
				(font
					(size 1 1)
					(thickness 0.15)
				)
				(justify mirror)
			)
		)
		(property "MPN" "BLM15AG601SN1D"
			(at 278.7 178.825 0)
			(layer "B.Fab")
			(hide yes)
			(effects
				(font
					(size 1 1)
					(thickness 0.15)
				)
				(justify mirror)
			)
		)
		(property "Manufacturer" "Murata"
			(at 278.7 178.825 0)
			(layer "B.Fab")
			(hide yes)
			(effects
				(font
					(size 1 1)
					(thickness 0.15)
				)
				(justify mirror)
			)
		)
		(property "Val" "600Z/0.3A"
			(at 278.7 178.825 0)
			(layer "B.Fab")
			(hide yes)
			(effects
				(font
					(size 1 1)
					(thickness 0.15)
				)
				(justify mirror)
			)
		)
		(sheetname "/Interfaces/")
		(sheetfile "interfaces.kicad_sch")
		(attr smd)
		(fp_rect
			(start -0.925 0.47)
			(end 0.925 -0.47)
			(stroke
				(width 0.05)
				(type default)
			)
			(fill no)
			(layer "B.CrtYd")
		)
		(fp_rect
			(start -0.5 0.25)
			(end 0.5 -0.25)
			(stroke
				(width 0.15)
				(type solid)
			)
			(fill no)
			(layer "B.Fab")
		)
		(pad "1" smd roundrect
			(at -0.48 0 180)
			(size 0.59 0.64)
			(layers "B.Cu" "B.Mask" "B.Paste")
			(roundrect_rratio 0.25)
			(net 2 "VCC3V3")
			(pintype "passive")
		)
		(pad "2" smd roundrect
			(at 0.48 0 180)
			(size 0.59 0.64)
			(layers "B.Cu" "B.Mask" "B.Paste")
			(roundrect_rratio 0.25)
			(net 115 "/Interfaces/FT_VPHY")
			(pintype "passive")
		)
	)
	(gr_line
		(start 150.1 177.3)
		(end 150.1 58.9)
		(stroke
			(width 0.12)
			(type solid)
		)
		(layer "Edge.Cuts")
	)
	(gr_line
		(start 150.1 58.9)
		(end 113.385 58.895)
		(stroke
			(width 0.12)
			(type solid)
		)
		(layer "Edge.Cuts")
	)
	(gr_line
		(start 73.4 178.5)
		(end 73.41 173.285)
		(stroke
			(width 0.12)
			(type solid)
		)
		(layer "Edge.Cuts")
	)
	(gr_line
		(start 136.9 178.5)
		(end 136.889901 173.285)
		(stroke
			(width 0.12)
			(type solid)
		)
		(layer "Edge.Cuts")
	)
	(gr_arc
		(start 136.889901 173.285)
		(mid 137.036377 172.931377)
		(end 137.39 172.784901)
		(stroke
			(width 0.12)
			(type solid)
		)
		(layer "Edge.Cuts")
	)
	(gr_line
		(start 136.9 178.5)
		(end 136.1 179.3)
		(stroke
			(width 0.12)
			(type solid)
		)
		(layer "Edge.Cuts")
	)
	(gr_line
		(start 136.1 179.3)
		(end 119.3 179.3)
		(stroke
			(width 0.12)
			(type solid)
		)
		(layer "Edge.Cuts")
	)
	(gr_line
		(start 119.3 179.3)
		(end 118.5 178.5)
		(stroke
			(width 0.12)
			(type solid)
		)
		(layer "Edge.Cuts")
	)
	(gr_line
		(start 118.5 178.5)
		(end 118.530008 173.490245)
		(stroke
			(width 0.12)
			(type solid)
		)
		(layer "Edge.Cuts")
	)
	(gr_line
		(start 115.779502 173.490245)
		(end 115.8 178.5)
		(stroke
			(width 0.12)
			(type solid)
		)
		(layer "Edge.Cuts")
	)
	(gr_line
		(start 115.8 178.5)
		(end 115 179.3)
		(stroke
			(width 0.12)
			(type solid)
		)
		(layer "Edge.Cuts")
	)
	(gr_line
		(start 115 179.3)
		(end 106.6 179.3)
		(stroke
			(width 0.12)
			(type solid)
		)
		(layer "Edge.Cuts")
	)
	(gr_line
		(start 106.6 179.3)
		(end 105.8 178.5)
		(stroke
			(width 0.12)
			(type solid)
		)
		(layer "Edge.Cuts")
	)
	(gr_line
		(start 105.8 178.5)
		(end 105.82 173.045)
		(stroke
			(width 0.12)
			(type solid)
		)
		(layer "Edge.Cuts")
	)
	(gr_line
		(start 140.2 179.3)
		(end 149 179.3)
		(stroke
			(width 0.12)
			(type solid)
		)
		(layer "Edge.Cuts")
	)
	(gr_line
		(start 149 179.3)
		(end 150.1 177.3)
		(stroke
			(width 0.12)
			(type solid)
		)
		(layer "Edge.Cuts")
	)
	(gr_line
		(start 82.6 179.3)
		(end 74.2 179.3)
		(stroke
			(width 0.12)
			(type solid)
		)
		(layer "Edge.Cuts")
	)
	(gr_line
		(start 74.2 179.3)
		(end 73.4 178.5)
		(stroke
			(width 0.12)
			(type solid)
		)
		(layer "Edge.Cuts")
	)
	(gr_line
		(start 60.1 177.3)
		(end 60.1 58.9)
		(stroke
			(width 0.12)
			(type solid)
		)
		(layer "Edge.Cuts")
	)
	(gr_line
		(start 83.4 178.5)
		(end 82.6 179.3)
		(stroke
			(width 0.12)
			(type solid)
		)
		(layer "Edge.Cuts")
	)
	(gr_line
		(start 83.365 173.245)
		(end 83.4 178.5)
		(stroke
			(width 0.12)
			(type solid)
		)
		(layer "Edge.Cuts")
	)
	(gr_line
		(start 139.4 178.5)
		(end 139.389901 173.285)
		(stroke
			(width 0.12)
			(type solid)
		)
		(layer "Edge.Cuts")
	)
	(gr_line
		(start 60.1 177.3)
		(end 61.3 179.3)
		(stroke
			(width 0.12)
			(type solid)
		)
		(layer "Edge.Cuts")
	)
	(gr_line
		(start 140.2 179.3)
		(end 139.4 178.5)
		(stroke
			(width 0.12)
			(type solid)
		)
		(layer "Edge.Cuts")
	)
	(gr_line
		(start 70.2 179.3)
		(end 61.3 179.3)
		(stroke
			(width 0.12)
			(type solid)
		)
		(layer "Edge.Cuts")
	)
	(gr_line
		(start 70.9 178.5)
		(end 70.2 179.3)
		(stroke
			(width 0.12)
			(type solid)
		)
		(layer "Edge.Cuts")
	)
	(gr_line
		(start 138.889802 172.784901)
		(end 137.39 172.784901)
		(stroke
			(width 0.12)
			(type solid)
		)
		(layer "Edge.Cuts")
	)
	(gr_line
		(start 86.4 179.3)
		(end 85.6 178.5)
		(stroke
			(width 0.12)
			(type solid)
		)
		(layer "Edge.Cuts")
	)
	(gr_arc
		(start 103.97 173.045)
		(mid 104.895 172.12)
		(end 105.82 173.045)
		(stroke
			(width 0.12)
			(type solid)
		)
		(layer "Edge.Cuts")
	)
	(gr_line
		(start 103.97 173.045)
		(end 104 178.5)
		(stroke
			(width 0.12)
			(type solid)
		)
		(layer "Edge.Cuts")
	)
	(gr_line
		(start 103.2 179.3)
		(end 86.4 179.3)
		(stroke
			(width 0.12)
			(type solid)
		)
		(layer "Edge.Cuts")
	)
	(gr_line
		(start 70.9092 173.2858)
		(end 70.9 178.5)
		(stroke
			(width 0.12)
			(type solid)
		)
		(layer "Edge.Cuts")
	)
	(gr_line
		(start 85.6 178.5)
		(end 85.615 173.245)
		(stroke
			(width 0.12)
			(type solid)
		)
		(layer "Edge.Cuts")
	)
	(gr_arc
		(start 83.365 173.245)
		(mid 84.49 172.12)
		(end 85.615 173.245)
		(stroke
			(width 0.12)
			(type solid)
		)
		(layer "Edge.Cuts")
	)
	(gr_line
		(start 104 178.5)
		(end 103.2 179.3)
		(stroke
			(width 0.12)
			(type solid)
		)
		(layer "Edge.Cuts")
	)
	(gr_arc
		(start 115.779502 173.490245)
		(mid 117.154755 172.114992)
		(end 118.530008 173.490245)
		(stroke
			(width 0.12)
			(type solid)
		)
		(layer "Edge.Cuts")
	)
	(gr_arc
		(start 138.889802 172.784901)
		(mid 139.243425 172.931377)
		(end 139.389901 173.285)
		(stroke
			(width 0.12)
			(type solid)
		)
		(layer "Edge.Cuts")
	)
	(gr_line
		(start 72.909901 172.784901)
		(end 71.409299 172.785701)
		(stroke
			(width 0.12)
			(type solid)
		)
		(layer "Edge.Cuts")
	)
	(gr_arc
		(start 70.9092 173.2858)
		(mid 71.055676 172.932177)
		(end 71.409299 172.785701)
		(stroke
			(width 0.12)
			(type solid)
		)
		(layer "Edge.Cuts")
	)
	(gr_arc
		(start 72.909901 172.784901)
		(mid 73.263524 172.931377)
		(end 73.41 173.285)
		(stroke
			(width 0.12)
			(type solid)
		)
		(layer "Edge.Cuts")
	)
	(gr_line
		(start 95.965 58.895)
		(end 60.1 58.9)
		(stroke
			(width 0.12)
			(type solid)
		)
		(layer "Edge.Cuts")
	)
	(gr_line
		(start 62.39 169.43)
		(end 67.385 169.43)
		(stroke
			(width 0.12)
			(type solid)
		)
		(layer "Edge.Cuts")
	)
	(gr_line
		(start 67.39 176.43)
		(end 62.39 176.43)
		(stroke
			(width 0.12)
			(type solid)
		)
		(layer "Edge.Cuts")
	)
	(gr_line
		(start 62.39 176.43)
		(end 62.39 169.43)
		(stroke
			(width 0.12)
			(type solid)
		)
		(layer "Edge.Cuts")
	)
	(gr_line
		(start 67.385 169.43)
		(end 67.39 176.43)
		(stroke
			(width 0.12)
			(type solid)
		)
		(layer "Edge.Cuts")
	)
	(gr_arc
		(start 113.387 61.6)
		(mid 113.124838 62.350505)
		(end 112.4 62.677)
		(stroke
			(width 0.12)
			(type solid)
		)
		(layer "Edge.Cuts")
	)
	(gr_line
		(start 109.755 62.677)
		(end 109.755 78.7)
		(stroke
			(width 0.12)
			(type solid)
		)
		(layer "Edge.Cuts")
	)
	(gr_line
		(start 99.595 78.7)
		(end 109.755 78.7)
		(stroke
			(width 0.12)
			(type solid)
		)
		(layer "Edge.Cuts")
	)
	(gr_line
		(start 113.385 58.895)
		(end 113.387 61.6)
		(stroke
			(width 0.12)
			(type solid)
		)
		(layer "Edge.Cuts")
	)
	(gr_arc
		(start 97.043 62.673)
		(mid 96.292504 62.410827)
		(end 95.966 61.686)
		(stroke
			(width 0.12)
			(type solid)
		)
		(layer "Edge.Cuts")
	)
	(gr_line
		(start 99.595 62.677)
		(end 99.595 78.7)
		(stroke
			(width 0.12)
			(type solid)
		)
		(layer "Edge.Cuts")
	)
	(gr_line
		(start 95.966 61.686)
		(end 95.965 58.895)
		(stroke
			(width 0.12)
			(type solid)
		)
		(layer "Edge.Cuts")
	)
	(gr_line
		(start 109.755 62.677)
		(end 112.4 62.677)
		(stroke
			(width 0.12)
			(type solid)
		)
		(layer "Edge.Cuts")
	)
	(gr_line
		(start 99.595 62.677)
		(end 97.043 62.673)
		(stroke
			(width 0.12)
			(type solid)
		)
		(layer "Edge.Cuts")
	)
	(gr_text "Artix DC-SCM \nRev. ${REVISION}"
		(at 88.025 146.68 90)
		(layer "F.Cu")
		(effects
			(font
				(size 1 1)
				(thickness 0.2)
			)
			(justify left)
		)
	)
	(segment
		(start 133.25 164.75)
		(end 133.25 166.05)
		(width 0.2)
		(layer "F.Cu")
		(net 1)
	)
	(segment
		(start 99.775 124.175)
		(end 100.275 124.675)
		(width 0.15)
		(layer "F.Cu")
		(net 1)
	)
	(segment
		(start 110.775 129.175)
		(end 111.275 129.675)
		(width 0.15)
		(layer "F.Cu")
		(net 1)
	)
	(segment
		(start 94.775 111.175)
		(end 94.275 110.675)
		(width 0.15)
		(layer "F.Cu")
		(net 1)
	)
	(segment
		(start 100.775 129.175)
		(end 101.275 129.675)
		(width 0.15)
		(layer "F.Cu")
		(net 1)
	)
	(segment
		(start 107.775 130.175)
		(end 108.275 130.675)
		(width 0.15)
		(layer "F.Cu")
		(net 1)
	)
	(segment
		(start 96.775 125.175)
		(end 96.275 125.675)
		(width 0.15)
		(layer "F.Cu")
		(net 1)
	)
	(segment
		(start 93.775 127.175)
		(end 93.275 126.675)
		(width 0.15)
		(layer "F.Cu")
		(net 1)
	)
	(segment
		(start 96.775 124.175)
		(end 97.275 124.675)
		(width 0.15)
		(layer "F.Cu")
		(net 1)
	)
	(segment
		(start 95.775 126.175)
		(end 95.275 126.675)
		(width 0.15)
		(layer "F.Cu")
		(net 1)
	)
	(segment
		(start 102.775 125.175)
		(end 103.275 125.675)
		(width 0.15)
		(layer "F.Cu")
		(net 1)
	)
	(segment
		(start 92.975 148.775)
		(end 92.975 148.175)
		(width 0.1)
		(layer "F.Cu")
		(net 1)
	)
	(segment
		(start 135.79 177.345)
		(end 135.79 175.87)
		(width 0.2)
		(layer "F.Cu")
		(net 1)
	)
	(segment
		(start 103.375 139.575)
		(end 103.375 138.775)
		(width 0.1)
		(layer "F.Cu")
		(net 1)
	)
	(segment
		(start 104.175 150.375)
		(end 104.175 151.07399)
		(width 0.1)
		(layer "F.Cu")
		(net 1)
	)
	(segment
		(start 105.074 155.16)
		(end 105.074 155.875)
		(width 0.15)
		(layer "F.Cu")
		(net 1)
	)
	(segment
		(start 97.775 130.175)
		(end 97.775 130.775)
		(width 0.15)
		(layer "F.Cu")
		(net 1)
	)
	(segment
		(start 99.775 120.175)
		(end 100.275 120.675)
		(width 0.15)
		(layer "F.Cu")
		(net 1)
	)
	(segment
		(start 101.775 120.175)
		(end 102.275 120.675)
		(width 0.15)
		(layer "F.Cu")
		(net 1)
	)
	(segment
		(start 97.775 122.175)
		(end 98.275 122.675)
		(width 0.15)
		(layer "F.Cu")
		(net 1)
	)
	(segment
		(start 100.775 121.175)
		(end 100.275 121.675)
		(width 0.15)
		(layer "F.Cu")
		(net 1)
	)
	(segment
		(start 104.175 143.975)
		(end 104.175 142.875)
		(width 0.1)
		(layer "F.Cu")
		(net 1)
	)
	(segment
		(start 100.975 143.975)
		(end 100.975 142.875)
		(width 0.1)
		(layer "F.Cu")
		(net 1)
	)
	(segment
		(start 96.775 126.175)
		(end 96.275 126.675)
		(width 0.15)
		(layer "F.Cu")
		(net 1)
	)
	(segment
		(start 96.975 144.775)
		(end 96.575 144.375)
		(width 0.1)
		(layer "F.Cu")
		(net 1)
	)
	(segment
		(start 96.575 144.375)
		(end 96.575 143.375)
		(width 0.1)
		(layer "F.Cu")
		(net 1)
	)
	(segment
		(start 92.975 143.975)
		(end 92.975 142.875)
		(width 0.1)
		(layer "F.Cu")
		(net 1)
	)
	(segment
		(start 104.775 111.175)
		(end 104.275 110.675)
		(width 0.15)
		(layer "F.Cu")
		(net 1)
	)
	(segment
		(start 109.775 126.175)
		(end 110.275 126.675)
		(width 0.15)
		(layer "F.Cu")
		(net 1)
	)
	(segment
		(start 101.69 177.295)
		(end 101.69 175.695)
		(width 0.2)
		(layer "F.Cu")
		(net 1)
	)
	(segment
		(start 92.175 143.975)
		(end 92.175 142.875)
		(width 0.1)
		(layer "F.Cu")
		(net 1)
	)
	(segment
		(start 96.265 177.17)
		(end 96.265 175.27)
		(width 0.2)
		(layer "F.Cu")
		(net 1)
	)
	(segment
		(start 103.775 128.175)
		(end 104.275 128.675)
		(width 0.15)
		(layer "F.Cu")
		(net 1)
	)
	(segment
		(start 105.76 162.075)
		(end 106.375 162.075)
		(width 0.15)
		(layer "F.Cu")
		(net 1)
	)
	(segment
		(start 92.115 177.07)
		(end 92.115 175.47)
		(width 0.2)
		(layer "F.Cu")
		(net 1)
	)
	(segment
		(start 100.775 109.175)
		(end 100.275 108.675)
		(width 0.15)
		(layer "F.Cu")
		(net 1)
	)
	(segment
		(start 101.775 112.175)
		(end 102.275 112.675)
		(width 0.15)
		(layer "F.Cu")
		(net 1)
	)
	(segment
		(start 110.775 109.175)
		(end 110.275 109.675)
		(width 0.15)
		(layer "F.Cu")
		(net 1)
	)
	(segment
		(start 107.785 110.195)
		(end 107.285 109.695)
		(width 0.15)
		(layer "F.Cu")
		(net 1)
	)
	(segment
		(start 127.61 112.625)
		(end 128.525 112.625)
		(width 0.15)
		(layer "F.Cu")
		(net 1)
	)
	(segment
		(start 108.775 123.175)
		(end 109.275 123.675)
		(width 0.15)
		(layer "F.Cu")
		(net 1)
	)
	(segment
		(start 112.29 177.345)
		(end 112.29 175.445)
		(width 0.2)
		(layer "F.Cu")
		(net 1)
	)
	(segment
		(start 98.775 113.175)
		(end 98.275 112.675)
		(width 0.15)
		(layer "F.Cu")
		(net 1)
	)
	(segment
		(start 142.274 127.004)
		(end 141.784 126.514)
		(width 0.15)
		(layer "F.Cu")
		(net 1)
	)
	(segment
		(start 94.775 124.175)
		(end 95.275 123.675)
		(width 0.15)
		(layer "F.Cu")
		(net 1)
	)
	(segment
		(start 106.775 117.175)
		(end 106.275 117.675)
		(width 0.15)
		(layer "F.Cu")
		(net 1)
	)
	(segment
		(start 103.775 118.175)
		(end 104.275 117.675)
		(width 0.15)
		(layer "F.Cu")
		(net 1)
	)
	(segment
		(start 135.274 120.014)
		(end 134.774 119.514)
		(width 0.2)
		(layer "F.Cu")
		(net 1)
	)
	(segment
		(start 104.775 121.175)
		(end 104.275 121.675)
		(width 0.15)
		(layer "F.Cu")
		(net 1)
	)
	(segment
		(start 97.775 120.175)
		(end 98.275 120.675)
		(width 0.15)
		(layer "F.Cu")
		(net 1)
	)
	(segment
		(start 98.775 119.175)
		(end 99.275 119.675)
		(width 0.15)
		(layer "F.Cu")
		(net 1)
	)
	(segment
		(start 96.775 117.175)
		(end 97.275 117.675)
		(width 0.15)
		(layer "F.Cu")
		(net 1)
	)
	(segment
		(start 105.775 124.175)
		(end 105.275 124.675)
		(width 0.15)
		(layer "F.Cu")
		(net 1)
	)
	(segment
		(start 76.29 177.345)
		(end 76.29 175.745)
		(width 0.15)
		(layer "F.Cu")
		(net 1)
	)
	(segment
		(start 95.775 114.175)
		(end 96.275 113.675)
		(width 0.15)
		(layer "F.Cu")
		(net 1)
	)
	(segment
		(start 92.775 115.175)
		(end 93.275 114.675)
		(width 0.15)
		(layer "F.Cu")
		(net 1)
	)
	(segment
		(start 77.715 64.515)
		(end 79.715 64.515)
		(width 0.5)
		(layer "F.Cu")
		(net 1)
	)
	(segment
		(start 91.775 112.175)
		(end 91.275 111.675)
		(width 0.15)
		(layer "F.Cu")
		(net 1)
	)
	(segment
		(start 140.625 106.575)
		(end 140.625 105.685)
		(width 0.2)
		(layer "F.Cu")
		(net 1)
	)
	(segment
		(start 101.775 121.175)
		(end 101.275 121.675)
		(width 0.15)
		(layer "F.Cu")
		(net 1)
	)
	(segment
		(start 122.45 61.65)
		(end 122.45 60.355)
		(width 0.2)
		(layer "F.Cu")
		(net 1)
	)
	(segment
		(start 103.775 120.175)
		(end 104.275 120.675)
		(width 0.15)
		(layer "F.Cu")
		(net 1)
	)
	(segment
		(start 120.3 77.005)
		(end 121.325 77.005)
		(width 0.2)
		(layer "F.Cu")
		(net 1)
	)
	(segment
		(start 104.775 123.175)
		(end 104.275 123.675)
		(width 0.15)
		(layer "F.Cu")
		(net 1)
	)
	(segment
		(start 136.35 90.8875)
		(end 136.35 91.6125)
		(width 0.1)
		(layer "F.Cu")
		(net 1)
	)
	(segment
		(start 102.075 159.775)
		(end 102.075 158.375)
		(width 0.2)
		(layer "F.Cu")
		(net 1)
	)
	(segment
		(start 69.648 97.542)
		(end 68.739 97.542)
		(width 0.15)
		(layer "F.Cu")
		(net 1)
	)
	(segment
		(start 109.29 177.345)
		(end 109.29 175.891)
		(width 0.2)
		(layer "F.Cu")
		(net 1)
	)
	(segment
		(start 124.99 175.92)
		(end 125.01 175.9)
		(width 0.2)
		(layer "F.Cu")
		(net 1)
	)
	(segment
		(start 83.34 166.815)
		(end 83.74 166.815)
		(width 0.2)
		(layer "F.Cu")
		(net 1)
	)
	(segment
		(start 94.575 144.775)
		(end 94.166294 144.366294)
		(width 0.1)
		(layer "F.Cu")
		(net 1)
	)
	(segment
		(start 130.05 61.65)
		(end 130.05 60.355)
		(width 0.2)
		(layer "F.Cu")
		(net 1)
	)
	(segment
		(start 92.174 155.16)
		(end 92.174 155.875)
		(width 0.15)
		(layer "F.Cu")
		(net 1)
	)
	(segment
		(start 123.15 64.2)
		(end 121.655 64.2)
		(width 0.2)
		(layer "F.Cu")
		(net 1)
	)
	(segment
		(start 90.775 126.175)
		(end 91.25999 125.69001)
		(width 0.15)
		(layer "F.Cu")
		(net 1)
	)
	(segment
		(start 100.975 150.375)
		(end 100.975 151.07399)
		(width 0.1)
		(layer "F.Cu")
		(net 1)
	)
	(segment
		(start 97.775 110.175)
		(end 97.285009 109.685009)
		(width 0.15)
		(layer "F.Cu")
		(net 1)
	)
	(segment
		(start 96.175 143.975)
		(end 96.175 142.875)
		(width 0.1)
		(layer "F.Cu")
		(net 1)
	)
	(segment
		(start 95.375 150.375)
		(end 95.375 151.074)
		(width 0.1)
		(layer "F.Cu")
		(net 1)
	)
	(segment
		(start 136.274 127.004)
		(end 135.784 126.514)
		(width 0.15)
		(layer "F.Cu")
		(net 1)
	)
	(segment
		(start 140.15 86.85)
		(end 140.2 86.8)
		(width 0.1)
		(layer "F.Cu")
		(net 1)
	)
	(segment
		(start 125.75 164.75)
		(end 125.75 166.05)
		(width 0.2)
		(layer "F.Cu")
		(net 1)
	)
	(segment
		(start 99.775 126.175)
		(end 99.275 126.675)
		(width 0.15)
		(layer "F.Cu")
		(net 1)
	)
	(segment
		(start 64.225 94.435)
		(end 64.225 93.461)
		(width 0.15)
		(layer "F.Cu")
		(net 1)
	)
	(segment
		(start 91.275 109.675)
		(end 91.275 109.685009)
		(width 0.15)
		(layer "F.Cu")
		(net 1)
	)
	(segment
		(start 133.45 88.2275)
		(end 133.45 87.791324)
		(width 0.2)
		(layer "F.Cu")
		(net 1)
	)
	(segment
		(start 91.775 139.575)
		(end 91.775 138.775)
		(width 0.1)
		(layer "F.Cu")
		(net 1)
	)
	(segment
		(start 93.775 128.175)
		(end 93.275 127.675)
		(width 0.15)
		(layer "F.Cu")
		(net 1)
	)
	(segment
		(start 108.65 92.27)
		(end 108.93 91.99)
		(width 0.2)
		(layer "F.Cu")
		(net 1)
	)
	(segment
		(start 108.95 96.89)
		(end 109.1 96.74)
		(width 0.2)
		(layer "F.Cu")
		(net 1)
	)
	(segment
		(start 116.75 163.6)
		(end 116.775 163.575)
		(width 0.2)
		(layer "F.Cu")
		(net 1)
	)
	(segment
		(start 92.065 163.84)
		(end 92.04 163.815)
		(width 0.2)
		(layer "F.Cu")
		(net 1)
	)
	(segment
		(start 91.775 119.175)
		(end 92.275 119.675)
		(width 0.15)
		(layer "F.Cu")
		(net 1)
	)
	(segment
		(start 126.095 117.835)
		(end 126.115 117.855)
		(width 0.15)
		(layer "F.Cu")
		(net 1)
	)
	(segment
		(start 132.85 102.2975)
		(end 132.165 102.2975)
		(width 0.1)
		(layer "F.Cu")
		(net 1)
	)
	(segment
		(start 136.35 163.975)
		(end 136.35 165.95)
		(width 0.2)
		(layer "F.Cu")
		(net 1)
	)
	(segment
		(start 64.225 91.175)
		(end 64.2 91.2)
		(width 0.2)
		(layer "F.Cu")
		(net 1)
	)
	(segment
		(start 102.575 150.375)
		(end 102.575 151.07399)
		(width 0.1)
		(layer "F.Cu")
		(net 1)
	)
	(segment
		(start 134.75 164.75)
		(end 134.75 166.05)
		(width 0.2)
		(layer "F.Cu")
		(net 1)
	)
	(segment
		(start 94.166294 144.366294)
		(end 94.166294 143.38951)
		(width 0.1)
		(layer "F.Cu")
		(net 1)
	)
	(segment
		(start 94.575 150.375)
		(end 94.575 151.07399)
		(width 0.1)
		(layer "F.Cu")
		(net 1)
	)
	(segment
		(start 100.6375 160.275)
		(end 101.575 160.275)
		(width 0.2)
		(layer "F.Cu")
		(net 1)
	)
	(segment
		(start 135.25 164.75)
		(end 135.25 166.45)
		(width 0.2)
		(layer "F.Cu")
		(net 1)
	)
	(segment
		(start 133.99 177.345)
		(end 133.99 175.87)
		(width 0.2)
		(layer "F.Cu")
		(net 1)
	)
	(segment
		(start 73.559 84.377)
		(end 75.228 84.377)
		(width 0.2)
		(layer "F.Cu")
		(net 1)
	)
	(segment
		(start 140.274 122.014)
		(end 140.774 121.514)
		(width 0.2)
		(layer "F.Cu")
		(net 1)
	)
	(segment
		(start 141.835 99.0125)
		(end 142.45 99.0125)
		(width 0.1)
		(layer "F.Cu")
		(net 1)
	)
	(segment
		(start 127.61 113.125)
		(end 128.525 113.125)
		(width 0.15)
		(layer "F.Cu")
		(net 1)
	)
	(segment
		(start 141.274 123.014)
		(end 141.774 122.514)
		(width 0.2)
		(layer "F.Cu")
		(net 1)
	)
	(segment
		(start 132.165 102.2975)
		(end 132.15 102.3125)
		(width 0.1)
		(layer "F.Cu")
		(net 1)
	)
	(segment
		(start 142.274 126.014)
		(end 141.774 125.514)
		(width 0.2)
		(layer "F.Cu")
		(net 1)
	)
	(segment
		(start 139.274 127.004)
		(end 138.784 126.514)
		(width 0.15)
		(layer "F.Cu")
		(net 1)
	)
	(segment
		(start 93.775 123.175)
		(end 93.275 123.675)
		(width 0.15)
		(layer "F.Cu")
		(net 1)
	)
	(segment
		(start 128.525 113.125)
		(end 128.575 113.175)
		(width 0.15)
		(layer "F.Cu")
		(net 1)
	)
	(segment
		(start 99.775 122.175)
		(end 100.275 122.675)
		(width 0.15)
		(layer "F.Cu")
		(net 1)
	)
	(segment
		(start 132.19 177.345)
		(end 132.19 175.87)
		(width 0.2)
		(layer "F.Cu")
		(net 1)
	)
	(segment
		(start 134.75 164.75)
		(end 134.75 166.25)
		(width 0.2)
		(layer "F.Cu")
		(net 1)
	)
	(segment
		(start 77.767 166.363)
		(end 75.829 166.363)
		(width 0.2)
		(layer "F.Cu")
		(net 1)
	)
	(segment
		(start 99.775 116.175)
		(end 100.275 115.675)
		(width 0.15)
		(layer "F.Cu")
		(net 1)
	)
	(segment
		(start 105.775 114.175)
		(end 105.275 113.675)
		(width 0.15)
		(layer "F.Cu")
		(net 1)
	)
	(segment
		(start 95.765 120.175)
		(end 95.265 120.675)
		(width 0.15)
		(layer "F.Cu")
		(net 1)
	)
	(segment
		(start 135.274 126.014)
		(end 135.774 125.514)
		(width 0.2)
		(layer "F.Cu")
		(net 1)
	)
	(segment
		(start 124.95 64.325)
		(end 124.95 65.655)
		(width 0.2)
		(layer "F.Cu")
		(net 1)
	)
	(segment
		(start 130.1875 95.55)
		(end 129.1875 95.55)
		(width 0.1)
		(layer "F.Cu")
		(net 1)
	)
	(segment
		(start 98.3 160.876805)
		(end 98.291302 160.885503)
		(width 0.2)
		(layer "F.Cu")
		(net 1)
	)
	(segment
		(start 137.625 106.575)
		(end 137.625 105.685)
		(width 0.2)
		(layer "F.Cu")
		(net 1)
	)
	(segment
		(start 103.775 122.175)
		(end 104.275 122.675)
		(width 0.15)
		(layer "F.Cu")
		(net 1)
	)
	(segment
		(start 126.79 177.345)
		(end 126.79 175.87)
		(width 0.2)
		(layer "F.Cu")
		(net 1)
	)
	(segment
		(start 98.575 144.775)
		(end 98.175 144.375)
		(width 0.1)
		(layer "F.Cu")
		(net 1)
	)
	(segment
		(start 101.775 139.575)
		(end 101.775 138.775)
		(width 0.1)
		(layer "F.Cu")
		(net 1)
	)
	(segment
		(start 92.065 164.89)
		(end 92.065 163.84)
		(width 0.2)
		(layer "F.Cu")
		(net 1)
	)
	(segment
		(start 96.775 122.175)
		(end 97.275 122.675)
		(width 0.15)
		(layer "F.Cu")
		(net 1)
	)
	(segment
		(start 124.99 177.345)
		(end 124.99 175.92)
		(width 0.2)
		(layer "F.Cu")
		(net 1)
	)
	(segment
		(start 86.084 110.496)
		(end 86.635 109.945)
		(width 0.5)
		(layer "F.Cu")
		(net 1)
	)
	(segment
		(start 121.35 69.08)
		(end 121.375 69.055)
		(width 0.2)
		(layer "F.Cu")
		(net 1)
	)
	(segment
		(start 79.561 68.184)
		(end 79.64 68.105)
		(width 0.2)
		(layer "F.Cu")
		(net 1)
	)
	(segment
		(start 107 144.115)
		(end 107 143.27)
		(width 0.2)
		(layer "F.Cu")
		(net 1)
	)
	(segment
		(start 141.274 127.004)
		(end 140.784 126.514)
		(width 0.15)
		(layer "F.Cu")
		(net 1)
	)
	(segment
		(start 98.59 160.26)
		(end 98.575 160.275)
		(width 0.2)
		(layer "F.Cu")
		(net 1)
	)
	(segment
		(start 90.775 120.175)
		(end 90.275 120.675)
		(width 0.15)
		(layer "F.Cu")
		(net 1)
	)
	(segment
		(start 110.775 119.175)
		(end 110.275 118.675)
		(width 0.15)
		(layer "F.Cu")
		(net 1)
	)
	(segment
		(start 83.39 166.265)
		(end 83.115 166.54)
		(width 0.2)
		(layer "F.Cu")
		(net 1)
	)
	(segment
		(start 109.29 175.891)
		(end 109.274 175.875)
		(width 0.2)
		(layer "F.Cu")
		(net 1)
	)
	(segment
		(start 108.65 92.725)
		(end 108.65 92.27)
		(width 0.2)
		(layer "F.Cu")
		(net 1)
	)
	(segment
		(start 120.325 69.08)
		(end 121.35 69.08)
		(width 0.2)
		(layer "F.Cu")
		(net 1)
	)
	(segment
		(start 137.274 127.004)
		(end 136.784 126.514)
		(width 0.15)
		(layer "F.Cu")
		(net 1)
	)
	(segment
		(start 136.274 123.014)
		(end 135.774 122.514)
		(width 0.2)
		(layer "F.Cu")
		(net 1)
	)
	(segment
		(start 139 86.85)
		(end 140.15 86.85)
		(width 0.1)
		(layer "F.Cu")
		(net 1)
	)
	(segment
		(start 132.45 88.2275)
		(end 132.45 87.6125)
		(width 0.2)
		(layer "F.Cu")
		(net 1)
	)
	(segment
		(start 64.225 90.335)
		(end 64.225 91.175)
		(width 0.2)
		(layer "F.Cu")
		(net 1)
	)
	(segment
		(start 130.745 64.2)
		(end 130.75 64.205)
		(width 0.2)
		(layer "F.Cu")
		(net 1)
	)
	(segment
		(start 78.265 68.184)
		(end 79.561 68.184)
		(width 0.2)
		(layer "F.Cu")
		(net 1)
	)
	(segment
		(start 124.785 134.585)
		(end 126.045 134.585)
		(width 0.15)
		(layer "F.Cu")
		(net 1)
	)
	(segment
		(start 70.85 131.75)
		(end 68.4149 131.75)
		(width 0.2)
		(layer "F.Cu")
		(net 1)
	)
	(segment
		(start 102.775 115.175)
		(end 103.275 115.675)
		(width 0.15)
		(layer "F.Cu")
		(net 1)
	)
	(segment
		(start 95.375 150.375)
		(end 95.375 151.07399)
		(width 0.1)
		(layer "F.Cu")
		(net 1)
	)
	(segment
		(start 134.77 153.995)
		(end 133.995 153.995)
		(width 0.2)
		(layer "F.Cu")
		(net 1)
	)
	(segment
		(start 133.35 90.8875)
		(end 133.35 91.6125)
		(width 0.1)
		(layer "F.Cu")
		(net 1)
	)
	(segment
		(start 64.225 93.461)
		(end 64.229 93.457)
		(width 0.15)
		(layer "F.Cu")
		(net 1)
	)
	(segment
		(start 128.59 177.345)
		(end 128.59 175.87)
		(width 0.2)
		(layer "F.Cu")
		(net 1)
	)
	(segment
		(start 107.995 143.255)
		(end 107.995 144.11)
		(width 0.2)
		(layer "F.Cu")
		(net 1)
	)
	(segment
		(start 128.7775 88.2275)
		(end 128.075 87.525)
		(width 0.2)
		(layer "F.Cu")
		(net 1)
	)
	(segment
		(start 129.1875 95.55)
		(end 129.15 95.5125)
		(width 0.1)
		(layer "F.Cu")
		(net 1)
	)
	(segment
		(start 102.775 123.175)
		(end 102.275 122.675)
		(width 0.15)
		(layer "F.Cu")
		(net 1)
	)
	(segment
		(start 121.25 164.75)
		(end 121.25 166.05)
		(width 0.2)
		(layer "F.Cu")
		(net 1)
	)
	(segment
		(start 98.775 123.175)
		(end 99.275 123.675)
		(width 0.15)
		(layer "F.Cu")
		(net 1)
	)
	(segment
		(start 101.35 99.652149)
		(end 101.35 100.39)
		(width 0.2)
		(layer "F.Cu")
		(net 1)
	)
	(segment
		(start 117.25 164.75)
		(end 117.25 163.2)
		(width 0.2)
		(layer "F.Cu")
		(net 1)
	)
	(segment
		(start 92.775 121.175)
		(end 93.275 121.675)
		(width 0.15)
		(layer "F.Cu")
		(net 1)
	)
	(segment
		(start 116.75 164.75)
		(end 116.75 163.6)
		(width 0.2)
		(layer "F.Cu")
		(net 1)
	)
	(segment
		(start 90.775 119.175)
		(end 91.275 118.675)
		(width 0.15)
		(layer "F.Cu")
		(net 1)
	)
	(segment
		(start 91.54 165.415)
		(end 92.065 164.89)
		(width 0.2)
		(layer "F.Cu")
		(net 1)
	)
	(segment
		(start 91.25999 125.69001)
		(end 91.275 125.69001)
		(width 0.15)
		(layer "F.Cu")
		(net 1)
	)
	(segment
		(start 96.975 150.375)
		(end 96.975 151.07399)
		(width 0.1)
		(layer "F.Cu")
		(net 1)
	)
	(segment
		(start 78.09 177.345)
		(end 78.09 175.745)
		(width 0.15)
		(layer "F.Cu")
		(net 1)
	)
	(segment
		(start 111.775 122.075001)
		(end 112.225 121.625001)
		(width 0.2)
		(layer "F.Cu")
		(net 1)
	)
	(segment
		(start 101.775 124.175)
		(end 102.275 124.675)
		(width 0.15)
		(layer "F.Cu")
		(net 1)
	)
	(segment
		(start 127.25 164.75)
		(end 127.25 166.05)
		(width 0.2)
		(layer "F.Cu")
		(net 1)
	)
	(segment
		(start 98.775 121.175)
		(end 98.275 121.675)
		(width 0.15)
		(layer "F.Cu")
		(net 1)
	)
	(segment
		(start 92.775 119.175)
		(end 93.275 119.675)
		(width 0.15)
		(layer "F.Cu")
		(net 1)
	)
	(segment
		(start 93.775 118.175)
		(end 94.275 118.675)
		(width 0.15)
		(layer "F.Cu")
		(net 1)
	)
	(segment
		(start 105.76 158.275)
		(end 106.375 158.275)
		(width 0.2)
		(layer "F.Cu")
		(net 1)
	)
	(segment
		(start 137.625 105.685)
		(end 137.62 105.68)
		(width 0.2)
		(layer "F.Cu")
		(net 1)
	)
	(segment
		(start 132.275 153.945)
		(end 132.945 153.945)
		(width 0.2)
		(layer "F.Cu")
		(net 1)
	)
	(segment
		(start 145.54 145.07)
		(end 145.54 146.39)
		(width 0.2)
		(layer "F.Cu")
		(net 1)
	)
	(segment
		(start 92.975 151.07399)
		(end 92.97399 151.075)
		(width 0.1)
		(layer "F.Cu")
		(net 1)
	)
	(segment
		(start 102.775 121.175)
		(end 102.275 121.675)
		(width 0.15)
		(layer "F.Cu")
		(net 1)
	)
	(segment
		(start 117.475 154.09)
		(end 115.51 154.09)
		(width 0.2)
		(layer "F.Cu")
		(net 1)
	)
	(segment
		(start 132.35 90.8875)
		(end 132.35 91.6125)
		(width 0.1)
		(layer "F.Cu")
		(net 1)
	)
	(segment
		(start 105.775 122.175)
		(end 106.275 121.675)
		(width 0.15)
		(layer "F.Cu")
		(net 1)
	)
	(segment
		(start 96.975 143.975)
		(end 96.975 142.875)
		(width 0.1)
		(layer "F.Cu")
		(net 1)
	)
	(segment
		(start 138.1875 98.05)
		(end 138.15 98.0125)
		(width 0.1)
		(layer "F.Cu")
		(net 1)
	)
	(segment
		(start 92.975 150.375)
		(end 92.975 151.07399)
		(width 0.1)
		(layer "F.Cu")
		(net 1)
	)
	(segment
		(start 94.775 120.165)
		(end 94.275 120.665)
		(width 0.15)
		(layer "F.Cu")
		(net 1)
	)
	(segment
		(start 82.18 163.565)
		(end 81.385 163.565)
		(width 0.2)
		(layer "F.Cu")
		(net 1)
	)
	(segment
		(start 101.775 122.175)
		(end 102.275 122.675)
		(width 0.15)
		(layer "F.Cu")
		(net 1)
	)
	(segment
		(start 69.71795 97.47205)
		(end 69.648 97.542)
		(width 0.15)
		(layer "F.Cu")
		(net 1)
	)
	(segment
		(start 98.175 144.375)
		(end 98.175 143.375)
		(width 0.1)
		(layer "F.Cu")
		(net 1)
	)
	(segment
		(start 107.775 120.175)
		(end 108.275 120.675)
		(width 0.15)
		(layer "F.Cu")
		(net 1)
	)
	(segment
		(start 98.175 149.975)
		(end 98.175 151.075)
		(width 0.1)
		(layer "F.Cu")
		(net 1)
	)
	(segment
		(start 90.137667 122.712667)
		(end 90.237333 122.712667)
		(width 0.15)
		(layer "F.Cu")
		(net 1)
	)
	(segment
		(start 95.375 151.074)
		(end 95.374 151.075)
		(width 0.1)
		(layer "F.Cu")
		(net 1)
	)
	(segment
		(start 123.19 177.345)
		(end 123.19 175.87)
		(width 0.2)
		(layer "F.Cu")
		(net 1)
	)
	(segment
		(start 98.574 155.16)
		(end 98.574 155.875)
		(width 0.15)
		(layer "F.Cu")
		(net 1)
	)
	(segment
		(start 99.675 154.19)
		(end 99.675 153.575)
		(width 0.2)
		(layer "F.Cu")
		(net 1)
	)
	(segment
		(start 127.265 98.6125)
		(end 127.265 97.9975)
		(width 0.1)
		(layer "F.Cu")
		(net 1)
	)
	(segment
		(start 137.015 75.935)
		(end 137.015 76.415)
		(width 0.15)
		(layer "F.Cu")
		(net 1)
	)
	(segment
		(start 141.835 91.7125)
		(end 142.45 91.7125)
		(width 0.1)
		(layer "F.Cu")
		(net 1)
	)
	(segment
		(start 92.775 125.175)
		(end 93.275 125.675)
		(width 0.15)
		(layer "F.Cu")
		(net 1)
	)
	(segment
		(start 136.35 163.975)
		(end 137.375 163.975)
		(width 0.2)
		(layer "F.Cu")
		(net 1)
	)
	(segment
		(start 90.775 129.175)
		(end 90.275 129.675)
		(width 0.15)
		(layer "F.Cu")
		(net 1)
	)
	(segment
		(start 120.325 73.03)
		(end 121.35 73.03)
		(width 0.2)
		(layer "F.Cu")
		(net 1)
	)
	(segment
		(start 122.75 164.75)
		(end 122.75 166.05)
		(width 0.2)
		(layer "F.Cu")
		(net 1)
	)
	(segment
		(start 100.575 139.575)
		(end 100.575 138.775)
		(width 0.1)
		(layer "F.Cu")
		(net 1)
	)
	(segment
		(start 93.675 139.575)
		(end 93.675 138.775)
		(width 0.1)
		(layer "F.Cu")
		(net 1)
	)
	(segment
		(start 69.392 90.705143)
		(end 69.392 89.79)
		(width 0.2)
		(layer "F.Cu")
		(net 1)
	)
	(segment
		(start 135.85 88.5275)
		(end 135.85 88.0125)
		(width 0.1)
		(layer "F.Cu")
		(net 1)
	)
	(segment
		(start 129.35 64.2)
		(end 130.745 64.2)
		(width 0.2)
		(layer "F.Cu")
		(net 1)
	)
	(segment
		(start 108.66 96.6)
		(end 108.95 96.89)
		(width 0.2)
		(layer "F.Cu")
		(net 1)
	)
	(segment
		(start 103.5125 159.775)
		(end 102.075 159.775)
		(width 0.2)
		(layer "F.Cu")
		(net 1)
	)
	(segment
		(start 97.775 124.175)
		(end 98.275 124.675)
		(width 0.15)
		(layer "F.Cu")
		(net 1)
	)
	(segment
		(start 69.229 89.627)
		(end 68.139 89.627)
		(width 0.2)
		(layer "F.Cu")
		(net 1)
	)
	(segment
		(start 137.85 99.7125)
		(end 137.85 100.7125)
		(width 0.1)
		(layer "F.Cu")
		(net 1)
	)
	(segment
		(start 127.41 128.725)
		(end 128.225 128.725)
		(width 0.15)
		(layer "F.Cu")
		(net 1)
	)
	(segment
		(start 72.9076 64.49)
		(end 72.0624 63.6448)
		(width 0.5)
		(layer "F.Cu")
		(net 1)
	)
	(segment
		(start 145.54 138.36)
		(end 145.54 136.94)
		(width 0.2)
		(layer "F.Cu")
		(net 1)
	)
	(segment
		(start 115.51 154.09)
		(end 115.505 154.095)
		(width 0.2)
		(layer "F.Cu")
		(net 1)
	)
	(segment
		(start 81.385 163.565)
		(end 81.375 163.575)
		(width 0.2)
		(layer "F.Cu")
		(net 1)
	)
	(segment
		(start 135.45 85.05)
		(end 135.4 85.1)
		(width 0.1)
		(layer "F.Cu")
		(net 1)
	)
	(segment
		(start 74.515 166.615)
		(end 74.815 166.915)
		(width 0.15)
		(layer "F.Cu")
		(net 1)
	)
	(segment
		(start 72.627 80.075)
		(end 72.639 80.087)
		(width 0.2)
		(layer "F.Cu")
		(net 1)
	)
	(segment
		(start 93.775 119.175)
		(end 94.275 119.675)
		(width 0.15)
		(layer "F.Cu")
		(net 1)
	)
	(segment
		(start 121.655 64.2)
		(end 121.65 64.205)
		(width 0.2)
		(layer "F.Cu")
		(net 1)
	)
	(segment
		(start 141.835 98.0125)
		(end 142.45 98.0125)
		(width 0.1)
		(layer "F.Cu")
		(net 1)
	)
	(segment
		(start 130.46 115.675)
		(end 130.756439 115.378561)
		(width 0.15)
		(layer "F.Cu")
		(net 1)
	)
	(segment
		(start 94.17499 144.37499)
		(end 94.17499 143.38951)
		(width 0.1)
		(layer "F.Cu")
		(net 1)
	)
	(segment
		(start 95.375 144.775)
		(end 94.983706 144.383706)
		(width 0.1)
		(layer "F.Cu")
		(net 1)
	)
	(segment
		(start 130.756439 115.378561)
		(end 130.778561 115.378561)
		(width 0.15)
		(layer "F.Cu")
		(net 1)
	)
	(segment
		(start 128.225 128.725)
		(end 128.275 128.775)
		(width 0.15)
		(layer "F.Cu")
		(net 1)
	)
	(segment
		(start 74.815 166.915)
		(end 75.615 166.915)
		(width 0.15)
		(layer "F.Cu")
		(net 1)
	)
	(segment
		(start 99.375 162.36)
		(end 100.06 162.36)
		(width 0.15)
		(layer "F.Cu")
		(net 1)
	)
	(segment
		(start 70.975 80.075)
		(end 72.627 80.075)
		(width 0.2)
		(layer "F.Cu")
		(net 1)
	)
	(segment
		(start 74.515 166.35)
		(end 74.515 166.615)
		(width 0.15)
		(layer "F.Cu")
		(net 1)
	)
	(segment
		(start 103.374 155.16)
		(end 103.374 155.875)
		(width 0.15)
		(layer "F.Cu")
		(net 1)
	)
	(segment
		(start 74.58 167.93)
		(end 74.565 167.915)
		(width 0.15)
		(layer "F.Cu")
		(net 1)
	)
	(segment
		(start 68.405 122.2499)
		(end 69.4801 122.2499)
		(width 0.2)
		(layer "F.Cu")
		(net 1)
	)
	(segment
		(start 124.25 164.75)
		(end 124.25 166.05)
		(width 0.2)
		(layer "F.Cu")
		(net 1)
	)
	(segment
		(start 94.575 144.775)
		(end 94.17499 144.37499)
		(width 0.1)
		(layer "F.Cu")
		(net 1)
	)
	(segment
		(start 79.89 177.345)
		(end 79.89 175.745)
		(width 0.15)
		(layer "F.Cu")
		(net 1)
	)
	(segment
		(start 96.775 121.175)
		(end 96.275 121.675)
		(width 0.15)
		(layer "F.Cu")
		(net 1)
	)
	(segment
		(start 133.45 87.791324)
		(end 133.210588 87.551912)
		(width 0.2)
		(layer "F.Cu")
		(net 1)
	)
	(segment
		(start 120.965 133.61)
		(end 120.965 134.425)
		(width 0.15)
		(layer "F.Cu")
		(net 1)
	)
	(segment
		(start 103.775 124.175)
		(end 103.275 124.675)
		(width 0.15)
		(layer "F.Cu")
		(net 1)
	)
	(segment
		(start 137.355 76.755)
		(end 137.565 76.755)
		(width 0.15)
		(layer "F.Cu")
		(net 1)
	)
	(segment
		(start 94.974 155.16)
		(end 94.974 155.875)
		(width 0.15)
		(layer "F.Cu")
		(net 1)
	)
	(segment
		(start 97.374 155.16)
		(end 97.374 155.875)
		(width 0.15)
		(layer "F.Cu")
		(net 1)
	)
	(segment
		(start 92.855 163.235)
		(end 92.3 163.79)
		(width 0.2)
		(layer "F.Cu")
		(net 1)
	)
	(segment
		(start 108.66 96.215)
		(end 108.66 96.6)
		(width 0.2)
		(layer "F.Cu")
		(net 1)
	)
	(segment
		(start 91.08 163.365)
		(end 91.09 163.365)
		(width 0.2)
		(layer "F.Cu")
		(net 1)
	)
	(segment
		(start 93.374 155.16)
		(end 93.374 155.875)
		(width 0.15)
		(layer "F.Cu")
		(net 1)
	)
	(segment
		(start 127.5 61.65)
		(end 127.5 60.355)
		(width 0.2)
		(layer "F.Cu")
		(net 1)
	)
	(segment
		(start 117.25 163.2)
		(end 117.275 163.175)
		(width 0.2)
		(layer "F.Cu")
		(net 1)
	)
	(segment
		(start 92.775 128.175)
		(end 92.275 128.675)
		(width 0.15)
		(layer "F.Cu")
		(net 1)
	)
	(segment
		(start 75.228 84.377)
		(end 75.23 84.375)
		(width 0.2)
		(layer "F.Cu")
		(net 1)
	)
	(segment
		(start 137.015 76.415)
		(end 137.355 76.755)
		(width 0.15)
		(layer "F.Cu")
		(net 1)
	)
	(segment
		(start 109.1 96.74)
		(end 109.84 96.74)
		(width 0.2)
		(layer "F.Cu")
		(net 1)
	)
	(segment
		(start 131.75 164.75)
		(end 131.75 166.05)
		(width 0.2)
		(layer "F.Cu")
		(net 1)
	)
	(segment
		(start 98.575 149.575)
		(end 98.175 149.975)
		(width 0.1)
		(layer "F.Cu")
		(net 1)
	)
	(segment
		(start 68.355 151.0499)
		(end 69.2499 151.0499)
		(width 0.2)
		(layer "F.Cu")
		(net 1)
	)
	(segment
		(start 138.35 90.8875)
		(end 138.35 90.1125)
		(width 0.1)
		(layer "F.Cu")
		(net 1)
	)
	(segment
		(start 101.575 160.275)
		(end 102.075 159.775)
		(width 0.2)
		(layer "F.Cu")
		(net 1)
	)
	(segment
		(start 129.375 88.2275)
		(end 128.7775 88.2275)
		(width 0.2)
		(layer "F.Cu")
		(net 1)
	)
	(segment
		(start 137.375 163.975)
		(end 137.174472 163.774472)
		(width 0.2)
		(layer "F.Cu")
		(net 1)
	)
	(segment
		(start 130.25 164.75)
		(end 130.25 166.05)
		(width 0.2)
		(layer "F.Cu")
		(net 1)
	)
	(segment
		(start 124.955 117.835)
		(end 126.095 117.835)
		(width 0.15)
		(layer "F.Cu")
		(net 1)
	)
	(segment
		(start 90.775 128.175)
		(end 90.275 128.675)
		(width 0.15)
		(layer "F.Cu")
		(net 1)
	)
	(segment
		(start 91.075 165.415)
		(end 91.54 165.415)
		(width 0.2)
		(layer "F.Cu")
		(net 1)
	)
	(segment
		(start 126.965 94.1125)
		(end 126.35 94.1125)
		(width 0.1)
		(layer "F.Cu")
		(net 1)
	)
	(segment
		(start 99.375 160.26)
		(end 98.59 160.26)
		(width 0.2)
		(layer "F.Cu")
		(net 1)
	)
	(segment
		(start 82.135 112.725)
		(end 82.135 114.115)
		(width 0.5)
		(layer "F.Cu")
		(net 1)
	)
	(segment
		(start 142.274 120.014)
		(end 142.774 119.514)
		(width 0.2)
		(layer "F.Cu")
		(net 1)
	)
	(segment
		(start 90.775 124.175)
		(end 90.275 124.675)
		(width 0.15)
		(layer "F.Cu")
		(net 1)
	)
	(segment
		(start 68.375 141.4399)
		(end 69.3299 141.4399)
		(width 0.2)
		(layer "F.Cu")
		(net 1)
	)
	(segment
		(start 129.06 131.375)
		(end 129.675 131.375)
		(width 0.15)
		(layer "F.Cu")
		(net 1)
	)
	(segment
		(start 134.55 85.8275)
		(end 135.235 85.8275)
		(width 0.1)
		(layer "F.Cu")
		(net 1)
	)
	(segment
		(start 91.565 163.365)
		(end 92.015 163.815)
		(width 0.2)
		(layer "F.Cu")
		(net 1)
	)
	(segment
		(start 107.995 144.11)
		(end 108 144.115)
		(width 0.2)
		(layer "F.Cu")
		(net 1)
	)
	(segment
		(start 102.575 143.975)
		(end 102.575 142.875)
		(width 0.1)
		(layer "F.Cu")
		(net 1)
	)
	(segment
		(start 138.274 127.004)
		(end 137.784 126.514)
		(width 0.15)
		(layer "F.Cu")
		(net 1)
	)
	(segment
		(start 117.75 164.75)
		(end 117.75 163.6)
		(width 0.2)
		(layer "F.Cu")
		(net 1)
	)
	(segment
		(start 133.85 90.8875)
		(end 133.85 91.6125)
		(width 0.1)
		(layer "F.Cu")
		(net 1)
	)
	(segment
		(start 68.072 159.783)
		(end 68.065 159.79)
		(width 0.15)
		(layer "F.Cu")
		(net 1)
	)
	(segment
		(start 95.675 139.575)
		(end 95.675 138.775)
		(width 0.1)
		(layer "F.Cu")
		(net 1)
	)
	(segment
		(start 68.572 158.45122)
		(end 68.572 159.847)
		(width 0.15)
		(layer "F.Cu")
		(net 1)
	)
	(segment
		(start 78.015 166.115)
		(end 77.767 166.363)
		(width 0.2)
		(layer "F.Cu")
		(net 1)
	)
	(segment
		(start 74.58 168.715)
		(end 74.58 167.93)
		(width 0.15)
		(layer "F.Cu")
		(net 1)
	)
	(segment
		(start 105.775 120.175)
		(end 106.275 119.675)
		(width 0.15)
		(layer "F.Cu")
		(net 1)
	)
	(segment
		(start 90.775 109.175)
		(end 91.275 109.675)
		(width 0.15)
		(layer "F.Cu")
		(net 1)
	)
	(segment
		(start 141.835 95.5125)
		(end 142.45 95.5125)
		(width 0.1)
		(layer "F.Cu")
		(net 1)
	)
	(segment
		(start 72.9826 64.49)
		(end 72.9076 64.49)
		(width 0.5)
		(layer "F.Cu")
		(net 1)
	)
	(segment
		(start 137.274 122.014)
		(end 137.774 122.514)
		(width 0.2)
		(layer "F.Cu")
		(net 1)
	)
	(segment
		(start 121.305 116.9)
		(end 121.305 118.005)
		(width 0.15)
		(layer "F.Cu")
		(net 1)
	)
	(segment
		(start 140.274 127.004)
		(end 139.784 126.514)
		(width 0.15)
		(layer "F.Cu")
		(net 1)
	)
	(segment
		(start 134.75 166.25)
		(end 134.775 166.275)
		(width 0.2)
		(layer "F.Cu")
		(net 1)
	)
	(segment
		(start 108.775 113.175)
		(end 109.275 112.675)
		(width 0.15)
		(layer "F.Cu")
		(net 1)
	)
	(segment
		(start 137.017 74.642)
		(end 137.017 75.89)
		(width 0.1)
		(layer "F.Cu")
		(net 1)
	)
	(segment
		(start 135.235 85.8275)
		(end 135.25 85.8125)
		(width 0.1)
		(layer "F.Cu")
		(net 1)
	)
	(segment
		(start 94.775 122.175)
		(end 95.275 121.675)
		(width 0.15)
		(layer "F.Cu")
		(net 1)
	)
	(segment
		(start 77.635 64.515)
		(end 72.9826 64.515)
		(width 0.5)
		(layer "F.Cu")
		(net 1)
	)
	(segment
		(start 125.1 61.65)
		(end 125.1 60.355)
		(width 0.2)
		(layer "F.Cu")
		(net 1)
	)
	(segment
		(start 115.65 163.975)
		(end 115.65 162.12)
		(width 0.15)
		(layer "F.Cu")
		(net 1)
	)
	(segment
		(start 86.084 110.57)
		(end 86.084 110.496)
		(width 0.5)
		(layer "F.Cu")
		(net 1)
	)
	(segment
		(start 102.075 159.775)
		(end 102.075 161.075)
		(width 0.2)
		(layer "F.Cu")
		(net 1)
	)
	(segment
		(start 68.4149 131.75)
		(end 68.365 131.7999)
		(width 0.2)
		(layer "F.Cu")
		(net 1)
	)
	(segment
		(start 104.775 119.175)
		(end 105.275 119.675)
		(width 0.15)
		(layer "F.Cu")
		(net 1)
	)
	(segment
		(start 139.0125 98.05)
		(end 138.1875 98.05)
		(width 0.1)
		(layer "F.Cu")
		(net 1)
	)
	(segment
		(start 98.775 139.575)
		(end 98.775 138.775)
		(width 0.1)
		(layer "F.Cu")
		(net 1)
	)
	(segment
		(start 120.965 134.425)
		(end 120.935 134.455)
		(width 0.15)
		(layer "F.Cu")
		(net 1)
	)
	(segment
		(start 107 143.27)
		(end 106.985 143.255)
		(width 0.2)
		(layer "F.Cu")
		(net 1)
	)
	(segment
		(start 75.83 166.365)
		(end 75.83 166.7)
		(width 0.15)
		(layer "F.Cu")
		(net 1)
	)
	(segment
		(start 75.83 166.7)
		(end 75.615 166.915)
		(width 0.15)
		(layer "F.Cu")
		(net 1)
	)
	(segment
		(start 126.55 69.4375)
		(end 126.55 69.9125)
		(width 0.1)
		(layer "F.Cu")
		(net 1)
	)
	(segment
		(start 92.015 163.815)
		(end 92.065 163.815)
		(width 0.2)
		(layer "F.Cu")
		(net 1)
	)
	(segment
		(start 75.279 86.487)
		(end 75.279 84.424)
		(width 0.2)
		(layer "F.Cu")
		(net 1)
	)
	(segment
		(start 97.775 139.575)
		(end 97.775 138.775)
		(width 0.1)
		(layer "F.Cu")
		(net 1)
	)
	(segment
		(start 100.06 162.36)
		(end 100.075 162.375)
		(width 0.15)
		(layer "F.Cu")
		(net 1)
	)
	(segment
		(start 68.072 158.45122)
		(end 68.072 159.783)
		(width 0.15)
		(layer "F.Cu")
		(net 1)
	)
	(segment
		(start 91.775 128.175)
		(end 91.275 128.675)
		(width 0.15)
		(layer "F.Cu")
		(net 1)
	)
	(segment
		(start 140.35 140.965)
		(end 139.09 140.965)
		(width 0.2)
		(layer "F.Cu")
		(net 1)
	)
	(segment
		(start 93.275 125.675)
		(end 93.275 125.69001)
		(width 0.15)
		(layer "F.Cu")
		(net 1)
	)
	(segment
		(start 99.39 160.275)
		(end 99.375 160.26)
		(width 0.2)
		(layer "F.Cu")
		(net 1)
	)
	(segment
		(start 126.045 134.585)
		(end 126.075 134.615)
		(width 0.15)
		(layer "F.Cu")
		(net 1)
	)
	(segment
		(start 117.75 163.6)
		(end 117.775 163.575)
		(width 0.2)
		(layer "F.Cu")
		(net 1)
	)
	(segment
		(start 96.174 155.16)
		(end 96.174 155.875)
		(width 0.15)
		(layer "F.Cu")
		(net 1)
	)
	(segment
		(start 91.09 163.365)
		(end 91.565 163.365)
		(width 0.2)
		(layer "F.Cu")
		(net 1)
	)
	(segment
		(start 97.285009 109.685009)
		(end 97.275 109.685009)
		(width 0.15)
		(layer "F.Cu")
		(net 1)
	)
	(segment
		(start 135.25 166.45)
		(end 135.275 166.475)
		(width 0.2)
		(layer "F.Cu")
		(net 1)
	)
	(segment
		(start 115.65 162.12)
		(end 115.695 162.075)
		(width 0.15)
		(layer "F.Cu")
		(net 1)
	)
	(segment
		(start 94.775 126.175)
		(end 94.275 126.675)
		(width 0.15)
		(layer "F.Cu")
		(net 1)
	)
	(segment
		(start 95.375 149.575)
		(end 95.775 149.975)
		(width 0.1)
		(layer "F.Cu")
		(net 1)
	)
	(segment
		(start 130.39 177.345)
		(end 130.39 175.87)
		(width 0.2)
		(layer "F.Cu")
		(net 1)
	)
	(segment
		(start 131.275 153.89)
		(end 130.49 153.89)
		(width 0.2)
		(layer "F.Cu")
		(net 1)
	)
	(segment
		(start 136.7 85.05)
		(end 135.45 85.05)
		(width 0.1)
		(layer "F.Cu")
		(net 1)
	)
	(segment
		(start 128.225 129.225)
		(end 128.275 129.275)
		(width 0.15)
		(layer "F.Cu")
		(net 1)
	)
	(segment
		(start 100.6375 160.275)
		(end 99.39 160.275)
		(width 0.2)
		(layer "F.Cu")
		(net 1)
	)
	(segment
		(start 132.945 153.945)
		(end 132.975 153.975)
		(width 0.2)
		(layer "F.Cu")
		(net 1)
	)
	(segment
		(start 96.775 119.175)
		(end 97.275 119.675)
		(width 0.15)
		(layer "F.Cu")
		(net 1)
	)
	(segment
		(start 127.41 129.225)
		(end 128.225 129.225)
		(width 0.15)
		(layer "F.Cu")
		(net 1)
	)
	(segment
		(start 111.83 93.97)
		(end 111.83 92.75)
		(width 0.2)
		(layer "F.Cu")
		(net 1)
	)
	(segment
		(start 130.05 60.355)
		(end 130.1 60.305)
		(width 0.2)
		(layer "F.Cu")
		(net 1)
	)
	(segment
		(start 133.995 153.995)
		(end 133.975 153.975)
		(width 0.2)
		(layer "F.Cu")
		(net 1)
	)
	(segment
		(start 94.675 139.575)
		(end 94.675 138.775)
		(width 0.1)
		(layer "F.Cu")
		(net 1)
	)
	(segment
		(start 134.565 102.2975)
		(end 134.55 102.3125)
		(width 0.1)
		(layer "F.Cu")
		(net 1)
	)
	(segment
		(start 92.3 163.79)
		(end 92.065 163.79)
		(width 0.2)
		(layer "F.Cu")
		(net 1)
	)
	(segment
		(start 84.455 166.265)
		(end 83.39 166.265)
		(width 0.2)
		(layer "F.Cu")
		(net 1)
	)
	(segment
		(start 131.85 99.7125)
		(end 131.85 98.8125)
		(width 0.1)
		(layer "F.Cu")
		(net 1)
	)
	(segment
		(start 111.775 112.175)
		(end 112.475 112.175)
		(width 0.15)
		(layer "F.Cu")
		(net 1)
	)
	(segment
		(start 135.274 127.004)
		(end 134.784 126.514)
		(width 0.15)
		(layer "F.Cu")
		(net 1)
	)
	(segment
		(start 83.09 166.565)
		(end 83.34 166.815)
		(width 0.2)
		(layer "F.Cu")
		(net 1)
	)
	(segment
		(start 101.35 100.39)
		(end 101.374 100.414)
		(width 0.2)
		(layer "F.Cu")
		(net 1)
	)
	(segment
		(start 128.75 164.75)
		(end 128.75 166.05)
		(width 0.2)
		(layer "F.Cu")
		(net 1)
	)
	(segment
		(start 109.775 116.175)
		(end 110.275 116.675)
		(width 0.15)
		(layer "F.Cu")
		(net 1)
	)
	(segment
		(start 135.35 102.2975)
		(end 134.565 102.2975)
		(width 0.1)
		(layer "F.Cu")
		(net 1)
	)
	(segment
		(start 75.279 84.424)
		(end 75.23 84.375)
		(width 0.2)
		(layer "F.Cu")
		(net 1)
	)
	(segment
		(start 111.775 122.175)
		(end 111.775 122.075001)
		(width 0.2)
		(layer "F.Cu")
		(net 1)
	)
	(segment
		(start 100.775 123.175)
		(end 101.275 123.675)
		(width 0.15)
		(layer "F.Cu")
		(net 1)
	)
	(segment
		(start 139.985 83.5)
		(end 140.6 83.5)
		(width 0.1)
		(layer "F.Cu")
		(net 1)
	)
	(segment
		(start 101.774 155.16)
		(end 101.774 155.875)
		(width 0.15)
		(layer "F.Cu")
		(net 1)
	)
	(segment
		(start 68.572 159.847)
		(end 68.665 159.94)
		(width 0.15)
		(layer "F.Cu")
		(net 1)
	)
	(segment
		(start 106.775 127.175)
		(end 107.275 127.675)
		(width 0.15)
		(layer "F.Cu")
		(net 1)
	)
	(segment
		(start 102.775 122.175)
		(end 103.275 122.675)
		(width 0.15)
		(layer "F.Cu")
		(net 1)
	)
	(segment
		(start 136.35 165.95)
		(end 136.375 165.975)
		(width 0.2)
		(layer "F.Cu")
		(net 1)
	)
	(segment
		(start 69.392 89.79)
		(end 69.229 89.627)
		(width 0.2)
		(layer "F.Cu")
		(net 1)
	)
	(segment
		(start 130.49 153.89)
		(end 130.475 153.875)
		(width 0.2)
		(layer "F.Cu")
		(net 1)
	)
	(segment
		(start 131.35 90.8875)
		(end 131.35 91.6125)
		(width 0.1)
		(layer "F.Cu")
		(net 1)
	)
	(segment
		(start 99.69 157.475)
		(end 99.075 157.475)
		(width 0.2)
		(layer "F.Cu")
		(net 1)
	)
	(segment
		(start 98.3 160.285)
		(end 98.3 160.876805)
		(width 0.2)
		(layer "F.Cu")
		(net 1)
	)
	(segment
		(start 139.264 125.014)
		(end 138.774 125.504)
		(width 0.15)
		(layer "F.Cu")
		(net 1)
	)
	(segment
		(start 90.237333 122.712667)
		(end 90.775 122.175)
		(width 0.15)
		(layer "F.Cu")
		(net 1)
	)
	(segment
		(start 100.775 122.175)
		(end 101.275 122.675)
		(width 0.15)
		(layer "F.Cu")
		(net 1)
	)
	(segment
		(start 96.775 123.175)
		(end 97.275 123.675)
		(width 0.15)
		(layer "F.Cu")
		(net 1)
	)
	(segment
		(start 94.775 127.175)
		(end 94.275 127.675)
		(width 0.15)
		(layer "F.Cu")
		(net 1)
	)
	(segment
		(start 94.983706 144.383706)
		(end 94.983706 143.38951)
		(width 0.1)
		(layer "F.Cu")
		(net 1)
	)
	(via blind
		(at 133.25 166.05)
		(size 0.5)
		(drill 0.2)
		(layers "F.Cu" "In1.Cu")
		(net 1)
	)
	(via
		(at 100.275 124.675)
		(size 0.5)
		(drill 0.2)
		(layers "F.Cu" "B.Cu")
		(net 1)
	)
	(via blind
		(at 111.275 129.675)
		(size 0.5)
		(drill 0.2)
		(layers "F.Cu" "In1.Cu")
		(net 1)
	)
	(via blind
		(at 94.275 110.675)
		(size 0.5)
		(drill 0.2)
		(layers "F.Cu" "In1.Cu")
		(net 1)
	)
	(via
		(at 126.675 112.175)
		(size 0.5)
		(drill 0.2)
		(layers "F.Cu" "B.Cu")
		(net 1)
	)
	(via
		(at 101.275 129.675)
		(size 0.5)
		(drill 0.2)
		(layers "F.Cu" "B.Cu")
		(net 1)
	)
	(via blind
		(at 108.275 130.675)
		(size 0.5)
		(drill 0.2)
		(layers "F.Cu" "In1.Cu")
		(net 1)
	)
	(via
		(at 96.275 125.675)
		(size 0.5)
		(drill 0.2)
		(layers "F.Cu" "B.Cu")
		(net 1)
	)
	(via blind
		(at 93.275 126.675)
		(size 0.5)
		(drill 0.2)
		(layers "F.Cu" "In1.Cu")
		(net 1)
	)
	(via
		(at 97.275 124.675)
		(size 0.5)
		(drill 0.2)
		(layers "F.Cu" "B.Cu")
		(net 1)
	)
	(via blind
		(at 95.275 126.675)
		(size 0.5)
		(drill 0.2)
		(layers "F.Cu" "In1.Cu")
		(net 1)
	)
	(via
		(at 103.275 125.675)
		(size 0.5)
		(drill 0.2)
		(layers "F.Cu" "B.Cu")
		(net 1)
	)
	(via blind
		(at 92.975 148.175)
		(size 0.5)
		(drill 0.2)
		(layers "F.Cu" "In1.Cu")
		(net 1)
	)
	(via
		(at 135.79 175.87)
		(size 0.5)
		(drill 0.2)
		(layers "F.Cu" "B.Cu")
		(net 1)
	)
	(via blind
		(at 103.375 138.775)
		(size 0.5)
		(drill 0.2)
		(layers "F.Cu" "In1.Cu")
		(net 1)
	)
	(via blind
		(at 104.17399 151.075)
		(size 0.5)
		(drill 0.2)
		(layers "F.Cu" "In1.Cu")
		(net 1)
	)
	(via blind
		(at 105.074 155.875)
		(size 0.5)
		(drill 0.2)
		(layers "F.Cu" "In1.Cu")
		(net 1)
	)
	(via blind
		(at 97.775 130.775)
		(size 0.5)
		(drill 0.2)
		(layers "F.Cu" "In1.Cu")
		(net 1)
	)
	(via blind
		(at 100.275 120.675)
		(size 0.5)
		(drill 0.2)
		(layers "F.Cu" "In1.Cu")
		(net 1)
	)
	(via blind
		(at 102.275 120.675)
		(size 0.5)
		(drill 0.2)
		(layers "F.Cu" "In1.Cu")
		(net 1)
	)
	(via
		(at 98.275 122.675)
		(size 0.5)
		(drill 0.2)
		(layers "F.Cu" "B.Cu")
		(net 1)
	)
	(via
		(at 100.275 121.675)
		(size 0.5)
		(drill 0.2)
		(layers "F.Cu" "B.Cu")
		(net 1)
	)
	(via blind
		(at 104.175 142.875)
		(size 0.5)
		(drill 0.2)
		(layers "F.Cu" "In1.Cu")
		(net 1)
	)
	(via blind
		(at 100.975 142.875)
		(size 0.5)
		(drill 0.2)
		(layers "F.Cu" "In1.Cu")
		(net 1)
	)
	(via blind
		(at 96.275 126.675)
		(size 0.5)
		(drill 0.2)
		(layers "F.Cu" "In1.Cu")
		(net 1)
	)
	(via
		(at 124.015 127.715)
		(size 0.5)
		(drill 0.2)
		(layers "F.Cu" "B.Cu")
		(net 1)
	)
	(via blind
		(at 96.575 143.375)
		(size 0.5)
		(drill 0.2)
		(layers "F.Cu" "In1.Cu")
		(net 1)
	)
	(via blind
		(at 92.975 142.875)
		(size 0.5)
		(drill 0.2)
		(layers "F.Cu" "In1.Cu")
		(net 1)
	)
	(via
		(at 104.275 110.675)
		(size 0.5)
		(drill 0.2)
		(layers "F.Cu" "B.Cu")
		(net 1)
	)
	(via blind
		(at 110.275 126.675)
		(size 0.5)
		(drill 0.2)
		(layers "F.Cu" "In1.Cu")
		(net 1)
	)
	(via blind
		(at 101.69 175.695)
		(size 0.5)
		(drill 0.2)
		(layers "F.Cu" "In1.Cu")
		(net 1)
	)
	(via blind
		(at 92.175 142.875)
		(size 0.5)
		(drill 0.2)
		(layers "F.Cu" "In1.Cu")
		(net 1)
	)
	(via blind
		(at 96.265 175.27)
		(size 0.5)
		(drill 0.2)
		(layers "F.Cu" "In2.Cu")
		(net 1)
	)
	(via blind
		(at 104.275 128.675)
		(size 0.5)
		(drill 0.2)
		(layers "F.Cu" "In1.Cu")
		(net 1)
	)
	(via blind
		(at 106.375 162.075)
		(size 0.5)
		(drill 0.2)
		(layers "F.Cu" "In1.Cu")
		(net 1)
	)
	(via blind
		(at 100.275 122.675)
		(size 0.5)
		(drill 0.2)
		(layers "F.Cu" "In1.Cu")
		(net 1)
	)
	(via blind
		(at 92.115 175.47)
		(size 0.5)
		(drill 0.2)
		(layers "F.Cu" "In2.Cu")
		(net 1)
	)
	(via blind
		(at 100.275 108.675)
		(size 0.5)
		(drill 0.2)
		(layers "F.Cu" "In1.Cu")
		(net 1)
	)
	(via
		(at 102.275 112.675)
		(size 0.5)
		(drill 0.2)
		(layers "F.Cu" "B.Cu")
		(net 1)
	)
	(via
		(at 64.585 128.41)
		(size 0.5)
		(drill 0.2)
		(layers "F.Cu" "B.Cu")
		(net 1)
	)
	(via
		(at 110.275 109.675)
		(size 0.5)
		(drill 0.2)
		(layers "F.Cu" "B.Cu")
		(net 1)
	)
	(via
		(at 107.285 109.695)
		(size 0.5)
		(drill 0.2)
		(layers "F.Cu" "B.Cu")
		(net 1)
	)
	(via blind
		(at 128.575 112.675)
		(size 0.5)
		(drill 0.2)
		(layers "F.Cu" "In1.Cu")
		(net 1)
	)
	(via
		(at 124.007 128.437)
		(size 0.5)
		(drill 0.2)
		(layers "F.Cu" "B.Cu")
		(net 1)
	)
	(via
		(at 125.975 110.675)
		(size 0.5)
		(drill 0.2)
		(layers "F.Cu" "B.Cu")
		(net 1)
	)
	(via
		(at 109.275 123.675)
		(size 0.5)
		(drill 0.2)
		(layers "F.Cu" "B.Cu")
		(net 1)
	)
	(via blind
		(at 112.29 175.445)
		(size 0.5)
		(drill 0.2)
		(layers "F.Cu" "In1.Cu")
		(net 1)
	)
	(via
		(at 98.275 112.675)
		(size 0.5)
		(drill 0.2)
		(layers "F.Cu" "B.Cu")
		(net 1)
	)
	(via
		(at 141.784 126.514)
		(size 0.5)
		(drill 0.2)
		(layers "F.Cu" "B.Cu")
		(net 1)
	)
	(via
		(at 64.565 147.645)
		(size 0.5)
		(drill 0.2)
		(layers "F.Cu" "B.Cu")
		(net 1)
	)
	(via
		(at 91.362 94.086)
		(size 0.5)
		(drill 0.2)
		(layers "F.Cu" "B.Cu")
		(net 1)
	)
	(via
		(at 90.402 93.086)
		(size 0.5)
		(drill 0.2)
		(layers "F.Cu" "B.Cu")
		(net 1)
	)
	(via
		(at 90.402 94.086)
		(size 0.5)
		(drill 0.2)
		(layers "F.Cu" "B.Cu")
		(net 1)
	)
	(via
		(at 91.362 93.086)
		(size 0.5)
		(drill 0.2)
		(layers "F.Cu" "B.Cu")
		(net 1)
	)
	(via blind
		(at 95.275 123.675)
		(size 0.5)
		(drill 0.2)
		(layers "F.Cu" "In1.Cu")
		(net 1)
	)
	(via
		(at 106.275 117.675)
		(size 0.5)
		(drill 0.2)
		(layers "F.Cu" "B.Cu")
		(net 1)
	)
	(via
		(at 101.469 95.597)
		(size 0.5)
		(drill 0.2)
		(layers "F.Cu" "B.Cu")
		(net 1)
	)
	(via
		(at 102.729 96.857)
		(size 0.5)
		(drill 0.2)
		(layers "F.Cu" "B.Cu")
		(net 1)
	)
	(via
		(at 104.275 117.675)
		(size 0.5)
		(drill 0.2)
		(layers "F.Cu" "B.Cu")
		(net 1)
	)
	(via blind
		(at 134.774 119.514)
		(size 0.5)
		(drill 0.2)
		(layers "F.Cu" "In5.Cu")
		(net 1)
	)
	(via
		(at 104.275 121.675)
		(size 0.5)
		(drill 0.2)
		(layers "F.Cu" "B.Cu")
		(net 1)
	)
	(via blind
		(at 98.275 120.675)
		(size 0.5)
		(drill 0.2)
		(layers "F.Cu" "In1.Cu")
		(net 1)
	)
	(via blind
		(at 99.275 119.675)
		(size 0.5)
		(drill 0.2)
		(layers "F.Cu" "In1.Cu")
		(net 1)
	)
	(via blind
		(at 97.275 117.675)
		(size 0.5)
		(drill 0.2)
		(layers "F.Cu" "In1.Cu")
		(net 1)
	)
	(via
		(at 105.275 124.675)
		(size 0.5)
		(drill 0.2)
		(layers "F.Cu" "B.Cu")
		(net 1)
	)
	(via
		(at 76.29 175.745)
		(size 0.5)
		(drill 0.2)
		(layers "F.Cu" "B.Cu")
		(net 1)
	)
	(via blind
		(at 96.275 113.675)
		(size 0.5)
		(drill 0.2)
		(layers "F.Cu" "In1.Cu")
		(net 1)
	)
	(via blind
		(at 93.275 114.675)
		(size 0.5)
		(drill 0.2)
		(layers "F.Cu" "In1.Cu")
		(net 1)
	)
	(via
		(at 100.875 89.515)
		(size 0.5)
		(drill 0.2)
		(layers "F.Cu" "B.Cu")
		(net 1)
	)
	(via
		(at 104.005 97.605)
		(size 0.5)
		(drill 0.2)
		(layers "F.Cu" "B.Cu")
		(net 1)
	)
	(via
		(at 100.195 96.835)
		(size 0.5)
		(drill 0.2)
		(layers "F.Cu" "B.Cu")
		(net 1)
	)
	(via
		(at 95.395 99.495)
		(size 0.5)
		(drill 0.2)
		(layers "F.Cu" "B.Cu")
		(net 1)
	)
	(via
		(at 89.527 70.566)
		(size 0.5)
		(drill 0.2)
		(layers "F.Cu" "B.Cu")
		(net 1)
	)
	(via
		(at 89.527 71.566)
		(size 0.5)
		(drill 0.2)
		(layers "F.Cu" "B.Cu")
		(net 1)
	)
	(via
		(at 90.527 70.566)
		(size 0.5)
		(drill 0.2)
		(layers "F.Cu" "B.Cu")
		(net 1)
	)
	(via
		(at 90.527 71.566)
		(size 0.5)
		(drill 0.2)
		(layers "F.Cu" "B.Cu")
		(net 1)
	)
	(via
		(at 80.855 59.835)
		(size 0.5)
		(drill 0.2)
		(layers "F.Cu" "B.Cu")
		(net 1)
	)
	(via
		(at 79.355 60.335)
		(size 0.5)
		(drill 0.2)
		(layers "F.Cu" "B.Cu")
		(net 1)
	)
	(via
		(at 78.855 59.835)
		(size 0.5)
		(drill 0.2)
		(layers "F.Cu" "B.Cu")
		(net 1)
	)
	(via
		(at 78.855 60.835)
		(size 0.5)
		(drill 0.2)
		(layers "F.Cu" "B.Cu")
		(net 1)
	)
	(via
		(at 79.855 59.835)
		(size 0.5)
		(drill 0.2)
		(layers "F.Cu" "B.Cu")
		(net 1)
	)
	(via
		(at 79.855 60.835)
		(size 0.5)
		(drill 0.2)
		(layers "F.Cu" "B.Cu")
		(net 1)
	)
	(via
		(at 80.855 60.835)
		(size 0.5)
		(drill 0.2)
		(layers "F.Cu" "B.Cu")
		(net 1)
	)
	(via
		(at 80.355 60.335)
		(size 0.5)
		(drill 0.2)
		(layers "F.Cu" "B.Cu")
		(net 1)
	)
	(via
		(at 82.145 114.125)
		(size 0.5)
		(drill 0.2)
		(layers "F.Cu" "B.Cu")
		(net 1)
	)
	(via blind
		(at 91.275 111.675)
		(size 0.5)
		(drill 0.2)
		(layers "F.Cu" "In1.Cu")
		(net 1)
	)
	(via
		(at 140.62 105.68)
		(size 0.5)
		(drill 0.2)
		(layers "F.Cu" "B.Cu")
		(net 1)
	)
	(via
		(at 101.275 121.675)
		(size 0.5)
		(drill 0.2)
		(layers "F.Cu" "B.Cu")
		(net 1)
	)
	(via
		(at 122.5 60.305)
		(size 0.5)
		(drill 0.2)
		(layers "F.Cu" "B.Cu")
		(net 1)
	)
	(via
		(at 61.35 148.838467)
		(size 0.5)
		(drill 0.2)
		(layers "F.Cu" "B.Cu")
		(net 1)
	)
	(via
		(at 61.35 146.822933)
		(size 0.5)
		(drill 0.2)
		(layers "F.Cu" "B.Cu")
		(net 1)
	)
	(via
		(at 61.35 144.8074)
		(size 0.5)
		(drill 0.2)
		(layers "F.Cu" "B.Cu")
		(net 1)
	)
	(via
		(at 61.35 142.791867)
		(size 0.5)
		(drill 0.2)
		(layers "F.Cu" "B.Cu")
		(net 1)
	)
	(via
		(at 61.35 140.776333)
		(size 0.5)
		(drill 0.2)
		(layers "F.Cu" "B.Cu")
		(net 1)
	)
	(via
		(at 61.35 138.7608)
		(size 0.5)
		(drill 0.2)
		(layers "F.Cu" "B.Cu")
		(net 1)
	)
	(via
		(at 61.35 136.745267)
		(size 0.5)
		(drill 0.2)
		(layers "F.Cu" "B.Cu")
		(net 1)
	)
	(via
		(at 61.35 134.729733)
		(size 0.5)
		(drill 0.2)
		(layers "F.Cu" "B.Cu")
		(net 1)
	)
	(via
		(at 61.35 132.7142)
		(size 0.5)
		(drill 0.2)
		(layers "F.Cu" "B.Cu")
		(net 1)
	)
	(via
		(at 61.35 130.698667)
		(size 0.5)
		(drill 0.2)
		(layers "F.Cu" "B.Cu")
		(net 1)
	)
	(via
		(at 61.35 128.683133)
		(size 0.5)
		(drill 0.2)
		(layers "F.Cu" "B.Cu")
		(net 1)
	)
	(via
		(at 61.35 126.6676)
		(size 0.5)
		(drill 0.2)
		(layers "F.Cu" "B.Cu")
		(net 1)
	)
	(via
		(at 61.35 124.652067)
		(size 0.5)
		(drill 0.2)
		(layers "F.Cu" "B.Cu")
		(net 1)
	)
	(via
		(at 61.35 122.636533)
		(size 0.5)
		(drill 0.2)
		(layers "F.Cu" "B.Cu")
		(net 1)
	)
	(via
		(at 61.35 120.621)
		(size 0.5)
		(drill 0.2)
		(layers "F.Cu" "B.Cu")
		(net 1)
	)
	(via
		(at 61.35 118.605467)
		(size 0.5)
		(drill 0.2)
		(layers "F.Cu" "B.Cu")
		(net 1)
	)
	(via
		(at 61.35 116.589933)
		(size 0.5)
		(drill 0.2)
		(layers "F.Cu" "B.Cu")
		(net 1)
	)
	(via
		(at 61.35 114.5744)
		(size 0.5)
		(drill 0.2)
		(layers "F.Cu" "B.Cu")
		(net 1)
	)
	(via
		(at 61.35 112.558866)
		(size 0.5)
		(drill 0.2)
		(layers "F.Cu" "B.Cu")
		(net 1)
	)
	(via
		(at 61.35 110.543333)
		(size 0.5)
		(drill 0.2)
		(layers "F.Cu" "B.Cu")
		(net 1)
	)
	(via
		(at 61.35 108.5278)
		(size 0.5)
		(drill 0.2)
		(layers "F.Cu" "B.Cu")
		(net 1)
	)
	(via
		(at 61.35 106.512266)
		(size 0.5)
		(drill 0.2)
		(layers "F.Cu" "B.Cu")
		(net 1)
	)
	(via
		(at 61.35 104.496733)
		(size 0.5)
		(drill 0.2)
		(layers "F.Cu" "B.Cu")
		(net 1)
	)
	(via
		(at 61.35 102.4812)
		(size 0.5)
		(drill 0.2)
		(layers "F.Cu" "B.Cu")
		(net 1)
	)
	(via
		(at 61.35 100.465666)
		(size 0.5)
		(drill 0.2)
		(layers "F.Cu" "B.Cu")
		(net 1)
	)
	(via
		(at 61.35 98.450133)
		(size 0.5)
		(drill 0.2)
		(layers "F.Cu" "B.Cu")
		(net 1)
	)
	(via
		(at 61.35 96.4346)
		(size 0.5)
		(drill 0.2)
		(layers "F.Cu" "B.Cu")
		(net 1)
	)
	(via
		(at 61.35 94.419066)
		(size 0.5)
		(drill 0.2)
		(layers "F.Cu" "B.Cu")
		(net 1)
	)
	(via
		(at 61.35 92.403533)
		(size 0.5)
		(drill 0.2)
		(layers "F.Cu" "B.Cu")
		(net 1)
	)
	(via
		(at 61.35 90.388)
		(size 0.5)
		(drill 0.2)
		(layers "F.Cu" "B.Cu")
		(net 1)
	)
	(via
		(at 61.35 88.372466)
		(size 0.5)
		(drill 0.2)
		(layers "F.Cu" "B.Cu")
		(net 1)
	)
	(via
		(at 61.35 86.356933)
		(size 0.5)
		(drill 0.2)
		(layers "F.Cu" "B.Cu")
		(net 1)
	)
	(via
		(at 61.35 84.3414)
		(size 0.5)
		(drill 0.2)
		(layers "F.Cu" "B.Cu")
		(net 1)
	)
	(via
		(at 61.35 82.325866)
		(size 0.5)
		(drill 0.2)
		(layers "F.Cu" "B.Cu")
		(net 1)
	)
	(via
		(at 61.35 80.310333)
		(size 0.5)
		(drill 0.2)
		(layers "F.Cu" "B.Cu")
		(net 1)
	)
	(via
		(at 61.35 78.2948)
		(size 0.5)
		(drill 0.2)
		(layers "F.Cu" "B.Cu")
		(net 1)
	)
	(via
		(at 61.35 76.279266)
		(size 0.5)
		(drill 0.2)
		(layers "F.Cu" "B.Cu")
		(net 1)
	)
	(via
		(at 61.35 74.263733)
		(size 0.5)
		(drill 0.2)
		(layers "F.Cu" "B.Cu")
		(net 1)
	)
	(via
		(at 61.35 72.2482)
		(size 0.5)
		(drill 0.2)
		(layers "F.Cu" "B.Cu")
		(net 1)
	)
	(via
		(at 61.35 70.232666)
		(size 0.5)
		(drill 0.2)
		(layers "F.Cu" "B.Cu")
		(net 1)
	)
	(via
		(at 61.35 68.217133)
		(size 0.5)
		(drill 0.2)
		(layers "F.Cu" "B.Cu")
		(net 1)
	)
	(via
		(at 61.35 66.2016)
		(size 0.5)
		(drill 0.2)
		(layers "F.Cu" "B.Cu")
		(net 1)
	)
	(via
		(at 61.35 64.186066)
		(size 0.5)
		(drill 0.2)
		(layers "F.Cu" "B.Cu")
		(net 1)
	)
	(via
		(at 61.35 62.170533)
		(size 0.5)
		(drill 0.2)
		(layers "F.Cu" "B.Cu")
		(net 1)
	)
	(via
		(at 74.307107 172.197893)
		(size 0.5)
		(drill 0.2)
		(layers "F.Cu" "B.Cu")
		(net 1)
	)
	(via
		(at 69.700123 178.053964)
		(size 0.5)
		(drill 0.2)
		(layers "F.Cu" "B.Cu")
		(net 1)
	)
	(via
		(at 61.979433 178.10499)
		(size 0.5)
		(drill 0.2)
		(layers "F.Cu" "B.Cu")
		(net 1)
	)
	(via
		(at 61.35 177.055934)
		(size 0.5)
		(drill 0.2)
		(layers "F.Cu" "B.Cu")
		(net 1)
	)
	(via
		(at 65.1 60.155)
		(size 0.5)
		(drill 0.2)
		(layers "F.Cu" "B.Cu")
		(net 1)
	)
	(via
		(at 63.2 60.155)
		(size 0.5)
		(drill 0.2)
		(layers "F.Cu" "B.Cu")
		(net 1)
	)
	(via
		(at 114.975 76.18191)
		(size 0.5)
		(drill 0.2)
		(layers "F.Cu" "B.Cu")
		(free yes)
		(net 1)
	)
	(via
		(at 114.975 73.983821)
		(size 0.5)
		(drill 0.2)
		(layers "F.Cu" "B.Cu")
		(free yes)
		(net 1)
	)
	(via
		(at 114.975 71.785732)
		(size 0.5)
		(drill 0.2)
		(layers "F.Cu" "B.Cu")
		(net 1)
	)
	(via
		(at 114.95501 67.235597)
		(size 0.5)
		(drill 0.2)
		(layers "F.Cu" "B.Cu")
		(net 1)
	)
	(via
		(at 114.95501 64.875398)
		(size 0.5)
		(drill 0.2)
		(layers "F.Cu" "B.Cu")
		(net 1)
	)
	(via
		(at 114.95501 62.515199)
		(size 0.5)
		(drill 0.2)
		(layers "F.Cu" "B.Cu")
		(net 1)
	)
	(via
		(at 117.073446 60.155)
		(size 0.5)
		(drill 0.2)
		(layers "F.Cu" "B.Cu")
		(free yes)
		(net 1)
	)
	(via
		(at 119.191883 60.155)
		(size 0.5)
		(drill 0.2)
		(layers "F.Cu" "B.Cu")
		(net 1)
	)
	(via
		(at 121.31032 60.155)
		(size 0.5)
		(drill 0.2)
		(layers "F.Cu" "B.Cu")
		(net 1)
	)
	(via
		(at 123.428757 60.155)
		(size 0.5)
		(drill 0.2)
		(layers "F.Cu" "B.Cu")
		(net 1)
	)
	(via
		(at 126.375 60.155)
		(size 0.5)
		(drill 0.2)
		(layers "F.Cu" "B.Cu")
		(net 1)
	)
	(via
		(at 131.902505 60.155)
		(size 0.5)
		(drill 0.2)
		(layers "F.Cu" "B.Cu")
		(net 1)
	)
	(via
		(at 134.020941 60.155)
		(size 0.5)
		(drill 0.2)
		(layers "F.Cu" "B.Cu")
		(net 1)
	)
	(via
		(at 136.139378 60.155)
		(size 0.5)
		(drill 0.2)
		(layers "F.Cu" "B.Cu")
		(net 1)
	)
	(via
		(at 137.782815 60.155)
		(size 0.5)
		(drill 0.2)
		(layers "F.Cu" "B.Cu")
		(net 1)
	)
	(via
		(at 139.901252 60.155)
		(size 0.5)
		(drill 0.2)
		(layers "F.Cu" "B.Cu")
		(net 1)
	)
	(via
		(at 142.019689 60.155)
		(size 0.5)
		(drill 0.2)
		(layers "F.Cu" "B.Cu")
		(net 1)
	)
	(via
		(at 144.613126 60.155)
		(size 0.5)
		(drill 0.2)
		(layers "F.Cu" "B.Cu")
		(net 1)
	)
	(via
		(at 146.731563 60.155)
		(size 0.5)
		(drill 0.2)
		(layers "F.Cu" "B.Cu")
		(net 1)
	)
	(via
		(at 148.85 62.17108)
		(size 0.5)
		(drill 0.2)
		(layers "F.Cu" "B.Cu")
		(net 1)
	)
	(via
		(at 148.85 64.18716)
		(size 0.5)
		(drill 0.2)
		(layers "F.Cu" "B.Cu")
		(net 1)
	)
	(via
		(at 148.85 66.203241)
		(size 0.5)
		(drill 0.2)
		(layers "F.Cu" "B.Cu")
		(free yes)
		(net 1)
	)
	(via
		(at 148.85 68.219321)
		(size 0.5)
		(drill 0.2)
		(layers "F.Cu" "B.Cu")
		(net 1)
	)
	(via
		(at 148.85 70.235402)
		(size 0.5)
		(drill 0.2)
		(layers "F.Cu" "B.Cu")
		(net 1)
	)
	(via
		(at 148.85 72.251482)
		(size 0.5)
		(drill 0.2)
		(layers "F.Cu" "B.Cu")
		(net 1)
	)
	(via
		(at 148.85 74.267562)
		(size 0.5)
		(drill 0.2)
		(layers "F.Cu" "B.Cu")
		(net 1)
	)
	(via
		(at 148.85 76.283643)
		(size 0.5)
		(drill 0.2)
		(layers "F.Cu" "B.Cu")
		(net 1)
	)
	(via
		(at 148.85 78.299723)
		(size 0.5)
		(drill 0.2)
		(layers "F.Cu" "B.Cu")
		(net 1)
	)
	(via
		(at 148.85 80.315804)
		(size 0.5)
		(drill 0.2)
		(layers "F.Cu" "B.Cu")
		(net 1)
	)
	(via
		(at 148.85 82.331884)
		(size 0.5)
		(drill 0.2)
		(layers "F.Cu" "B.Cu")
		(net 1)
	)
	(via
		(at 148.85 84.347964)
		(size 0.5)
		(drill 0.2)
		(layers "F.Cu" "B.Cu")
		(net 1)
	)
	(via
		(at 148.85 86.364045)
		(size 0.5)
		(drill 0.2)
		(layers "F.Cu" "B.Cu")
		(net 1)
	)
	(via
		(at 148.85 88.380125)
		(size 0.5)
		(drill 0.2)
		(layers "F.Cu" "B.Cu")
		(net 1)
	)
	(via
		(at 148.85 90.396206)
		(size 0.5)
		(drill 0.2)
		(layers "F.Cu" "B.Cu")
		(net 1)
	)
	(via
		(at 148.85 92.412286)
		(size 0.5)
		(drill 0.2)
		(layers "F.Cu" "B.Cu")
		(net 1)
	)
	(via
		(at 148.85 94.428367)
		(size 0.5)
		(drill 0.2)
		(layers "F.Cu" "B.Cu")
		(net 1)
	)
	(via
		(at 148.85 96.444447)
		(size 0.5)
		(drill 0.2)
		(layers "F.Cu" "B.Cu")
		(net 1)
	)
	(via
		(at 148.85 98.460527)
		(size 0.5)
		(drill 0.2)
		(layers "F.Cu" "B.Cu")
		(net 1)
	)
	(via
		(at 148.85 100.476608)
		(size 0.5)
		(drill 0.2)
		(layers "F.Cu" "B.Cu")
		(net 1)
	)
	(via
		(at 148.85 102.492688)
		(size 0.5)
		(drill 0.2)
		(layers "F.Cu" "B.Cu")
		(net 1)
	)
	(via
		(at 148.85 104.508769)
		(size 0.5)
		(drill 0.2)
		(layers "F.Cu" "B.Cu")
		(net 1)
	)
	(via
		(at 148.85 106.524849)
		(size 0.5)
		(drill 0.2)
		(layers "F.Cu" "B.Cu")
		(net 1)
	)
	(via
		(at 148.85 108.540929)
		(size 0.5)
		(drill 0.2)
		(layers "F.Cu" "B.Cu")
		(net 1)
	)
	(via
		(at 148.85 110.55701)
		(size 0.5)
		(drill 0.2)
		(layers "F.Cu" "B.Cu")
		(net 1)
	)
	(via
		(at 148.85 112.57309)
		(size 0.5)
		(drill 0.2)
		(layers "F.Cu" "B.Cu")
		(net 1)
	)
	(via
		(at 148.85 114.589171)
		(size 0.5)
		(drill 0.2)
		(layers "F.Cu" "B.Cu")
		(net 1)
	)
	(via
		(at 148.85 116.605251)
		(size 0.5)
		(drill 0.2)
		(layers "F.Cu" "B.Cu")
		(net 1)
	)
	(via
		(at 148.85 118.621332)
		(size 0.5)
		(drill 0.2)
		(layers "F.Cu" "B.Cu")
		(net 1)
	)
	(via
		(at 148.85 120.637412)
		(size 0.5)
		(drill 0.2)
		(layers "F.Cu" "B.Cu")
		(net 1)
	)
	(via
		(at 148.85 122.653492)
		(size 0.5)
		(drill 0.2)
		(layers "F.Cu" "B.Cu")
		(net 1)
	)
	(via
		(at 148.85 124.669573)
		(size 0.5)
		(drill 0.2)
		(layers "F.Cu" "B.Cu")
		(net 1)
	)
	(via
		(at 148.85 126.685653)
		(size 0.5)
		(drill 0.2)
		(layers "F.Cu" "B.Cu")
		(net 1)
	)
	(via
		(at 148.85 128.701734)
		(size 0.5)
		(drill 0.2)
		(layers "F.Cu" "B.Cu")
		(net 1)
	)
	(via
		(at 148.85 130.717814)
		(size 0.5)
		(drill 0.2)
		(layers "F.Cu" "B.Cu")
		(net 1)
	)
	(via
		(at 148.85 132.733894)
		(size 0.5)
		(drill 0.2)
		(layers "F.Cu" "B.Cu")
		(net 1)
	)
	(via
		(at 148.85 134.749975)
		(size 0.5)
		(drill 0.2)
		(layers "F.Cu" "B.Cu")
		(net 1)
	)
	(via
		(at 148.85 136.766055)
		(size 0.5)
		(drill 0.2)
		(layers "F.Cu" "B.Cu")
		(net 1)
	)
	(via
		(at 148.85 138.782136)
		(size 0.5)
		(drill 0.2)
		(layers "F.Cu" "B.Cu")
		(net 1)
	)
	(via
		(at 148.85 140.798216)
		(size 0.5)
		(drill 0.2)
		(layers "F.Cu" "B.Cu")
		(net 1)
	)
	(via
		(at 148.85 142.814296)
		(size 0.5)
		(drill 0.2)
		(layers "F.Cu" "B.Cu")
		(net 1)
	)
	(via
		(at 148.85 144.830377)
		(size 0.5)
		(drill 0.2)
		(layers "F.Cu" "B.Cu")
		(net 1)
	)
	(via
		(at 148.85 146.846457)
		(size 0.5)
		(drill 0.2)
		(layers "F.Cu" "B.Cu")
		(net 1)
	)
	(via
		(at 148.85 148.862538)
		(size 0.5)
		(drill 0.2)
		(layers "F.Cu" "B.Cu")
		(net 1)
	)
	(via
		(at 148.85 150.878618)
		(size 0.5)
		(drill 0.2)
		(layers "F.Cu" "B.Cu")
		(net 1)
	)
	(via
		(at 148.85 152.894699)
		(size 0.5)
		(drill 0.2)
		(layers "F.Cu" "B.Cu")
		(net 1)
	)
	(via
		(at 148.85 154.910779)
		(size 0.5)
		(drill 0.2)
		(layers "F.Cu" "B.Cu")
		(net 1)
	)
	(via
		(at 148.85 156.926859)
		(size 0.5)
		(drill 0.2)
		(layers "F.Cu" "B.Cu")
		(net 1)
	)
	(via
		(at 148.85 158.94294)
		(size 0.5)
		(drill 0.2)
		(layers "F.Cu" "B.Cu")
		(net 1)
	)
	(via
		(at 148.85 160.95902)
		(size 0.5)
		(drill 0.2)
		(layers "F.Cu" "B.Cu")
		(net 1)
	)
	(via
		(at 148.85 162.975101)
		(size 0.5)
		(drill 0.2)
		(layers "F.Cu" "B.Cu")
		(net 1)
	)
	(via
		(at 148.85 164.991181)
		(size 0.5)
		(drill 0.2)
		(layers "F.Cu" "B.Cu")
		(net 1)
	)
	(via
		(at 148.85 167.007261)
		(size 0.5)
		(drill 0.2)
		(layers "F.Cu" "B.Cu")
		(net 1)
	)
	(via
		(at 148.85 169.023342)
		(size 0.5)
		(drill 0.2)
		(layers "F.Cu" "B.Cu")
		(net 1)
	)
	(via
		(at 148.85 171.039422)
		(size 0.5)
		(drill 0.2)
		(layers "F.Cu" "B.Cu")
		(net 1)
	)
	(via
		(at 148.85 173.055503)
		(size 0.5)
		(drill 0.2)
		(layers "F.Cu" "B.Cu")
		(net 1)
	)
	(via
		(at 148.85 175.071583)
		(size 0.5)
		(drill 0.2)
		(layers "F.Cu" "B.Cu")
		(net 1)
	)
	(via
		(at 145.765048 178.10499)
		(size 0.5)
		(drill 0.2)
		(layers "F.Cu" "B.Cu")
		(net 1)
	)
	(via
		(at 143.239626 178.10499)
		(size 0.5)
		(drill 0.2)
		(layers "F.Cu" "B.Cu")
		(net 1)
	)
	(via
		(at 140.6 175.741465)
		(size 0.5)
		(drill 0.2)
		(layers "F.Cu" "B.Cu")
		(net 1)
	)
	(via
		(at 140.6 173.492145)
		(size 0.5)
		(drill 0.2)
		(layers "F.Cu" "B.Cu")
		(net 1)
	)
	(via
		(at 139.631781 171.651985)
		(size 0.5)
		(drill 0.2)
		(layers "F.Cu" "B.Cu")
		(net 1)
	)
	(via
		(at 137.389824 171.589891)
		(size 0.5)
		(drill 0.2)
		(layers "F.Cu" "B.Cu")
		(net 1)
	)
	(via
		(at 114.95501 69.595796)
		(size 0.5)
		(drill 0.2)
		(layers "F.Cu" "B.Cu")
		(net 1)
	)
	(via
		(at 114.95501 60.155)
		(size 0.5)
		(drill 0.2)
		(layers "F.Cu" "B.Cu")
		(net 1)
	)
	(via
		(at 148.85 60.155)
		(size 0.5)
		(drill 0.2)
		(layers "F.Cu" "B.Cu")
		(net 1)
	)
	(via
		(at 148.85 177.087664)
		(size 0.5)
		(drill 0.2)
		(layers "F.Cu" "B.Cu")
		(net 1)
	)
	(via
		(at 148.29047 178.10499)
		(size 0.5)
		(drill 0.2)
		(layers "F.Cu" "B.Cu")
		(net 1)
	)
	(via
		(at 140.6 177.990786)
		(size 0.5)
		(drill 0.2)
		(layers "F.Cu" "B.Cu")
		(net 1)
	)
	(via
		(at 135.707634 172.806953)
		(size 0.5)
		(drill 0.2)
		(layers "F.Cu" "B.Cu")
		(net 1)
	)
	(via
		(at 72.372364 171.584299)
		(size 0.5)
		(drill 0.2)
		(layers "F.Cu" "B.Cu")
		(net 1)
	)
	(via
		(at 70.280922 171.815739)
		(size 0.5)
		(drill 0.2)
		(layers "F.Cu" "B.Cu")
		(net 1)
	)
	(via
		(at 69.700123 173.762218)
		(size 0.5)
		(drill 0.2)
		(layers "F.Cu" "B.Cu")
		(net 1)
	)
	(via
		(at 69.700123 175.908091)
		(size 0.5)
		(drill 0.2)
		(layers "F.Cu" "B.Cu")
		(net 1)
	)
	(via
		(at 67.096794 178.10499)
		(size 0.5)
		(drill 0.2)
		(layers "F.Cu" "B.Cu")
		(net 1)
	)
	(via
		(at 64.538113 178.10499)
		(size 0.5)
		(drill 0.2)
		(layers "F.Cu" "B.Cu")
		(net 1)
	)
	(via
		(at 61.35 175.0404)
		(size 0.5)
		(drill 0.2)
		(layers "F.Cu" "B.Cu")
		(net 1)
	)
	(via
		(at 61.35 173.024867)
		(size 0.5)
		(drill 0.2)
		(layers "F.Cu" "B.Cu")
		(net 1)
	)
	(via
		(at 61.35 171.009333)
		(size 0.5)
		(drill 0.2)
		(layers "F.Cu" "B.Cu")
		(net 1)
	)
	(via
		(at 61.35 168.9938)
		(size 0.5)
		(drill 0.2)
		(layers "F.Cu" "B.Cu")
		(net 1)
	)
	(via
		(at 61.35 166.978267)
		(size 0.5)
		(drill 0.2)
		(layers "F.Cu" "B.Cu")
		(net 1)
	)
	(via
		(at 61.35 164.962733)
		(size 0.5)
		(drill 0.2)
		(layers "F.Cu" "B.Cu")
		(net 1)
	)
	(via
		(at 61.35 162.9472)
		(size 0.5)
		(drill 0.2)
		(layers "F.Cu" "B.Cu")
		(net 1)
	)
	(via
		(at 61.35 160.931667)
		(size 0.5)
		(drill 0.2)
		(layers "F.Cu" "B.Cu")
		(net 1)
	)
	(via
		(at 61.35 158.916133)
		(size 0.5)
		(drill 0.2)
		(layers "F.Cu" "B.Cu")
		(net 1)
	)
	(via
		(at 61.35 156.9006)
		(size 0.5)
		(drill 0.2)
		(layers "F.Cu" "B.Cu")
		(net 1)
	)
	(via
		(at 61.35 154.885067)
		(size 0.5)
		(drill 0.2)
		(layers "F.Cu" "B.Cu")
		(net 1)
	)
	(via
		(at 61.35 152.869533)
		(size 0.5)
		(drill 0.2)
		(layers "F.Cu" "B.Cu")
		(net 1)
	)
	(via
		(at 61.35 150.854)
		(size 0.5)
		(drill 0.2)
		(layers "F.Cu" "B.Cu")
		(net 1)
	)
	(via blind
		(at 104.275 120.675)
		(size 0.5)
		(drill 0.2)
		(layers "F.Cu" "In1.Cu")
		(net 1)
	)
	(via
		(at 114.975 80.58191)
		(size 0.5)
		(drill 0.2)
		(layers "F.Cu" "B.Cu")
		(net 1)
	)
	(via
		(at 114.975 78.383821)
		(size 0.5)
		(drill 0.2)
		(layers "F.Cu" "B.Cu")
		(net 1)
	)
	(via
		(at 114.975 82.78)
		(size 0.5)
		(drill 0.2)
		(layers "F.Cu" "B.Cu")
		(net 1)
	)
	(via
		(at 121.35 76.98)
		(size 0.5)
		(drill 0.2)
		(layers "F.Cu" "B.Cu")
		(net 1)
	)
	(via blind
		(at 104.275 123.675)
		(size 0.5)
		(drill 0.2)
		(layers "F.Cu" "In1.Cu")
		(net 1)
	)
	(via
		(at 125.945 112.285)
		(size 0.5)
		(drill 0.2)
		(layers "F.Cu" "B.Cu")
		(net 1)
	)
	(via
		(at 82.14 60.115)
		(size 0.5)
		(drill 0.2)
		(layers "F.Cu" "B.Cu")
		(net 1)
	)
	(via
		(at 61.348437 60.15)
		(size 0.5)
		(drill 0.2)
		(layers "F.Cu" "B.Cu")
		(net 1)
	)
	(via
		(at 67.1 60.155)
		(size 0.5)
		(drill 0.2)
		(layers "F.Cu" "B.Cu")
		(net 1)
	)
	(via
		(at 69.1 60.155)
		(size 0.5)
		(drill 0.2)
		(layers "F.Cu" "B.Cu")
		(net 1)
	)
	(via
		(at 71.1 60.155)
		(size 0.5)
		(drill 0.2)
		(layers "F.Cu" "B.Cu")
		(net 1)
	)
	(via
		(at 73.1 60.155)
		(size 0.5)
		(drill 0.2)
		(layers "F.Cu" "B.Cu")
		(net 1)
	)
	(via
		(at 75.1 60.155)
		(size 0.5)
		(drill 0.2)
		(layers "F.Cu" "B.Cu")
		(net 1)
	)
	(via
		(at 77.1 60.155)
		(size 0.5)
		(drill 0.2)
		(layers "F.Cu" "B.Cu")
		(net 1)
	)
	(via
		(at 84.14 60.115)
		(size 0.5)
		(drill 0.2)
		(layers "F.Cu" "B.Cu")
		(net 1)
	)
	(via
		(at 88.14 60.115)
		(size 0.5)
		(drill 0.2)
		(layers "F.Cu" "B.Cu")
		(net 1)
	)
	(via
		(at 90.14 60.115)
		(size 0.5)
		(drill 0.2)
		(layers "F.Cu" "B.Cu")
		(net 1)
	)
	(via
		(at 94.55 76.13191)
		(size 0.5)
		(drill 0.2)
		(layers "F.Cu" "B.Cu")
		(net 1)
	)
	(via
		(at 94.55 73.933821)
		(size 0.5)
		(drill 0.2)
		(layers "F.Cu" "B.Cu")
		(net 1)
	)
	(via
		(at 94.55 71.735732)
		(size 0.5)
		(drill 0.2)
		(layers "F.Cu" "B.Cu")
		(net 1)
	)
	(via
		(at 94.53001 67.185597)
		(size 0.5)
		(drill 0.2)
		(layers "F.Cu" "B.Cu")
		(net 1)
	)
	(via
		(at 94.53001 64.825398)
		(size 0.5)
		(drill 0.2)
		(layers "F.Cu" "B.Cu")
		(net 1)
	)
	(via
		(at 94.53001 62.465199)
		(size 0.5)
		(drill 0.2)
		(layers "F.Cu" "B.Cu")
		(net 1)
	)
	(via
		(at 94.53001 69.545796)
		(size 0.5)
		(drill 0.2)
		(layers "F.Cu" "B.Cu")
		(net 1)
	)
	(via
		(at 94.53001 60.105)
		(size 0.5)
		(drill 0.2)
		(layers "F.Cu" "B.Cu")
		(net 1)
	)
	(via
		(at 94.55 80.53191)
		(size 0.5)
		(drill 0.2)
		(layers "F.Cu" "B.Cu")
		(net 1)
	)
	(via
		(at 94.55 78.333821)
		(size 0.5)
		(drill 0.2)
		(layers "F.Cu" "B.Cu")
		(net 1)
	)
	(via
		(at 94.55 82.73)
		(size 0.5)
		(drill 0.2)
		(layers "F.Cu" "B.Cu")
		(net 1)
	)
	(via
		(at 120.465 129.615)
		(size 0.5)
		(drill 0.2)
		(layers "F.Cu" "B.Cu")
		(net 1)
	)
	(via
		(at 85.565 166.015)
		(size 0.5)
		(drill 0.2)
		(layers "F.Cu" "B.Cu")
		(net 1)
	)
	(via blind
		(at 107.995 143.255)
		(size 0.5)
		(drill 0.2)
		(layers "F.Cu" "In1.Cu")
		(net 1)
	)
	(via blind
		(at 81.375 163.575)
		(size 0.5)
		(drill 0.2)
		(layers "F.Cu" "In1.Cu")
		(net 1)
	)
	(via blind
		(at 74.565 167.915)
		(size 0.5)
		(drill 0.2)
		(layers "F.Cu" "In1.Cu")
		(net 1)
	)
	(via
		(at 136.35 91.6125)
		(size 0.5)
		(drill 0.2)
		(layers "F.Cu" "B.Cu")
		(net 1)
	)
	(via
		(at 128.075 87.525)
		(size 0.5)
		(drill 0.2)
		(layers "F.Cu" "B.Cu")
		(net 1)
	)
	(via
		(at 115.215 175.265)
		(size 0.5)
		(drill 0.2)
		(layers "F.Cu" "B.Cu")
		(net 1)
	)
	(via
		(at 103.735 89.375)
		(size 0.5)
		(drill 0.2)
		(layers "F.Cu" "B.Cu")
		(net 1)
	)
	(via
		(at 93.275 121.675)
		(size 0.5)
		(drill 0.2)
		(layers "F.Cu" "B.Cu")
		(net 1)
	)
	(via
		(at 94.078521 172.337479)
		(size 0.5)
		(drill 0.2)
		(layers "F.Cu" "B.Cu")
		(net 1)
	)
	(via blind
		(at 96.175 142.875)
		(size 0.5)
		(drill 0.2)
		(layers "F.Cu" "In1.Cu")
		(net 1)
	)
	(via blind
		(at 92.275 119.675)
		(size 0.5)
		(drill 0.2)
		(layers "F.Cu" "In1.Cu")
		(net 1)
	)
	(via
		(at 115.1 104.9)
		(size 0.5)
		(drill 0.2)
		(layers "F.Cu" "B.Cu")
		(net 1)
	)
	(via
		(at 117 138.6)
		(size 0.5)
		(drill 0.2)
		(layers "F.Cu" "B.Cu")
		(net 1)
	)
	(via
		(at 132.45 87.6125)
		(size 0.5)
		(drill 0.2)
		(layers "F.Cu" "B.Cu")
		(net 1)
	)
	(via blind
		(at 125.75 166.05)
		(size 0.5)
		(drill 0.2)
		(layers "F.Cu" "In1.Cu")
		(net 1)
	)
	(via
		(at 86.635 109.945)
		(size 0.5)
		(drill 0.2)
		(layers "F.Cu" "B.Cu")
		(net 1)
	)
	(via
		(at 101.885 98.065)
		(size 0.5)
		(drill 0.2)
		(layers "F.Cu" "B.Cu")
		(net 1)
	)
	(via
		(at 105.275 113.675)
		(size 0.5)
		(drill 0.2)
		(layers "F.Cu" "B.Cu")
		(net 1)
	)
	(via
		(at 72.639 80.087)
		(size 0.5)
		(drill 0.2)
		(layers "F.Cu" "B.Cu")
		(net 1)
	)
	(via
		(at 126.075 134.615)
		(size 0.5)
		(drill 0.2)
		(layers "F.Cu" "B.Cu")
		(net 1)
	)
	(via
		(at 70.85 131.75)
		(size 0.5)
		(drill 0.2)
		(layers "F.Cu" "B.Cu")
		(net 1)
	)
	(via blind
		(at 102.075 158.375)
		(size 0.5)
		(drill 0.2)
		(layers "F.Cu" "In1.Cu")
		(net 1)
	)
	(via
		(at 90.5 154.3)
		(size 0.5)
		(drill 0.2)
		(layers "F.Cu" "B.Cu")
		(net 1)
	)
	(via
		(at 140.774 132.114)
		(size 0.5)
		(drill 0.2)
		(layers "F.Cu" "B.Cu")
		(net 1)
	)
	(via blind
		(at 100.075 162.375)
		(size 0.5)
		(drill 0.2)
		(layers "F.Cu" "In1.Cu")
		(net 1)
	)
	(via
		(at 91.402 77.046)
		(size 0.5)
		(drill 0.2)
		(layers "F.Cu" "B.Cu")
		(net 1)
	)
	(via blind
		(at 93.275 127.675)
		(size 0.5)
		(drill 0.2)
		(layers "F.Cu" "In1.Cu")
		(net 1)
	)
	(via
		(at 136.375 165.975)
		(size 0.5)
		(drill 0.2)
		(layers "F.Cu" "B.Cu")
		(net 1)
	)
	(via
		(at 99.275 126.675)
		(size 0.5)
		(drill 0.2)
		(layers "F.Cu" "B.Cu")
		(net 1)
	)
	(via
		(at 121.375 73.005)
		(size 0.5)
		(drill 0.2)
		(layers "F.Cu" "B.Cu")
		(net 1)
	)
	(via
		(at 98.57 88.305)
		(size 0.5)
		(drill 0.2)
		(layers "F.Cu" "B.Cu")
		(net 1)
	)
	(via
		(at 117.7 123.6)
		(size 0.5)
		(drill 0.2)
		(layers "F.Cu" "B.Cu")
		(net 1)
	)
	(via
		(at 136 93.5)
		(size 0.5)
		(drill 0.2)
		(layers "F.Cu" "B.Cu")
		(net 1)
	)
	(via
		(at 69.3299 141.4399)
		(size 0.5)
		(drill 0.2)
		(layers "F.Cu" "B.Cu")
		(net 1)
	)
	(via
		(at 116.1 129.7)
		(size 0.5)
		(drill 0.2)
		(layers "F.Cu" "B.Cu")
		(net 1)
	)
	(via
		(at 121.375 69.055)
		(size 0.5)
		(drill 0.2)
		(layers "F.Cu" "B.Cu")
		(net 1)
	)
	(via
		(at 117 135.1)
		(size 0.5)
		(drill 0.2)
		(layers "F.Cu" "B.Cu")
		(net 1)
	)
	(via
		(at 118.9 123.6)
		(size 0.5)
		(drill 0.2)
		(layers "F.Cu" "B.Cu")
		(net 1)
	)
	(via
		(at 125.315 128.015)
		(size 0.5)
		(drill 0.2)
		(layers "F.Cu" "B.Cu")
		(net 1)
	)
	(via
		(at 130.615 126.715)
		(size 0.5)
		(drill 0.2)
		(layers "F.Cu" "B.Cu")
		(net 1)
	)
	(via
		(at 115.1 106.1)
		(size 0.5)
		(drill 0.2)
		(layers "F.Cu" "B.Cu")
		(net 1)
	)
	(via
		(at 116.775 163.575)
		(size 0.5)
		(drill 0.2)
		(layers "F.Cu" "B.Cu")
		(net 1)
	)
	(via
		(at 125.957 128.447)
		(size 0.5)
		(drill 0.2)
		(layers "F.Cu" "B.Cu")
		(net 1)
	)
	(via blind
		(at 106.985 143.255)
		(size 0.5)
		(drill 0.2)
		(layers "F.Cu" "In1.Cu")
		(net 1)
	)
	(via
		(at 124.015 112.265)
		(size 0.5)
		(drill 0.2)
		(layers "F.Cu" "B.Cu")
		(net 1)
	)
	(via
		(at 133.775 126.375)
		(size 0.5)
		(drill 0.2)
		(layers "F.Cu" "B.Cu")
		(net 1)
	)
	(via blind
		(at 128.75 166.05)
		(size 0.5)
		(drill 0.2)
		(layers "F.Cu" "In1.Cu")
		(net 1)
	)
	(via
		(at 68.139 89.627)
		(size 0.5)
		(drill 0.2)
		(layers "F.Cu" "B.Cu")
		(net 1)
	)
	(via
		(at 104.315 106.365)
		(size 0.5)
		(drill 0.2)
		(layers "F.Cu" "B.Cu")
		(net 1)
	)
	(via
		(at 138.774 125.504)
		(size 0.5)
		(drill 0.2)
		(layers "F.Cu" "B.Cu")
		(net 1)
	)
	(via
		(at 83.74 166.815)
		(size 0.5)
		(drill 0.2)
		(layers "F.Cu" "B.Cu")
		(net 1)
	)
	(via
		(at 115.1 101.4)
		(size 0.5)
		(drill 0.2)
		(layers "F.Cu" "B.Cu")
		(net 1)
	)
	(via blind
		(at 97.275 123.675)
		(size 0.5)
		(drill 0.2)
		(layers "F.Cu" "In1.Cu")
		(net 1)
	)
	(via blind
		(at 94.275 126.675)
		(size 0.5)
		(drill 0.2)
		(layers "F.Cu" "In1.Cu")
		(net 1)
	)
	(via
		(at 125.949 127.479)
		(size 0.5)
		(drill 0.2)
		(layers "F.Cu" "B.Cu")
		(net 1)
	)
	(via
		(at 91.3 135.7)
		(size 0.5)
		(drill 0.2)
		(layers "F.Cu" "B.Cu")
		(net 1)
	)
	(via
		(at 108.93 91.99)
		(size 0.5)
		(drill 0.2)
		(layers "F.Cu" "B.Cu")
		(net 1)
	)
	(via blind
		(at 97.775 138.775)
		(size 0.5)
		(drill 0.2)
		(layers "F.Cu" "In1.Cu")
		(net 1)
	)
	(via
		(at 136.45 88.0125)
		(size 0.5)
		(drill 0.2)
		(layers "F.Cu" "B.Cu")
		(net 1)
	)
	(via
		(at 90.137667 122.712667)
		(size 0.5)
		(drill 0.2)
		(layers "F.Cu" "B.Cu")
		(net 1)
	)
	(via blind
		(at 102.575 142.875)
		(size 0.5)
		(drill 0.2)
		(layers "F.Cu" "In1.Cu")
		(net 1)
	)
	(via blind
		(at 101.275 122.675)
		(size 0.5)
		(drill 0.2)
		(layers "F.Cu" "In1.Cu")
		(net 1)
	)
	(via
		(at 115.1 99)
		(size 0.5)
		(drill 0.2)
		(layers "F.Cu" "B.Cu")
		(net 1)
	)
	(via blind
		(at 90.275 128.675)
		(size 0.5)
		(drill 0.2)
		(layers "F.Cu" "In1.Cu")
		(net 1)
	)
	(via
		(at 103.275 122.675)
		(size 0.5)
		(drill 0.2)
		(layers "F.Cu" "B.Cu")
		(net 1)
	)
	(via
		(at 94.4 95.7)
		(size 0.5)
		(drill 0.2)
		(layers "F.Cu" "B.Cu")
		(net 1)
	)
	(via
		(at 133.075 121.55)
		(size 0.5)
		(drill 0.2)
		(layers "F.Cu" "B.Cu")
		(net 1)
	)
	(via
		(at 130.1 60.305)
		(size 0.5)
		(drill 0.2)
		(layers "F.Cu" "B.Cu")
		(net 1)
	)
	(via
		(at 133 95)
		(size 0.5)
		(drill 0.2)
		(layers "F.Cu" "B.Cu")
		(net 1)
	)
	(via blind
		(at 124.25 166.05)
		(size 0.5)
		(drill 0.2)
		(layers "F.Cu" "In1.Cu")
		(net 1)
	)
	(via
		(at 111.83 92.75)
		(size 0.5)
		(drill 0.2)
		(layers "F.Cu" "B.Cu")
		(net 1)
	)
	(via
		(at 135.4 85.1)
		(size 0.5)
		(drill 0.2)
		(layers "F.Cu" "B.Cu")
		(net 1)
	)
	(via
		(at 117.275 163.175)
		(size 0.5)
		(drill 0.2)
		(layers "F.Cu" "B.Cu")
		(net 1)
	)
	(via
		(at 64.605 118.865)
		(size 0.5)
		(drill 0.2)
		(layers "F.Cu" "B.Cu")
		(net 1)
	)
	(via
		(at 129.15 95.5125)
		(size 0.5)
		(drill 0.2)
		(layers "F.Cu" "B.Cu")
		(net 1)
	)
	(via
		(at 91.402 78.046)
		(size 0.5)
		(drill 0.2)
		(layers "F.Cu" "B.Cu")
		(net 1)
	)
	(via
		(at 115.695 162.075)
		(size 0.5)
		(drill 0.2)
		(layers "F.Cu" "B.Cu")
		(net 1)
	)
	(via
		(at 89.892 100.386)
		(size 0.5)
		(drill 0.2)
		(layers "F.Cu" "B.Cu")
		(net 1)
	)
	(via
		(at 91.275 125.69001)
		(size 0.5)
		(drill 0.2)
		(layers "F.Cu" "B.Cu")
		(net 1)
	)
	(via blind
		(at 106.275 121.675)
		(size 0.5)
		(drill 0.2)
		(layers "F.Cu" "In1.Cu")
		(net 1)
	)
	(via blind
		(at 95.374 151.075)
		(size 0.5)
		(drill 0.2)
		(layers "F.Cu" "In1.Cu")
		(net 1)
	)
	(via
		(at 142.45 91.7125)
		(size 0.5)
		(drill 0.2)
		(layers "F.Cu" "B.Cu")
		(net 1)
	)
	(via
		(at 124.009 126.615)
		(size 0.5)
		(drill 0.2)
		(layers "F.Cu" "B.Cu")
		(net 1)
	)
	(via
		(at 97.275 109.685009)
		(size 0.5)
		(drill 0.2)
		(layers "F.Cu" "B.Cu")
		(net 1)
	)
	(via blind
		(at 91.275 128.675)
		(size 0.5)
		(drill 0.2)
		(layers "F.Cu" "In1.Cu")
		(net 1)
	)
	(via blind
		(at 96.275 121.675)
		(size 0.5)
		(drill 0.2)
		(layers "F.Cu" "In1.Cu")
		(net 1)
	)
	(via
		(at 73.559 84.377)
		(size 0.5)
		(drill 0.2)
		(layers "F.Cu" "B.Cu")
		(net 1)
	)
	(via
		(at 93.275 125.69001)
		(size 0.5)
		(drill 0.2)
		(layers "F.Cu" "B.Cu")
		(net 1)
	)
	(via blind
		(at 99.675 153.575)
		(size 0.5)
		(drill 0.2)
		(layers "F.Cu" "In1.Cu")
		(net 1)
	)
	(via
		(at 133.210588 87.551912)
		(size 0.5)
		(drill 0.2)
		(layers "F.Cu" "B.Cu")
		(net 1)
	)
	(via blind
		(at 110.275 116.675)
		(size 0.5)
		(drill 0.2)
		(layers "F.Cu" "In1.Cu")
		(net 1)
	)
	(via
		(at 90.402 86.716)
		(size 0.5)
		(drill 0.2)
		(layers "F.Cu" "B.Cu")
		(net 1)
	)
	(via
		(at 102.275 121.675)
		(size 0.5)
		(drill 0.2)
		(layers "F.Cu" "B.Cu")
		(net 1)
	)
	(via
		(at 145.54 136.94)
		(size 0.5)
		(drill 0.2)
		(layers "F.Cu" "B.Cu")
		(net 1)
	)
	(via
		(at 64.229 93.457)
		(size 0.5)
		(drill 0.2)
		(layers "F.Cu" "B.Cu")
		(net 1)
	)
	(via blind
		(at 78.09 175.745)
		(size 0.5)
		(drill 0.2)
		(layers "F.Cu" "In1.Cu")
		(net 1)
	)
	(via
		(at 110.275 118.675)
		(size 0.5)
		(drill 0.2)
		(layers "F.Cu" "B.Cu")
		(net 1)
	)
	(via
		(at 82.175 175.305)
		(size 0.5)
		(drill 0.2)
		(layers "F.Cu" "B.Cu")
		(net 1)
	)
	(via blind
		(at 101.775 138.775)
		(size 0.5)
		(drill 0.2)
		(layers "F.Cu" "In1.Cu")
		(net 1)
	)
	(via blind
		(at 94.275 119.675)
		(size 0.5)
		(drill 0.2)
		(layers "F.Cu" "In1.Cu")
		(net 1)
	)
	(via
		(at 117.1 131.7)
		(size 0.5)
		(drill 0.2)
		(layers "F.Cu" "B.Cu")
		(net 1)
	)
	(via
		(at 81.919 82.727)
		(size 0.5)
		(drill 0.2)
		(layers "F.Cu" "B.Cu")
		(net 1)
	)
	(via blind
		(at 91.775 138.775)
		(size 0.5)
		(drill 0.2)
		(layers "F.Cu" "In1.Cu")
		(net 1)
	)
	(via
		(at 93.7 95.7)
		(size 0.5)
		(drill 0.2)
		(layers "F.Cu" "B.Cu")
		(net 1)
	)
	(via blind
		(at 100.97399 151.075)
		(size 0.5)
		(drill 0.2)
		(layers "F.Cu" "In1.Cu")
		(net 1)
	)
	(via blind
		(at 107.275 127.675)
		(size 0.5)
		(drill 0.2)
		(layers "F.Cu" "In1.Cu")
		(net 1)
	)
	(via
		(at 142.45 98.0125)
		(size 0.5)
		(drill 0.2)
		(layers "F.Cu" "B.Cu")
		(net 1)
	)
	(via
		(at 139.975 122.475)
		(size 0.5)
		(drill 0.2)
		(layers "F.Cu" "B.Cu")
		(net 1)
	)
	(via
		(at 104.2 96.4)
		(size 0.5)
		(drill 0.2)
		(layers "F.Cu" "B.Cu")
		(net 1)
	)
	(via
		(at 93.7 95)
		(size 0.5)
		(drill 0.2)
		(layers "F.Cu" "B.Cu")
		(net 1)
	)
	(via
		(at 140.2 86.8)
		(size 0.5)
		(drill 0.2)
		(layers "F.Cu" "B.Cu")
		(net 1)
	)
	(via blind
		(at 90.275 124.675)
		(size 0.5)
		(drill 0.2)
		(layers "F.Cu" "In1.Cu")
		(net 1)
	)
	(via
		(at 117 134.4)
		(size 0.5)
		(drill 0.2)
		(layers "F.Cu" "B.Cu")
		(net 1)
	)
	(via
		(at 117 135.8)
		(size 0.5)
		(drill 0.2)
		(layers "F.Cu" "B.Cu")
		(net 1)
	)
	(via blind
		(at 141.774 125.514)
		(size 0.5)
		(drill 0.2)
		(layers "F.Cu" "In5.Cu")
		(net 1)
	)
	(via
		(at 69.2499 151.0499)
		(size 0.5)
		(drill 0.2)
		(layers "F.Cu" "B.Cu")
		(net 1)
	)
	(via
		(at 90.7 136.9)
		(size 0.5)
		(drill 0.2)
		(layers "F.Cu" "B.Cu")
		(net 1)
	)
	(via
		(at 135.784 126.514)
		(size 0.5)
		(drill 0.2)
		(layers "F.Cu" "B.Cu")
		(net 1)
	)
	(via blind
		(at 93.675 138.775)
		(size 0.5)
		(drill 0.2)
		(layers "F.Cu" "In1.Cu")
		(net 1)
	)
	(via
		(at 117 132.3)
		(size 0.5)
		(drill 0.2)
		(layers "F.Cu" "B.Cu")
		(net 1)
	)
	(via blind
		(at 98.275 121.675)
		(size 0.5)
		(drill 0.2)
		(layers "F.Cu" "In1.Cu")
		(net 1)
	)
	(via
		(at 133 93.5)
		(size 0.5)
		(drill 0.2)
		(layers "F.Cu" "B.Cu")
		(net 1)
	)
	(via
		(at 88.892 100.386)
		(size 0.5)
		(drill 0.2)
		(layers "F.Cu" "B.Cu")
		(net 1)
	)
	(via
		(at 140.784 126.514)
		(size 0.5)
		(drill 0.2)
		(layers "F.Cu" "B.Cu")
		(net 1)
	)
	(via
		(at 117 137.2)
		(size 0.5)
		(drill 0.2)
		(layers "F.Cu" "B.Cu")
		(net 1)
	)
	(via
		(at 134.55 102.3125)
		(size 0.5)
		(drill 0.2)
		(layers "F.Cu" "B.Cu")
		(net 1)
	)
	(via
		(at 120.935 134.455)
		(size 0.5)
		(drill 0.2)
		(layers "F.Cu" "B.Cu")
		(net 1)
	)
	(via blind
		(at 102.075 161.075)
		(size 0.5)
		(drill 0.2)
		(layers "F.Cu" "In1.Cu")
		(net 1)
	)
	(via
		(at 101.374 100.414)
		(size 0.5)
		(drill 0.2)
		(layers "F.Cu" "B.Cu")
		(net 1)
	)
	(via
		(at 126.55 69.9125)
		(size 0.5)
		(drill 0.2)
		(layers "F.Cu" "B.Cu")
		(net 1)
	)
	(via
		(at 138.15 98.0125)
		(size 0.5)
		(drill 0.2)
		(layers "F.Cu" "B.Cu")
		(net 1)
	)
	(via
		(at 130.75 64.205)
		(size 0.5)
		(drill 0.2)
		(layers "F.Cu" "B.Cu")
		(net 1)
	)
	(via blind
		(at 96.975 142.875)
		(size 0.5)
		(drill 0.2)
		(layers "F.Cu" "In1.Cu")
		(net 1)
	)
	(via
		(at 95.275 94.015)
		(size 0.5)
		(drill 0.2)
		(layers "F.Cu" "B.Cu")
		(net 1)
	)
	(via
		(at 101.469 96.857)
		(size 0.5)
		(drill 0.2)
		(layers "F.Cu" "B.Cu")
		(net 1)
	)
	(via blind
		(at 98.574 155.875)
		(size 0.5)
		(drill 0.2)
		(layers "F.Cu" "In1.Cu")
		(net 1)
	)
	(via
		(at 97.275 122.675)
		(size 0.5)
		(drill 0.2)
		(layers "F.Cu" "B.Cu")
		(net 1)
	)
	(via
		(at 124.015 110.615)
		(size 0.5)
		(drill 0.2)
		(layers "F.Cu" "B.Cu")
		(net 1)
	)
	(via
		(at 95.275 96.925)
		(size 0.5)
		(drill 0.2)
		(layers "F.Cu" "B.Cu")
		(net 1)
	)
	(via blind
		(at 94.275 118.675)
		(size 0.5)
		(drill 0.2)
		(layers "F.Cu" "In1.Cu")
		(net 1)
	)
	(via
		(at 103.965 107.015)
		(size 0.5)
		(drill 0.2)
		(layers "F.Cu" "B.Cu")
		(net 1)
	)
	(via
		(at 131.85 98.8125)
		(size 0.5)
		(drill 0.2)
		(layers "F.Cu" "B.Cu")
		(net 1)
	)
	(via
		(at 97.515 89.375)
		(size 0.5)
		(drill 0.2)
		(layers "F.Cu" "B.Cu")
		(net 1)
	)
	(via
		(at 115.1 97.7)
		(size 0.5)
		(drill 0.2)
		(layers "F.Cu" "B.Cu")
		(net 1)
	)
	(via
		(at 134.775 166.275)
		(size 0.5)
		(drill 0.2)
		(layers "F.Cu" "B.Cu")
		(net 1)
	)
	(via
		(at 132.35 91.6125)
		(size 0.5)
		(drill 0.2)
		(layers "F.Cu" "B.Cu")
		(net 1)
	)
	(via
		(at 95.728 173.736)
		(size 0.5)
		(drill 0.2)
		(layers "F.Cu" "B.Cu")
		(net 1)
	)
	(via
		(at 104.465 105.115)
		(size 0.5)
		(drill 0.2)
		(layers "F.Cu" "B.Cu")
		(net 1)
	)
	(via
		(at 90.325 116.625)
		(size 0.5)
		(drill 0.2)
		(layers "F.Cu" "B.Cu")
		(net 1)
	)
	(via
		(at 90.402 77.046)
		(size 0.5)
		(drill 0.2)
		(layers "F.Cu" "B.Cu")
		(net 1)
	)
	(via
		(at 133.35 91.6125)
		(size 0.5)
		(drill 0.2)
		(layers "F.Cu" "B.Cu")
		(net 1)
	)
	(via
		(at 98.525 89.375)
		(size 0.5)
		(drill 0.2)
		(layers "F.Cu" "B.Cu")
		(net 1)
	)
	(via
		(at 90.7 136.3)
		(size 0.5)
		(drill 0.2)
		(layers "F.Cu" "B.Cu")
		(net 1)
	)
	(via
		(at 80.275 88.575)
		(size 0.5)
		(drill 0.2)
		(layers "F.Cu" "B.Cu")
		(net 1)
	)
	(via
		(at 95.275 95.925)
		(size 0.5)
		(drill 0.2)
		(layers "F.Cu" "B.Cu")
		(net 1)
	)
	(via
		(at 103.275 115.675)
		(size 0.5)
		(drill 0.2)
		(layers "F.Cu" "B.Cu")
		(net 1)
	)
	(via blind
		(at 99.275 123.675)
		(size 0.5)
		(drill 0.2)
		(layers "F.Cu" "In1.Cu")
		(net 1)
	)
	(via blind
		(at 90.275 120.675)
		(size 0.5)
		(drill 0.2)
		(layers "F.Cu" "In1.Cu")
		(net 1)
	)
	(via
		(at 138.58 169.285)
		(size 0.5)
		(drill 0.2)
		(layers "F.Cu" "B.Cu")
		(free yes)
		(net 1)
	)
	(via
		(at 92.855 163.235)
		(size 0.5)
		(drill 0.2)
		(layers "F.Cu" "B.Cu")
		(net 1)
	)
	(via blind
		(at 93.275 119.675)
		(size 0.5)
		(drill 0.2)
		(layers "F.Cu" "In1.Cu")
		(net 1)
	)
	(via
		(at 136 95)
		(size 0.5)
		(drill 0.2)
		(layers "F.Cu" "B.Cu")
		(net 1)
	)
	(via blind
		(at 102.275 122.675)
		(size 0.5)
		(drill 0.2)
		(layers "F.Cu" "In1.Cu")
		(net 1)
	)
	(via blind
		(at 91.275 118.675)
		(size 0.5)
		(drill 0.2)
		(layers "F.Cu" "In1.Cu")
		(net 1)
	)
	(via
		(at 81.919 89.947)
		(size 0.5)
		(drill 0.2)
		(layers "F.Cu" "B.Cu")
		(net 1)
	)
	(via
		(at 106.275 119.675)
		(size 0.5)
		(drill 0.2)
		(layers "F.Cu" "B.Cu")
		(net 1)
	)
	(via
		(at 75.279 86.487)
		(size 0.5)
		(drill 0.2)
		(layers "F.Cu" "B.Cu")
		(net 1)
	)
	(via
		(at 117 136.5)
		(size 0.5)
		(drill 0.2)
		(layers "F.Cu" "B.Cu")
		(net 1)
	)
	(via
		(at 103.915 105.715)
		(size 0.5)
		(drill 0.2)
		(layers "F.Cu" "B.Cu")
		(net 1)
	)
	(via blind
		(at 97.374 155.875)
		(size 0.5)
		(drill 0.2)
		(layers "F.Cu" "In1.Cu")
		(net 1)
	)
	(via
		(at 94.4 97.2)
		(size 0.5)
		(drill 0.2)
		(layers "F.Cu" "B.Cu")
		(net 1)
	)
	(via
		(at 121.305 118.005)
		(size 0.5)
		(drill 0.2)
		(layers "F.Cu" "B.Cu")
		(net 1)
	)
	(via
		(at 117.775 163.575)
		(size 0.5)
		(drill 0.2)
		(layers "F.Cu" "B.Cu")
		(net 1)
	)
	(via blind
		(at 142.774 119.514)
		(size 0.5)
		(drill 0.2)
		(layers "F.Cu" "In5.Cu")
		(net 1)
	)
	(via
		(at 92.275 128.675)
		(size 0.5)
		(drill 0.2)
		(layers "F.Cu" "B.Cu")
		(net 1)
	)
	(via
		(at 116.6 131.2)
		(size 0.5)
		(drill 0.2)
		(layers "F.Cu" "B.Cu")
		(net 1)
	)
	(via
		(at 116.1 131.7)
		(size 0.5)
		(drill 0.2)
		(layers "F.Cu" "B.Cu")
		(net 1)
	)
	(via
		(at 130.475 153.875)
		(size 0.5)
		(drill 0.2)
		(layers "F.Cu" "B.Cu")
		(net 1)
	)
	(via
		(at 103.415 98.105)
		(size 0.5)
		(drill 0.2)
		(layers "F.Cu" "B.Cu")
		(net 1)
	)
	(via
		(at 105.275 119.675)
		(size 0.5)
		(drill 0.2)
		(layers "F.Cu" "B.Cu")
		(net 1)
	)
	(via
		(at 68.065 159.79)
		(size 0.5)
		(drill 0.2)
		(layers "F.Cu" "B.Cu")
		(net 1)
	)
	(via blind
		(at 95.675 138.775)
		(size 0.5)
		(drill 0.2)
		(layers "F.Cu" "In1.Cu")
		(net 1)
	)
	(via
		(at 138.55 88.4125)
		(size 0.5)
		(drill 0.2)
		(layers "F.Cu" "B.Cu")
		(net 1)
	)
	(via blind
		(at 92.174 155.875)
		(size 0.5)
		(drill 0.2)
		(layers "F.Cu" "In1.Cu")
		(net 1)
	)
	(via
		(at 90.5 154.9)
		(size 0.5)
		(drill 0.2)
		(layers "F.Cu" "B.Cu")
		(net 1)
	)
	(via
		(at 64.575 138.035)
		(size 0.5)
		(drill 0.2)
		(layers "F.Cu" "B.Cu")
		(net 1)
	)
	(via
		(at 137.85 100.7125)
		(size 0.5)
		(drill 0.2)
		(layers "F.Cu" "B.Cu")
		(net 1)
	)
	(via
		(at 130.39 175.87)
		(size 0.5)
		(drill 0.2)
		(layers "F.Cu" "B.Cu")
		(net 1)
	)
	(via
		(at 131.35 91.6125)
		(size 0.5)
		(drill 0.2)
		(layers "F.Cu" "B.Cu")
		(net 1)
	)
	(via
		(at 118.3 123.6)
		(size 0.5)
		(drill 0.2)
		(layers "F.Cu" "B.Cu")
		(net 1)
	)
	(via
		(at 142.45 99.0125)
		(size 0.5)
		(drill 0.2)
		(layers "F.Cu" "B.Cu")
		(net 1)
	)
	(via
		(at 136 97)
		(size 0.5)
		(drill 0.2)
		(layers "F.Cu" "B.Cu")
		(net 1)
	)
	(via blind
		(at 94.983706 143.38951)
		(size 0.5)
		(drill 0.2)
		(layers "F.Cu" "In1.Cu")
		(net 1)
	)
	(via
		(at 137.784 126.514)
		(size 0.5)
		(drill 0.2)
		(layers "F.Cu" "B.Cu")
		(net 1)
	)
	(via blind
		(at 103.374 155.875)
		(size 0.5)
		(drill 0.2)
		(layers "F.Cu" "In1.Cu")
		(net 1)
	)
	(via blind
		(at 128.275 129.275)
		(size 0.5)
		(drill 0.2)
		(layers "F.Cu" "In1.Cu")
		(net 1)
	)
	(via
		(at 129.675 131.375)
		(size 0.5)
		(drill 0.2)
		(layers "F.Cu" "B.Cu")
		(net 1)
	)
	(via
		(at 109.025 98.425)
		(size 0.5)
		(drill 0.2)
		(layers "F.Cu" "B.Cu")
		(net 1)
	)
	(via blind
		(at 109.275 112.675)
		(size 0.5)
		(drill 0.2)
		(layers "F.Cu" "B.Cu")
		(net 1)
	)
	(via
		(at 91.275 109.685009)
		(size 0.5)
		(drill 0.2)
		(layers "F.Cu" "B.Cu")
		(net 1)
	)
	(via blind
		(at 94.275 120.665)
		(size 0.5)
		(drill 0.2)
		(layers "F.Cu" "In1.Cu")
		(net 1)
	)
	(via blind
		(at 93.374 155.875)
		(size 0.5)
		(drill 0.2)
		(layers "F.Cu" "In1.Cu")
		(net 1)
	)
	(via
		(at 96.575 146.775)
		(size 0.5)
		(drill 0.2)
		(layers "F.Cu" "B.Cu")
		(net 1)
	)
	(via
		(at 139.784 126.514)
		(size 0.5)
		(drill 0.2)
		(layers "F.Cu" "B.Cu")
		(net 1)
	)
	(via
		(at 97.506 173.736)
		(size 0.5)
		(drill 0.2)
		(layers "F.Cu" "B.Cu")
		(net 1)
	)
	(via
		(at 108.97 97.54)
		(size 0.5)
		(drill 0.2)
		(layers "F.Cu" "B.Cu")
		(net 1)
	)
	(via
		(at 69.71795 97.47205)
		(size 0.5)
		(drill 0.2)
		(layers "F.Cu" "B.Cu")
		(net 1)
	)
	(via
		(at 102.795 89.335)
		(size 0.5)
		(drill 0.2)
		(layers "F.Cu" "B.Cu")
		(net 1)
	)
	(via blind
		(at 94.57399 151.075)
		(size 0.5)
		(drill 0.2)
		(layers "F.Cu" "In1.Cu")
		(net 1)
	)
	(via
		(at 70.109 82.877)
		(size 0.5)
		(drill 0.2)
		(layers "F.Cu" "B.Cu")
		(net 1)
	)
	(via
		(at 91.1 154.3)
		(size 0.5)
		(drill 0.2)
		(layers "F.Cu" "B.Cu")
		(net 1)
	)
	(via
		(at 115.3 123.6)
		(size 0.5)
		(drill 0.2)
		(layers "F.Cu" "B.Cu")
		(net 1)
	)
	(via
		(at 130.778561 115.378561)
		(size 0.5)
		(drill 0.2)
		(layers "F.Cu" "B.Cu")
		(net 1)
	)
	(via
		(at 117.1 129.7)
		(size 0.5)
		(drill 0.2)
		(layers "F.Cu" "B.Cu")
		(net 1)
	)
	(via
		(at 116.5 123.6)
		(size 0.5)
		(drill 0.2)
		(layers "F.Cu" "B.Cu")
		(net 1)
	)
	(via
		(at 98.291302 160.885503)
		(size 0.5)
		(drill 0.2)
		(layers "F.Cu" "B.Cu")
		(net 1)
	)
	(via
		(at 106.874 147.075)
		(size 0.5)
		(drill 0.2)
		(layers "F.Cu" "B.Cu")
		(net 1)
	)
	(via blind
		(at 140.774 121.514)
		(size 0.5)
		(drill 0.2)
		(layers "F.Cu" "In5.Cu")
		(net 1)
	)
	(via
		(at 109.29999 106.725)
		(size 0.5)
		(drill 0.2)
		(layers "F.Cu" "B.Cu")
		(net 1)
	)
	(via blind
		(at 106.375 158.275)
		(size 0.5)
		(drill 0.2)
		(layers "F.Cu" "In1.Cu")
		(net 1)
	)
	(via
		(at 116.1 130.7)
		(size 0.5)
		(drill 0.2)
		(layers "F.Cu" "B.Cu")
		(net 1)
	)
	(via
		(at 75.975 155.775)
		(size 0.5)
		(drill 0.2)
		(layers "F.Cu" "B.Cu")
		(net 1)
	)
	(via
		(at 95.275 121.675)
		(size 0.5)
		(drill 0.2)
		(layers "F.Cu" "B.Cu")
		(net 1)
	)
	(via
		(at 94.4 95)
		(size 0.5)
		(drill 0.2)
		(layers "F.Cu" "B.Cu")
		(net 1)
	)
	(via
		(at 133.99 175.87)
		(size 0.5)
		(drill 0.2)
		(layers "F.Cu" "B.Cu")
		(net 1)
	)
	(via
		(at 126.35 94.1125)
		(size 0.5)
		(drill 0.2)
		(layers "F.Cu" "B.Cu")
		(net 1)
	)
	(via
		(at 106.875 90.275)
		(size 0.5)
		(drill 0.2)
		(layers "F.Cu" "B.Cu")
		(net 1)
	)
	(via
		(at 134.784 126.514)
		(size 0.5)
		(drill 0.2)
		(layers "F.Cu" "B.Cu")
		(net 1)
	)
	(via blind
		(at 94.675 138.775)
		(size 0.5)
		(drill 0.2)
		(layers "F.Cu" "In1.Cu")
		(net 1)
	)
	(via blind
		(at 92.97399 151.075)
		(size 0.5)
		(drill 0.2)
		(layers "F.Cu" "In1.Cu")
		(net 1)
	)
	(via
		(at 121.65 64.205)
		(size 0.5)
		(drill 0.2)
		(layers "F.Cu" "B.Cu")
		(net 1)
	)
	(via blind
		(at 98.175 151.075)
		(size 0.5)
		(drill 0.2)
		(layers "F.Cu" "In1.Cu")
		(net 1)
	)
	(via
		(at 124.95 65.655)
		(size 0.5)
		(drill 0.2)
		(layers "F.Cu" "B.Cu")
		(net 1)
	)
	(via
		(at 117.1 123.6)
		(size 0.5)
		(drill 0.2)
		(layers "F.Cu" "B.Cu")
		(net 1)
	)
	(via blind
		(at 99.075 157.475)
		(size 0.5)
		(drill 0.2)
		(layers "F.Cu" "In1.Cu")
		(net 1)
	)
	(via
		(at 117 139.3)
		(size 0.5)
		(drill 0.2)
		(layers "F.Cu" "B.Cu")
		(net 1)
	)
	(via
		(at 127.55 60.305)
		(size 0.5)
		(drill 0.2)
		(layers "F.Cu" "B.Cu")
		(net 1)
	)
	(via
		(at 64.2 91.2)
		(size 0.5)
		(drill 0.2)
		(layers "F.Cu" "B.Cu")
		(net 1)
	)
	(via
		(at 139.09 140.965)
		(size 0.5)
		(drill 0.2)
		(layers "F.Cu" "B.Cu")
		(net 1)
	)
	(via
		(at 100.275 115.675)
		(size 0.5)
		(drill 0.2)
		(layers "F.Cu" "B.Cu")
		(net 1)
	)
	(via blind
		(at 121.25 166.05)
		(size 0.5)
		(drill 0.2)
		(layers "F.Cu" "In1.Cu")
		(net 1)
	)
	(via
		(at 102.729 95.597)
		(size 0.5)
		(drill 0.2)
		(layers "F.Cu" "B.Cu")
		(net 1)
	)
	(via
		(at 133.85 91.6125)
		(size 0.5)
		(drill 0.2)
		(layers "F.Cu" "B.Cu")
		(net 1)
	)
	(via
		(at 81.775 104.675)
		(size 0.5)
		(drill 0.2)
		(layers "F.Cu" "B.Cu")
		(net 1)
	)
	(via
		(at 138.35 90.1125)
		(size 0.5)
		(drill 0.2)
		(layers "F.Cu" "B.Cu")
		(net 1)
	)
	(via
		(at 117 133)
		(size 0.5)
		(drill 0.2)
		(layers "F.Cu" "B.Cu")
		(net 1)
	)
	(via
		(at 117 133.7)
		(size 0.5)
		(drill 0.2)
		(layers "F.Cu" "B.Cu")
		(net 1)
	)
	(via
		(at 133 97)
		(size 0.5)
		(drill 0.2)
		(layers "F.Cu" "B.Cu")
		(net 1)
	)
	(via
		(at 91.402 85.716)
		(size 0.5)
		(drill 0.2)
		(layers "F.Cu" "B.Cu")
		(net 1)
	)
	(via blind
		(at 127.25 166.05)
		(size 0.5)
		(drill 0.2)
		(layers "F.Cu" "In1.Cu")
		(net 1)
	)
	(via blind
		(at 137.774 122.514)
		(size 0.5)
		(drill 0.2)
		(layers "F.Cu" "In5.Cu")
		(net 1)
	)
	(via blind
		(at 135.774 122.514)
		(size 0.5)
		(drill 0.2)
		(layers "F.Cu" "In5.Cu")
		(net 1)
	)
	(via
		(at 115.1 102.6)
		(size 0.5)
		(drill 0.2)
		(layers "F.Cu" "B.Cu")
		(net 1)
	)
	(via
		(at 94.275 127.675)
		(size 0.5)
		(drill 0.2)
		(layers "F.Cu" "B.Cu")
		(net 1)
	)
	(via blind
		(at 98.175 143.375)
		(size 0.5)
		(drill 0.2)
		(layers "F.Cu" "In1.Cu")
		(net 1)
	)
	(via blind
		(at 131.75 166.05)
		(size 0.5)
		(drill 0.2)
		(layers "F.Cu" "In1.Cu")
		(net 1)
	)
	(via
		(at 109.274 175.875)
		(size 0.5)
		(drill 0.2)
		(layers "F.Cu" "B.Cu")
		(net 1)
	)
	(via
		(at 94.4 96.5)
		(size 0.5)
		(drill 0.2)
		(layers "F.Cu" "B.Cu")
		(net 1)
	)
	(via
		(at 68.665 159.94)
		(size 0.5)
		(drill 0.2)
		(layers "F.Cu" "B.Cu")
		(net 1)
	)
	(via
		(at 69.4801 122.2499)
		(size 0.5)
		(drill 0.2)
		(layers "F.Cu" "B.Cu")
		(net 1)
	)
	(via blind
		(at 95.265 120.675)
		(size 0.5)
		(drill 0.2)
		(layers "F.Cu" "In1.Cu")
		(net 1)
	)
	(via
		(at 110.78 88.255)
		(size 0.5)
		(drill 0.2)
		(layers "F.Cu" "B.Cu")
		(net 1)
	)
	(via
		(at 121.015 113.965)
		(size 0.5)
		(drill 0.2)
		(layers "F.Cu" "B.Cu")
		(net 1)
	)
	(via
		(at 81.819 97.317)
		(size 0.5)
		(drill 0.2)
		(layers "F.Cu" "B.Cu")
		(net 1)
	)
	(via
		(at 133.975 153.975)
		(size 0.5)
		(drill 0.2)
		(layers "F.Cu" "B.Cu")
		(net 1)
	)
	(via
		(at 128.59 175.87)
		(size 0.5)
		(drill 0.2)
		(layers "F.Cu" "B.Cu")
		(net 1)
	)
	(via
		(at 91.3 136.3)
		(size 0.5)
		(drill 0.2)
		(layers "F.Cu" "B.Cu")
		(net 1)
	)
	(via
		(at 138.784 126.514)
		(size 0.5)
		(drill 0.2)
		(layers "F.Cu" "B.Cu")
		(net 1)
	)
	(via
		(at 134.5 95)
		(size 0.5)
		(drill 0.2)
		(layers "F.Cu" "B.Cu")
		(net 1)
	)
	(via
		(at 137.174472 163.774472)
		(size 0.5)
		(drill 0.2)
		(layers "F.Cu" "B.Cu")
		(net 1)
	)
	(via blind
		(at 122.75 166.05)
		(size 0.5)
		(drill 0.2)
		(layers "F.Cu" "In1.Cu")
		(net 1)
	)
	(via
		(at 91.1 155.5)
		(size 0.5)
		(drill 0.2)
		(layers "F.Cu" "B.Cu")
		(net 1)
	)
	(via
		(at 125.15 60.305)
		(size 0.5)
		(drill 0.2)
		(layers "F.Cu" "B.Cu")
		(net 1)
	)
	(via blind
		(at 95.775 149.975)
		(size 0.5)
		(drill 0.2)
		(layers "F.Cu" "In1.Cu")
		(net 1)
	)
	(via
		(at 90.402 85.716)
		(size 0.5)
		(drill 0.2)
		(layers "F.Cu" "B.Cu")
		(net 1)
	)
	(via
		(at 102.275 124.675)
		(size 0.5)
		(drill 0.2)
		(layers "F.Cu" "B.Cu")
		(net 1)
	)
	(via blind
		(at 128.275 128.775)
		(size 0.5)
		(drill 0.2)
		(layers "F.Cu" "In1.Cu")
		(net 1)
	)
	(via
		(at 136.784 126.514)
		(size 0.5)
		(drill 0.2)
		(layers "F.Cu" "B.Cu")
		(net 1)
	)
	(via
		(at 88.892 99.386)
		(size 0.5)
		(drill 0.2)
		(layers "F.Cu" "B.Cu")
		(net 1)
	)
	(via
		(at 132.975 153.975)
		(size 0.5)
		(drill 0.2)
		(layers "F.Cu" "B.Cu")
		(net 1)
	)
	(via
		(at 76.265 174.715)
		(size 0.5)
		(drill 0.2)
		(layers "F.Cu" "B.Cu")
		(net 1)
	)
	(via
		(at 134.5 93.5)
		(size 0.5)
		(drill 0.2)
		(layers "F.Cu" "B.Cu")
		(net 1)
	)
	(via
		(at 132.15 102.3125)
		(size 0.5)
		(drill 0.2)
		(layers "F.Cu" "B.Cu")
		(net 1)
	)
	(via
		(at 145.54 146.39)
		(size 0.5)
		(drill 0.2)
		(layers "F.Cu" "B.Cu")
		(net 1)
	)
	(via blind
		(at 123.19 175.87)
		(size 0.5)
		(drill 0.2)
		(layers "F.Cu" "In1.Cu")
		(net 1)
	)
	(via blind
		(at 130.25 166.05)
		(size 0.5)
		(drill 0.2)
		(layers "F.Cu" "In1.Cu")
		(net 1)
	)
	(via blind
		(at 125.01 175.9)
		(size 0.5)
		(drill 0.2)
		(layers "F.Cu" "In1.Cu")
		(net 1)
	)
	(via blind
		(at 128.575 113.175)
		(size 0.5)
		(drill 0.2)
		(layers "F.Cu" "In1.Cu")
		(net 1)
	)
	(via
		(at 98.275 124.675)
		(size 0.5)
		(drill 0.2)
		(layers "F.Cu" "B.Cu")
		(net 1)
	)
	(via
		(at 116.6 130.2)
		(size 0.5)
		(drill 0.2)
		(layers "F.Cu" "B.Cu")
		(net 1)
	)
	(via
		(at 90.402 78.046)
		(size 0.5)
		(drill 0.2)
		(layers "F.Cu" "B.Cu")
		(net 1)
	)
	(via
		(at 115.1 103.8)
		(size 0.5)
		(drill 0.2)
		(layers "F.Cu" "B.Cu")
		(net 1)
	)
	(via blind
		(at 102.57399 151.075)
		(size 0.5)
		(drill 0.2)
		(layers "F.Cu" "In1.Cu")
		(net 1)
	)
	(via
		(at 75.615 166.915)
		(size 0.5)
		(drill 0.2)
		(layers "F.Cu" "B.Cu")
		(net 1)
	)
	(via blind
		(at 101.275 123.675)
		(size 0.5)
		(drill 0.2)
		(layers "F.Cu" "In1.Cu")
		(net 1)
	)
	(via blind
		(at 108.275 120.675)
		(size 0.5)
		(drill 0.2)
		(layers "F.Cu" "In1.Cu")
		(net 1)
	)
	(via blind
		(at 100.575 138.775)
		(size 0.5)
		(drill 0.2)
		(layers "F.Cu" "In1.Cu")
		(net 1)
	)
	(via
		(at 115.505 154.095)
		(size 0.5)
		(drill 0.2)
		(layers "F.Cu" "B.Cu")
		(net 1)
	)
	(via
		(at 90.7 135.7)
		(size 0.5)
		(drill 0.2)
		(layers "F.Cu" "B.Cu")
		(net 1)
	)
	(via
		(at 108.95 96.89)
		(size 0.5)
		(drill 0.2)
		(layers "F.Cu" "B.Cu")
		(net 1)
	)
	(via blind
		(at 101.774 155.875)
		(size 0.5)
		(drill 0.2)
		(layers "F.Cu" "In1.Cu")
		(net 1)
	)
	(via
		(at 137.62 105.68)
		(size 0.5)
		(drill 0.2)
		(layers "F.Cu" "B.Cu")
		(net 1)
	)
	(via
		(at 117 137.9)
		(size 0.5)
		(drill 0.2)
		(layers "F.Cu" "B.Cu")
		(net 1)
	)
	(via
		(at 127.25 97.9125)
		(size 0.5)
		(drill 0.2)
		(layers "F.Cu" "B.Cu")
		(net 1)
	)
	(via
		(at 108.225 100.125)
		(size 0.5)
		(drill 0.2)
		(layers "F.Cu" "B.Cu")
		(net 1)
	)
	(via
		(at 137.565 76.755)
		(size 0.5)
		(drill 0.2)
		(layers "F.Cu" "B.Cu")
		(net 1)
	)
	(via
		(at 135.275 166.475)
		(size 0.5)
		(drill 0.2)
		(layers "F.Cu" "B.Cu")
		(net 1)
	)
	(via blind
		(at 103.275 124.675)
		(size 0.5)
		(drill 0.2)
		(layers "F.Cu" "In1.Cu")
		(net 1)
	)
	(via blind
		(at 94.17499 143.38951)
		(size 0.5)
		(drill 0.2)
		(layers "F.Cu" "In1.Cu")
		(net 1)
	)
	(via blind
		(at 98.775 138.775)
		(size 0.5)
		(drill 0.2)
		(layers "F.Cu" "In1.Cu")
		(net 1)
	)
	(via blind
		(at 79.89 175.745)
		(size 0.5)
		(drill 0.2)
		(layers "F.Cu" "In1.Cu")
		(net 1)
	)
	(via blind
		(at 135.774 125.514)
		(size 0.5)
		(drill 0.2)
		(layers "F.Cu" "In5.Cu")
		(net 1)
	)
	(via
		(at 82.375 106.21)
		(size 0.5)
		(drill 0.2)
		(layers "F.Cu" "B.Cu")
		(free yes)
		(net 1)
	)
	(via
		(at 135.25 85.8125)
		(size 0.5)
		(drill 0.2)
		(layers "F.Cu" "B.Cu")
		(net 1)
	)
	(via
		(at 95.395 98.675)
		(size 0.5)
		(drill 0.2)
		(layers "F.Cu" "B.Cu")
		(net 1)
	)
	(via
		(at 95.285 94.975)
		(size 0.5)
		(drill 0.2)
		(layers "F.Cu" "B.Cu")
		(net 1)
	)
	(via
		(at 142.45 95.5125)
		(size 0.5)
		(drill 0.2)
		(layers "F.Cu" "B.Cu")
		(net 1)
	)
	(via
		(at 95.575 151.775)
		(size 0.5)
		(drill 0.2)
		(layers "F.Cu" "B.Cu")
		(net 1)
	)
	(via blind
		(at 96.174 155.875)
		(size 0.5)
		(drill 0.2)
		(layers "F.Cu" "In1.Cu")
		(net 1)
	)
	(via
		(at 91.1 154.9)
		(size 0.5)
		(drill 0.2)
		(layers "F.Cu" "B.Cu")
		(net 1)
	)
	(via
		(at 111.78 88.205)
		(size 0.5)
		(drill 0.2)
		(layers "F.Cu" "B.Cu")
		(net 1)
	)
	(via
		(at 115.1 100.2)
		(size 0.5)
		(drill 0.2)
		(layers "F.Cu" "B.Cu")
		(net 1)
	)
	(via blind
		(at 104.275 122.675)
		(size 0.5)
		(drill 0.2)
		(layers "F.Cu" "In1.Cu")
		(net 1)
	)
	(via
		(at 132.19 175.87)
		(size 0.5)
		(drill 0.2)
		(layers "F.Cu" "B.Cu")
		(net 1)
	)
	(via blind
		(at 141.774 122.514)
		(size 0.5)
		(drill 0.2)
		(layers "F.Cu" "In5.Cu")
		(net 1)
	)
	(via
		(at 70.174 86.614)
		(size 0.5)
		(drill 0.2)
		(layers "F.Cu" "B.Cu")
		(net 1)
	)
	(via
		(at 134.5 97)
		(size 0.5)
		(drill 0.2)
		(layers "F.Cu" "B.Cu")
		(net 1)
	)
	(via
		(at 112.225 121.625001)
		(size 0.5)
		(drill 0.2)
		(layers "F.Cu" "B.Cu")
		(net 1)
	)
	(via
		(at 124.915 112.295)
		(size 0.5)
		(drill 0.2)
		(layers "F.Cu" "B.Cu")
		(net 1)
	)
	(via blind
		(at 90.275 129.675)
		(size 0.5)
		(drill 0.2)
		(layers "F.Cu" "In1.Cu")
		(net 1)
	)
	(via
		(at 115.9 123.6)
		(size 0.5)
		(drill 0.2)
		(layers "F.Cu" "B.Cu")
		(net 1)
	)
	(via
		(at 91.402 86.716)
		(size 0.5)
		(drill 0.2)
		(layers "F.Cu" "B.Cu")
		(net 1)
	)
	(via
		(at 99.284 173.736)
		(size 0.5)
		(drill 0.2)
		(layers "F.Cu" "B.Cu")
		(net 1)
	)
	(via blind
		(at 96.97399 151.075)
		(size 0.5)
		(drill 0.2)
		(layers "F.Cu" "In1.Cu")
		(net 1)
	)
	(via blind
		(at 126.79 175.87)
		(size 0.5)
		(drill 0.2)
		(layers "F.Cu" "In1.Cu")
		(net 1)
	)
	(via
		(at 140.6 83.5)
		(size 0.5)
		(drill 0.2)
		(layers "F.Cu" "B.Cu")
		(net 1)
	)
	(via blind
		(at 94.974 155.875)
		(size 0.5)
		(drill 0.2)
		(layers "F.Cu" "In1.Cu")
		(net 1)
	)
	(via
		(at 89.892 99.386)
		(size 0.5)
		(drill 0.2)
		(layers "F.Cu" "B.Cu")
		(net 1)
	)
	(via
		(at 97.275 119.675)
		(size 0.5)
		(drill 0.2)
		(layers "F.Cu" "B.Cu")
		(net 1)
	)
	(via
		(at 135.85 88.0125)
		(size 0.5)
		(drill 0.2)
		(layers "F.Cu" "B.Cu")
		(net 1)
	)
	(via
		(at 120.915 109.115)
		(size 0.5)
		(drill 0.2)
		(layers "F.Cu" "B.Cu")
		(net 1)
	)
	(via
		(at 91.3 136.9)
		(size 0.5)
		(drill 0.2)
		(layers "F.Cu" "B.Cu")
		(net 1)
	)
	(via
		(at 117.1 130.7)
		(size 0.5)
		(drill 0.2)
		(layers "F.Cu" "B.Cu")
		(net 1)
	)
	(via
		(at 97.57 88.305)
		(size 0.5)
		(drill 0.2)
		(layers "F.Cu" "B.Cu")
		(net 1)
	)
	(via
		(at 112.475 112.175)
		(size 0.5)
		(drill 0.2)
		(layers "F.Cu" "B.Cu")
		(net 1)
	)
	(via
		(at 126.115 117.855)
		(size 0.5)
		(drill 0.2)
		(layers "F.Cu" "B.Cu")
		(net 1)
	)
	(via
		(at 108.87 94.46)
		(size 0.5)
		(drill 0.2)
		(layers "F.Cu" "B.Cu")
		(net 1)
	)
	(via
		(at 93.275 123.675)
		(size 0.5)
		(drill 0.2)
		(layers "F.Cu" "B.Cu")
		(net 1)
	)
	(segment
		(start 123.86 112.975)
		(end 123.86 112.29)
		(width 0.15)
		(layer "B.Cu")
		(net 1)
	)
	(segment
		(start 64.555 127.585)
		(end 64.555 128.38)
		(width 0.2)
		(layer "B.Cu")
		(net 1)
	)
	(segment
		(start 126.675 110.69)
		(end 125.99 110.69)
		(width 0.15)
		(layer "B.Cu")
		(net 1)
	)
	(segment
		(start 64.565 146.845)
		(end 64.565 147.645)
		(width 0.2)
		(layer "B.Cu")
		(net 1)
	)
	(segment
		(start 102.77 90.265)
		(end 102.77 89.36)
		(width 0.2)
		(layer "B.Cu")
		(net 1)
	)
	(segment
		(start 104.82 97.63)
		(end 104.03 97.63)
		(width 0.2)
		(layer "B.Cu")
		(net 1)
	)
	(segment
		(start 96.2 99.49)
		(end 95.41 99.49)
		(width 0.2)
		(layer "B.Cu")
		(net 1)
	)
	(segment
		(start 125.93 112.985)
		(end 125.93 112.3)
		(width 0.15)
		(layer "B.Cu")
		(net 1)
	)
	(segment
		(start 91.285009 109.675)
		(end 91.275 109.685009)
		(width 0.15)
		(layer "B.Cu")
		(net 1)
	)
	(segment
		(start 92.875 120.075)
		(end 92.875 120.675)
		(width 0.2)
		(layer "B.Cu")
		(net 1)
	)
	(segment
		(start 106.655 120.055)
		(end 106.275 119.675)
		(width 0.15)
		(layer "B.Cu")
		(net 1)
	)
	(segment
		(start 97.57 87.49)
		(end 97.57 88.305)
		(width 0.2)
		(layer "B.Cu")
		(net 1)
	)
	(segment
		(start 109.29 177.345)
		(end 109.29 175.891)
		(width 0.15)
		(layer "B.Cu")
		(net 1)
	)
	(segment
		(start 91.29 125.67501)
		(end 91.275 125.69001)
		(width 0.15)
		(layer "B.Cu")
		(net 1)
	)
	(segment
		(start 124.365 128.795)
		(end 124.365 129.165)
		(width 0.2)
		(layer "B.Cu")
		(net 1)
	)
	(segment
		(start 104.26 109.975)
		(end 104.26 110.66)
		(width 0.15)
		(layer "B.Cu")
		(net 1)
	)
	(segment
		(start 140.759 132.099)
		(end 140.774 132.114)
		(width 0.15)
		(layer "B.Cu")
		(net 1)
	)
	(segment
		(start 100.88 90.265)
		(end 100.88 89.52)
		(width 0.2)
		(layer "B.Cu")
		(net 1)
	)
	(segment
		(start 101.955 120.675)
		(end 101.955 121.355)
		(width 0.15)
		(layer "B.Cu")
		(net 1)
	)
	(segment
		(start 134.774 127.029)
		(end 134.774 126.524)
		(width 0.15)
		(layer "B.Cu")
		(net 1)
	)
	(segment
		(start 104.275 118.19)
		(end 103.19 118.19)
		(width 0.15)
		(layer "B.Cu")
		(net 1)
	)
	(segment
		(start 114.69 177.345)
		(end 114.69 175.79)
		(width 0.15)
		(layer "B.Cu")
		(net 1)
	)
	(segment
		(start 75.69 175.29)
		(end 76.265 174.715)
		(width 0.15)
		(layer "B.Cu")
		(net 1)
	)
	(segment
		(start 100.88 89.52)
		(end 100.875 89.515)
		(width 0.2)
		(layer "B.Cu")
		(net 1)
	)
	(segment
		(start 121.875 109.845)
		(end 121.645 109.845)
		(width 0.2)
		(layer "B.Cu")
		(net 1)
	)
	(segment
		(start 82.525 89.925)
		(end 81.825 89.925)
		(width 0.15)
		(layer "B.Cu")
		(net 1)
	)
	(segment
		(start 91.495 109.675)
		(end 91.79 109.675)
		(width 0.15)
		(layer "B.Cu")
		(net 1)
	)
	(segment
		(start 98.005 122.405)
		(end 98.275 122.675)
		(width 0.15)
		(layer "B.Cu")
		(net 1)
	)
	(segment
		(start 96.055 121.675)
		(end 95.275 121.675)
		(width 0.15)
		(layer "B.Cu")
		(net 1)
	)
	(segment
		(start 105.03 96.4)
		(end 105.76 97.13)
		(width 0.2)
		(layer "B.Cu")
		(net 1)
	)
	(segment
		(start 95.225 127.94)
		(end 94.54 127.94)
		(width 0.2)
		(layer "B.Cu")
		(net 1)
	)
	(segment
		(start 80.225 88.525)
		(end 80.275 88.575)
		(width 0.15)
		(layer "B.Cu")
		(net 1)
	)
	(segment
		(start 129.66 126.775)
		(end 130.555 126.775)
		(width 0.15)
		(layer "B.Cu")
		(net 1)
	)
	(segment
		(start 94.54 127.94)
		(end 94.275 127.675)
		(width 0.2)
		(layer "B.Cu")
		(net 1)
	)
	(segment
		(start 96.205 96.95)
		(end 95.3 96.95)
		(width 0.2)
		(layer "B.Cu")
		(net 1)
	)
	(segment
		(start 90.175334 122.675)
		(end 90.69 122.675)
		(width 0.15)
		(layer "B.Cu")
		(net 1)
	)
	(segment
		(start 135.774 127.029)
		(end 135.774 126.524)
		(width 0.15)
		(layer "B.Cu")
		(net 1)
	)
	(segment
		(start 124.007 128.437)
		(end 124.365 128.795)
		(width 0.2)
		(layer "B.Cu")
		(net 1)
	)
	(segment
		(start 111.275 112.09)
		(end 112.39 112.09)
		(width 0.15)
		(layer "B.Cu")
		(net 1)
	)
	(segment
		(start 139.259 123.014)
		(end 139.436 123.014)
		(width 0.2)
		(layer "B.Cu")
		(net 1)
	)
	(segment
		(start 81.825 104.625)
		(end 81.775 104.675)
		(width 0.15)
		(layer "B.Cu")
		(net 1)
	)
	(segment
		(start 108.87 97.44)
		(end 108.23 97.44)
		(width 0.2)
		(layer "B.Cu")
		(net 1)
	)
	(segment
		(start 93.89 172.526)
		(end 94.078521 172.337479)
		(width 0.2)
		(layer "B.Cu")
		(net 1)
	)
	(segment
		(start 92.31 128.64)
		(end 92.275 128.675)
		(width 0.2)
		(layer "B.Cu")
		(net 1)
	)
	(segment
		(start 120.905 129.175)
		(end 120.465 129.615)
		(width 0.15)
		(layer "B.Cu")
		(net 1)
	)
	(segment
		(start 106.025 124.705)
		(end 105.305 124.705)
		(width 0.2)
		(layer "B.Cu")
		(net 1)
	)
	(segment
		(start 133.775 127.03)
		(end 133.775 126.375)
		(width 0.2)
		(layer "B.Cu")
		(net 1)
	)
	(segment
		(start 134.774 126.524)
		(end 134.784 126.514)
		(width 0.15)
		(layer "B.Cu")
		(net 1)
	)
	(segment
		(start 110.16 109.79)
		(end 110.275 109.675)
		(width 0.15)
		(layer "B.Cu")
		(net 1)
	)
	(segment
		(start 99.29 173.742)
		(end 99.284 173.736)
		(width 0.2)
		(layer "B.Cu")
		(net 1)
	)
	(segment
		(start 82.425 104.625)
		(end 81.825 104.625)
		(width 0.15)
		(layer "B.Cu")
		(net 1)
	)
	(segment
		(start 90.34 116.64)
		(end 90.325 116.625)
		(width 0.15)
		(layer "B.Cu")
		(net 1)
	)
	(segment
		(start 75.075 154.79)
		(end 75.395 154.79)
		(width 0.15)
		(layer "B.Cu")
		(net 1)
	)
	(segment
		(start 70.09 81.79)
		(end 70.09 82.858)
		(width 0.2)
		(layer "B.Cu")
		(net 1)
	)
	(segment
		(start 138.535 88.4275)
		(end 138.55 88.4125)
		(width 0.1)
		(layer "B.Cu")
		(net 1)
	)
	(segment
		(start 108.285 125.55)
		(end 108.26 125.525)
		(width 0.2)
		(layer "B.Cu")
		(net 1)
	)
	(segment
		(start 122.975 109.86)
		(end 124.055 109.86)
		(width 0.2)
		(layer "B.Cu")
		(net 1)
	)
	(segment
		(start 81.827 97.325)
		(end 81.819 97.317)
		(width 0.2)
		(layer "B.Cu")
		(net 1)
	)
	(segment
		(start 102.6 97.615)
		(end 102.6 96.986)
		(width 0.2)
		(layer "B.Cu")
		(net 1)
	)
	(segment
		(start 114.69 175.79)
		(end 115.215 175.265)
		(width 0.15)
		(layer "B.Cu")
		(net 1)
	)
	(segment
		(start 99.025 126.925)
		(end 99.275 126.675)
		(width 0.2)
		(layer "B.Cu")
		(net 1)
	)
	(segment
		(start 101.14 97.635)
		(end 101.455 97.635)
		(width 0.2)
		(layer "B.Cu")
		(net 1)
	)
	(segment
		(start 105.015 126.7)
		(end 105.015 126.115)
		(width 0.2)
		(layer "B.Cu")
		(net 1)
	)
	(segment
		(start 105.59 113.99)
		(end 105.275 113.675)
		(width 0.15)
		(layer "B.Cu")
		(net 1)
	)
	(segment
		(start 96.075 151.16)
		(end 96.075 151.455)
		(width 0.2)
		(layer "B.Cu")
		(net 1)
	)
	(segment
		(start 123 125.884)
		(end 124 125.884)
		(width 0.2)
		(layer "B.Cu")
		(net 1)
	)
	(segment
		(start 97.955 117.99)
		(end 96.275 117.99)
		(width 0.15)
		(layer "B.Cu")
		(net 1)
	)
	(segment
		(start 138.784 125.514)
		(end 138.774 125.504)
		(width 0.1)
		(layer "B.Cu")
		(net 1)
	)
	(segment
		(start 126.315 128.805)
		(end 125.957 128.447)
		(width 0.15)
		(layer "B.Cu")
		(net 1)
	)
	(segment
		(start 108.21 98.4)
		(end 109 98.4)
		(width 0.2)
		(layer "B.Cu")
		(net 1)
	)
	(segment
		(start 91.29 124.375)
		(end 91.29 125.67501)
		(width 0.15)
		(layer "B.Cu")
		(net 1)
	)
	(segment
		(start 76.29 177.345)
		(end 76.29 175.745)
		(width 0.15)
		(layer "B.Cu")
		(net 1)
	)
	(segment
		(start 130.555 126.775)
		(end 130.615 126.715)
		(width 0.15)
		(layer "B.Cu")
		(net 1)
	)
	(segment
		(start 103.79 115.675)
		(end 103.275 115.675)
		(width 0.15)
		(layer "B.Cu")
		(net 1)
	)
	(segment
		(start 105.015 126.115)
		(end 104.575 125.675)
		(width 0.2)
		(layer "B.Cu")
		(net 1)
	)
	(segment
		(start 98.26 112.66)
		(end 98.275 112.675)
		(width 0.15)
		(layer "B.Cu")
		(net 1)
	)
	(segment
		(start 108.76 112.175)
		(end 108.775 112.175)
		(width 0.15)
		(layer "B.Cu")
		(net 1)
	)
	(segment
		(start 124.9 112.995)
		(end 124.9 112.31)
		(width 0.15)
		(layer "B.Cu")
		(net 1)
	)
	(segment
		(start 109.29 175.891)
		(end 109.274 175.875)
		(width 0.15)
		(layer "B.Cu")
		(net 1)
	)
	(segment
		(start 108.26 124.69)
		(end 109.275 123.675)
		(width 0.2)
		(layer "B.Cu")
		(net 1)
	)
	(segment
		(start 93.29 126.375)
		(end 93.29 125.70501)
		(width 0.15)
		(layer "B.Cu")
		(net 1)
	)
	(segment
		(start 96.205 95.95)
		(end 95.3 95.95)
		(width 0.2)
		(layer "B.Cu")
		(net 1)
	)
	(segment
		(start 128.59 177.345)
		(end 128.59 175.87)
		(width 0.2)
		(layer "B.Cu")
		(net 1)
	)
	(segment
		(start 109.29 123.69)
		(end 109.275 123.675)
		(width 0.2)
		(layer "B.Cu")
		(net 1)
	)
	(segment
		(start 140.774 126.524)
		(end 140.784 126.514)
		(width 0.1)
		(layer "B.Cu")
		(net 1)
	)
	(segment
		(start 124.015 110.615)
		(end 124.015 109.85)
		(width 0.15)
		(layer "B.Cu")
		(net 1)
	)
	(segment
		(start 103.955 122.675)
		(end 103.275 122.675)
		(width 0.15)
		(layer "B.Cu")
		(net 1)
	)
	(segment
		(start 133.835 91.5975)
		(end 133.85 91.6125)
		(width 0.1)
		(layer "B.Cu")
		(net 1)
	)
	(segment
		(start 108.285 126.6)
		(end 108.285 125.55)
		(width 0.2)
		(layer "B.Cu")
		(net 1)
	)
	(segment
		(start 98.26 111.675)
		(end 98.26 112.66)
		(width 0.15)
		(layer "B.Cu")
		(net 1)
	)
	(segment
		(start 112.225 121.14)
		(end 111.81 120.725)
		(width 0.2)
		(layer "B.Cu")
		(net 1)
	)
	(segment
		(start 135.774 126.524)
		(end 135.784 126.514)
		(width 0.15)
		(layer "B.Cu")
		(net 1)
	)
	(segment
		(start 93.275 123.675)
		(end 93.275 124.36)
		(width 0.15)
		(layer "B.Cu")
		(net 1)
	)
	(segment
		(start 92.9 119.1)
		(end 92.9 120.65)
		(width 0.2)
		(layer "B.Cu")
		(net 1)
	)
	(segment
		(start 64.605 118.065)
		(end 64.605 118.865)
		(width 0.2)
		(layer "B.Cu")
		(net 1)
	)
	(segment
		(start 109.375 109.79)
		(end 110.16 109.79)
		(width 0.15)
		(layer "B.Cu")
		(net 1)
	)
	(segment
		(start 104.575 125.675)
		(end 103.275 125.675)
		(width 0.2)
		(layer "B.Cu")
		(net 1)
	)
	(segment
		(start 98.5 90.305)
		(end 98.5 89.4)
		(width 0.2)
		(layer "B.Cu")
		(net 1)
	)
	(segment
		(start 108.23 97.44)
		(end 108.23 96.54)
		(width 0.2)
		(layer "B.Cu")
		(net 1)
	)
	(segment
		(start 81.69 175.79)
		(end 82.175 175.305)
		(width 0.25)
		(layer "B.Cu")
		(net 1)
	)
	(segment
		(start 136.85 88.4125)
		(end 136.45 88.0125)
		(width 0.1)
		(layer "B.Cu")
		(net 1)
	)
	(segment
		(start 108.23 96.54)
		(end 108.21 96.52)
		(width 0.2)
		(layer "B.Cu")
		(net 1)
	)
	(segment
		(start 121.31 129.175)
		(end 120.905 129.175)
		(width 0.15)
		(layer "B.Cu")
		(net 1)
	)
	(segment
		(start 82.525 82.725)
		(end 81.825 82.725)
		(width 0.15)
		(layer "B.Cu")
		(net 1)
	)
	(segment
		(start 104.2 96.4)
		(end 105.03 96.4)
		(width 0.2)
		(layer "B.Cu")
		(net 1)
	)
	(segment
		(start 140.759 131.414)
		(end 140.759 132.099)
		(width 0.15)
		(layer "B.Cu")
		(net 1)
	)
	(segment
		(start 93.29 125.70501)
		(end 93.275 125.69001)
		(width 0.15)
		(layer "B.Cu")
		(net 1)
	)
	(segment
		(start 101.34 129.61)
		(end 101.275 129.675)
		(width 0.2)
		(layer "B.Cu")
		(net 1)
	)
	(segment
		(start 108.93 91.99)
		(end 108.843 92.077)
		(width 0.15)
		(layer "B.Cu")
		(net 1)
	)
	(segment
		(start 102.6 96.986)
		(end 102.729 96.857)
		(width 0.2)
		(layer "B.Cu")
		(net 1)
	)
	(segment
		(start 75.254 84.367)
		(end 75.254 86.462)
		(width 0.2)
		(layer "B.Cu")
		(net 1)
	)
	(segment
		(start 138.774 126.524)
		(end 138.784 126.514)
		(width 0.1)
		(layer "B.Cu")
		(net 1)
	)
	(segment
		(start 75.975 155.37)
		(end 75.975 155.775)
		(width 0.15)
		(layer "B.Cu")
		(net 1)
	)
	(segment
		(start 139.436 123.014)
		(end 139.975 122.475)
		(width 0.2)
		(layer "B.Cu")
		(net 1)
	)
	(segment
		(start 101.955 121.355)
		(end 102.275 121.675)
		(width 0.15)
		(layer "B.Cu")
		(net 1)
	)
	(segment
		(start 96.215 95)
		(end 95.31 95)
		(width 0.2)
		(layer "B.Cu")
		(net 1)
	)
	(segment
		(start 106.865 90.265)
		(end 106.875 90.275)
		(width 0.2)
		(layer "B.Cu")
		(net 1)
	)
	(segment
		(start 140.774 127.029)
		(end 140.774 126.524)
		(width 0.1)
		(layer "B.Cu")
		(net 1)
	)
	(segment
		(start 123.065 127.715)
		(end 124.015 127.715)
		(width 0.15)
		(layer "B.Cu")
		(net 1)
	)
	(segment
		(start 99.29 177.355)
		(end 99.29 173.742)
		(width 0.2)
		(layer "B.Cu")
		(net 1)
	)
	(segment
		(start 103.005 124.675)
		(end 102.275 124.675)
		(width 0.15)
		(layer "B.Cu")
		(net 1)
	)
	(segment
		(start 107.074 147.79)
		(end 107.074 147.275)
		(width 0.15)
		(layer "B.Cu")
		(net 1)
	)
	(segment
		(start 101.645 124.045)
		(end 102.275 124.675)
		(width 0.15)
		(layer "B.Cu")
		(net 1)
	)
	(segment
		(start 103.415 98.105)
		(end 103.09 98.105)
		(width 0.2)
		(layer "B.Cu")
		(net 1)
	)
	(segment
		(start 70.09 85.54)
		(end 70.09 86.53)
		(width 0.2)
		(layer "B.Cu")
		(net 1)
	)
	(segment
		(start 96.075 151.455)
		(end 95.755 151.775)
		(width 0.2)
		(layer "B.Cu")
		(net 1)
	)
	(segment
		(start 99.545 123.675)
		(end 99.545 123.945)
		(width 0.15)
		(layer "B.Cu")
		(net 1)
	)
	(segment
		(start 101.645 123.675)
		(end 101.645 124.045)
		(width 0.15)
		(layer "B.Cu")
		(net 1)
	)
	(segment
		(start 75.254 86.462)
		(end 75.279 86.487)
		(width 0.2)
		(layer "B.Cu")
		(net 1)
	)
	(segment
		(start 126.315 129.18)
		(end 126.315 128.805)
		(width 0.15)
		(layer "B.Cu")
		(net 1)
	)
	(segment
		(start 101.8 90.28)
		(end 100.845 90.28)
		(width 0.2)
		(layer "B.Cu")
		(net 1)
	)
	(segment
		(start 108.26 125.525)
		(end 108.26 124.69)
		(width 0.2)
		(layer "B.Cu")
		(net 1)
	)
	(segment
		(start 98.005 121.675)
		(end 98.005 122.405)
		(width 0.15)
		(layer "B.Cu")
		(net 1)
	)
	(segment
		(start 107.275 113.99)
		(end 105.59 113.99)
		(width 0.15)
		(layer "B.Cu")
		(net 1)
	)
	(segment
		(start 98.29 124.69)
		(end 98.275 124.675)
		(width 0.15)
		(layer "B.Cu")
		(net 1)
	)
	(segment
		(start 105.76 97.13)
		(end 105.76 97.635)
		(width 0.2)
		(layer "B.Cu")
		(net 1)
	)
	(segment
		(start 126.875 112.405)
		(end 126.66 112.19)
		(width 0.15)
		(layer "B.Cu")
		(net 1)
	)
	(segment
		(start 104.26 117.66)
		(end 104.275 117.675)
		(width 0.15)
		(layer "B.Cu")
		(net 1)
	)
	(segment
		(start 64.575 137.235)
		(end 64.575 138.035)
		(width 0.2)
		(layer "B.Cu")
		(net 1)
	)
	(segment
		(start 96.06 112.675)
		(end 98.275 112.675)
		(width 0.15)
		(layer "B.Cu")
		(net 1)
	)
	(segment
		(start 125.315 128.015)
		(end 125.315 129.165)
		(width 0.2)
		(layer "B.Cu")
		(net 1)
	)
	(segment
		(start 104.26 110.66)
		(end 104.275 110.675)
		(width 0.15)
		(layer "B.Cu")
		(net 1)
	)
	(segment
		(start 106.275 117.675)
		(end 106.96 117.675)
		(width 0.15)
		(layer "B.Cu")
		(net 1)
	)
	(segment
		(start 99.545 123.945)
		(end 100.275 124.675)
		(width 0.15)
		(layer "B.Cu")
		(net 1)
	)
	(segment
		(start 121.865 113.965)
		(end 121.015 113.965)
		(width 0.15)
		(layer "B.Cu")
		(net 1)
	)
	(segment
		(start 108.87 94.46)
		(end 108.7 94.63)
		(width 0.2)
		(layer "B.Cu")
		(net 1)
	)
	(segment
		(start 97.49 177.355)
		(end 97.49 173.879)
		(width 0.2)
		(layer "B.Cu")
		(net 1)
	)
	(segment
		(start 98.57 87.49)
		(end 98.57 88.305)
		(width 0.2)
		(layer "B.Cu")
		(net 1)
	)
	(segment
		(start 70.09 82.858)
		(end 70.109 82.877)
		(width 0.2)
		(layer "B.Cu")
		(net 1)
	)
	(segment
		(start 101.34 128.825)
		(end 101.34 129.61)
		(width 0.2)
		(layer "B.Cu")
		(net 1)
	)
	(segment
		(start 97.955 120.355)
		(end 97.275 119.675)
		(width 0.15)
		(layer "B.Cu")
		(net 1)
	)
	(segment
		(start 97.49 173.879)
		(end 97.49 173.752)
		(width 0.2)
		(layer "B.Cu")
		(net 1)
	)
	(segment
		(start 133.089 122.514)
		(end 133.089 121.564)
		(width 0.2)
		(layer "B.Cu")
		(net 1)
	)
	(segment
		(start 107.074 147.275)
		(end 106.874 147.075)
		(width 0.15)
		(layer "B.Cu")
		(net 1)
	)
	(segment
		(start 103.09 98.105)
		(end 102.6 97.615)
		(width 0.2)
		(layer "B.Cu")
		(net 1)
	)
	(segment
		(start 98.075 146.86)
		(end 96.66 146.86)
		(width 0.2)
		(layer "B.Cu")
		(net 1)
	)
	(segment
		(start 104.26 116.675)
		(end 104.26 117.66)
		(width 0.15)
		(layer "B.Cu")
		(net 1)
	)
	(segment
		(start 139.774 126.524)
		(end 139.784 126.514)
		(width 0.1)
		(layer "B.Cu")
		(net 1)
	)
	(segment
		(start 139.289 125.514)
		(end 138.784 125.514)
		(width 0.1)
		(layer "B.Cu")
		(net 1)
	)
	(segment
		(start 100.275 117.89)
		(end 98.375 117.89)
		(width 0.15)
		(layer "B.Cu")
		(net 1)
	)
	(segment
		(start 100.005 121.405)
		(end 100.275 121.675)
		(width 0.15)
		(layer "B.Cu")
		(net 1)
	)
	(segment
		(start 98.375 117.89)
		(end 98.275 117.99)
		(width 0.15)
		(layer "B.Cu")
		(net 1)
	)
	(segment
		(start 133.835 90.8125)
		(end 133.835 91.5975)
		(width 0.1)
		(layer "B.Cu")
		(net 1)
	)
	(segment
		(start 108.21 95.55)
		(end 108.21 94.58)
		(width 0.2)
		(layer "B.Cu")
		(net 1)
	)
	(segment
		(start 110.275 118.675)
		(end 110.275 118.09)
		(width 0.15)
		(layer "B.Cu")
		(net 1)
	)
	(segment
		(start 137.774 127.029)
		(end 137.774 126.524)
		(width 0.1)
		(layer "B.Cu")
		(net 1)
	)
	(segment
		(start 141.774 126.524)
		(end 141.784 126.514)
		(width 0.15)
		(layer "B.Cu")
		(net 1)
	)
	(segment
		(start 97.264991 109.675)
		(end 97.275 109.685009)
		(width 0.15)
		(layer "B.Cu")
		(net 1)
	)
	(segment
		(start 104.275 118.19)
		(end 104.275 117.675)
		(width 0.15)
		(layer "B.Cu")
		(net 1)
	)
	(segment
		(start 104.005 123.758553)
		(end 104.921447 124.675)
		(width 0.15)
		(layer "B.Cu")
		(net 1)
	)
	(segment
		(start 95.755 151.775)
		(end 95.575 151.775)
		(width 0.2)
		(layer "B.Cu")
		(net 1)
	)
	(segment
		(start 91.79 109.675)
		(end 91.285009 109.675)
		(width 0.15)
		(layer "B.Cu")
		(net 1)
	)
	(segment
		(start 136.774 127.029)
		(end 136.774 126.524)
		(width 0.15)
		(layer "B.Cu")
		(net 1)
	)
	(segment
		(start 101.14 97.186)
		(end 101.469 96.857)
		(width 0.2)
		(layer "B.Cu")
		(net 1)
	)
	(segment
		(start 122.35 129.215)
		(end 122.35 128.43)
		(width 0.15)
		(layer "B.Cu")
		(net 1)
	)
	(segment
		(start 108.7 94.63)
		(end 108.235 94.63)
		(width 0.2)
		(layer "B.Cu")
		(net 1)
	)
	(segment
		(start 109.76 118.675)
		(end 110.275 118.675)
		(width 0.15)
		(layer "B.Cu")
		(net 1)
	)
	(segment
		(start 96.76 109.675)
		(end 97.264991 109.675)
		(width 0.15)
		(layer "B.Cu")
		(net 1)
	)
	(segment
		(start 92.9 120.65)
		(end 92.875 120.675)
		(width 0.2)
		(layer "B.Cu")
		(net 1)
	)
	(segment
		(start 75.69 177.345)
		(end 75.69 175.29)
		(width 0.15)
		(layer "B.Cu")
		(net 1)
	)
	(segment
		(start 96.34 126.575)
		(end 96.34 125.74)
		(width 0.2)
		(layer "B.Cu")
		(net 1)
	)
	(segment
		(start 123.743 128.437)
		(end 123.365 128.815)
		(width 0.2)
		(layer "B.Cu")
		(net 1)
	)
	(segment
		(start 139.774 127.029)
		(end 139.774 126.524)
		(width 0.1)
		(layer "B.Cu")
		(net 1)
	)
	(segment
		(start 91.275 109.675)
		(end 91.275 109.685009)
		(width 0.15)
		(layer "B.Cu")
		(net 1)
	)
	(segment
		(start 105.305 124.705)
		(end 105.275 124.675)
		(width 0.2)
		(layer "B.Cu")
		(net 1)
	)
	(segment
		(start 106.96 117.675)
		(end 106.975 117.69)
		(width 0.15)
		(layer "B.Cu")
		(net 1)
	)
	(segment
		(start 100.26 114.675)
		(end 100.26 115.66)
		(width 0.15)
		(layer "B.Cu")
		(net 1)
	)
	(segment
		(start 108.97 97.54)
		(end 108.87 97.44)
		(width 0.2)
		(layer "B.Cu")
		(net 1)
	)
	(segment
		(start 126.955 113.015)
		(end 126.875 112.935)
		(width 0.15)
		(layer "B.Cu")
		(net 1)
	)
	(segment
		(start 109 98.4)
		(end 109.025 98.425)
		(width 0.2)
		(layer "B.Cu")
		(net 1)
	)
	(segment
		(start 101.455 97.635)
		(end 101.885 98.065)
		(width 0.2)
		(layer "B.Cu")
		(net 1)
	)
	(segment
		(start 124 125.885)
		(end 124 126.468)
		(width 0.15)
		(layer "B.Cu")
		(net 1)
	)
	(segment
		(start 97.49 90.305)
		(end 97.49 89.4)
		(width 0.2)
		(layer "B.Cu")
		(net 1)
	)
	(segment
		(start 122.865 112.98)
		(end 123.8 112.98)
		(width 0.2)
		(layer "B.Cu")
		(net 1)
	)
	(segment
		(start 92.875 121.275)
		(end 93.275 121.675)
		(width 0.15)
		(layer "B.Cu")
		(net 1)
	)
	(segment
		(start 90.34 117.325)
		(end 90.34 116.64)
		(width 0.15)
		(layer "B.Cu")
		(net 1)
	)
	(segment
		(start 97.285009 109.675)
		(end 97.275 109.685009)
		(width 0.15)
		(layer "B.Cu")
		(net 1)
	)
	(segment
		(start 135.79 177.345)
		(end 135.79 175.87)
		(width 0.2)
		(layer "B.Cu")
		(net 1)
	)
	(segment
		(start 138.774 127.029)
		(end 138.774 126.524)
		(width 0.1)
		(layer "B.Cu")
		(net 1)
	)
	(segment
		(start 126.875 112.935)
		(end 126.875 112.405)
		(width 0.15)
		(layer "B.Cu")
		(net 1)
	)
	(segment
		(start 109.925 123.69)
		(end 109.29 123.69)
		(width 0.2)
		(layer "B.Cu")
		(net 1)
	)
	(segment
		(start 137.85 88.4275)
		(end 138.535 88.4275)
		(width 0.1)
		(layer "B.Cu")
		(net 1)
	)
	(segment
		(start 104.005 121.405)
		(end 104.275 121.675)
		(width 0.15)
		(layer "B.Cu")
		(net 1)
	)
	(segment
		(start 107.855 106.74)
		(end 109.28499 106.74)
		(width 0.15)
		(layer "B.Cu")
		(net 1)
	)
	(segment
		(start 96.86 124.26)
		(end 97.275 124.675)
		(width 0.15)
		(layer "B.Cu")
		(net 1)
	)
	(segment
		(start 97.06 115.675)
		(end 100.275 115.675)
		(width 0.15)
		(layer "B.Cu")
		(net 1)
	)
	(segment
		(start 124 126.468)
		(end 124 126.6)
		(width 0.15)
		(layer "B.Cu")
		(net 1)
	)
	(segment
		(start 97.49 173.752)
		(end 97.506 173.736)
		(width 0.2)
		(layer "B.Cu")
		(net 1)
	)
	(segment
		(start 104.005 120.675)
		(end 104.005 121.405)
		(width 0.15)
		(layer "B.Cu")
		(net 1)
	)
	(segment
		(start 96.205 94.04)
		(end 95.3 94.04)
		(width 0.2)
		(layer "B.Cu")
		(net 1)
	)
	(segment
		(start 100.26 115.66)
		(end 100.275 115.675)
		(width 0.15)
		(layer "B.Cu")
		(net 1)
	)
	(segment
		(start 141.774 127.029)
		(end 141.774 126.524)
		(width 0.15)
		(layer "B.Cu")
		(net 1)
	)
	(segment
		(start 97.045 123.175)
		(end 97.045 122.905)
		(width 0.15)
		(layer "B.Cu")
		(net 1)
	)
	(segment
		(start 108.775 112.175)
		(end 109.275 112.675)
		(width 0.15)
		(layer "B.Cu")
		(net 1)
	)
	(segment
		(start 136.85 88.4275)
		(end 136.85 88.4125)
		(width 0.1)
		(layer "B.Cu")
		(net 1)
	)
	(segment
		(start 112.39 112.09)
		(end 112.475 112.175)
		(width 0.15)
		(layer "B.Cu")
		(net 1)
	)
	(segment
		(start 96.34 125.74)
		(end 96.275 125.675)
		(width 0.2)
		(layer "B.Cu")
		(net 1)
	)
	(segment
		(start 133.089 121.564)
		(end 133.075 121.55)
		(width 0.2)
		(layer "B.Cu")
		(net 1)
	)
	(segment
		(start 98.29 109.675)
		(end 97.285009 109.675)
		(width 0.15)
		(layer "B.Cu")
		(net 1)
	)
	(segment
		(start 106.1 90.265)
		(end 106.865 90.265)
		(width 0.2)
		(layer "B.Cu")
		(net 1)
	)
	(segment
		(start 92.875 120.675)
		(end 92.875 121.275)
		(width 0.15)
		(layer "B.Cu")
		(net 1)
	)
	(segment
		(start 108.21 99.35)
		(end 108.21 100.11)
		(width 0.2)
		(layer "B.Cu")
		(net 1)
	)
	(segment
		(start 140.759 130.314)
		(end 140.759 131.414)
		(width 0.15)
		(layer "B.Cu")
		(net 1)
	)
	(segment
		(start 95.69 173.774)
		(end 95.728 173.736)
		(width 0.2)
		(layer "B.Cu")
		(net 1)
	)
	(segment
		(start 93.89 177.355)
		(end 93.89 172.526)
		(width 0.2)
		(layer "B.Cu")
		(net 1)
	)
	(segment
		(start 99.025 127.69)
		(end 99.025 126.925)
		(width 0.2)
		(layer "B.Cu")
		(net 1)
	)
	(segment
		(start 93.025 128.64)
		(end 92.31 128.64)
		(width 0.2)
		(layer "B.Cu")
		(net 1)
	)
	(segment
		(start 108.843 92.077)
		(end 108.204 92.077)
		(width 0.15)
		(layer "B.Cu")
		(net 1)
	)
	(segment
		(start 102.89 117.89)
		(end 102.275 117.89)
		(width 0.15)
		(layer "B.Cu")
		(net 1)
	)
	(segment
		(start 90.137667 122.712667)
		(end 90.137667 121.952333)
		(width 0.15)
		(layer "B.Cu")
		(net 1)
	)
	(segment
		(start 102.555 127.025)
		(end 103.275 126.305)
		(width 0.2)
		(layer "B.Cu")
		(net 1)
	)
	(segment
		(start 98.29 125.275)
		(end 98.29 124.69)
		(width 0.15)
		(layer "B.Cu")
		(net 1)
	)
	(segment
		(start 137.774 126.524)
		(end 137.784 126.514)
		(width 0.1)
		(layer "B.Cu")
		(net 1)
	)
	(segment
		(start 121.645 109.845)
		(end 120.915 109.115)
		(width 0.2)
		(layer "B.Cu")
		(net 1)
	)
	(segment
		(start 101.14 97.635)
		(end 101.14 97.186)
		(width 0.2)
		(layer "B.Cu")
		(net 1)
	)
	(segment
		(start 100.2 97.64)
		(end 100.2 96.85)
		(width 0.2)
		(layer "B.Cu")
		(net 1)
	)
	(segment
		(start 102.26 127.025)
		(end 102.555 127.025)
		(width 0.2)
		(layer "B.Cu")
		(net 1)
	)
	(segment
		(start 104.005 123.625)
		(end 104.005 123.758553)
		(width 0.15)
		(layer "B.Cu")
		(net 1)
	)
	(segment
		(start 132.19 177.345)
		(end 132.19 175.87)
		(width 0.2)
		(layer "B.Cu")
		(net 1)
	)
	(segment
		(start 70.09 86.53)
		(end 70.174 86.614)
		(width 0.2)
		(layer "B.Cu")
		(net 1)
	)
	(segment
		(start 133.99 177.345)
		(end 133.99 175.87)
		(width 0.2)
		(layer "B.Cu")
		(net 1)
	)
	(segment
		(start 96.2 98.67)
		(end 95.41 98.67)
		(width 0.2)
		(layer "B.Cu")
		(net 1)
	)
	(segment
		(start 106.875 120.055)
		(end 106.655 120.055)
		(width 0.15)
		(layer "B.Cu")
		(net 1)
	)
	(segment
		(start 97.955 120.675)
		(end 97.955 120.355)
		(width 0.15)
		(layer "B.Cu")
		(net 1)
	)
	(segment
		(start 75.395 154.79)
		(end 75.975 155.37)
		(width 0.15)
		(layer "B.Cu")
		(net 1)
	)
	(segment
		(start 96.66 146.86)
		(end 96.575 146.775)
		(width 0.2)
		(layer "B.Cu")
		(net 1)
	)
	(segment
		(start 103.275 126.305)
		(end 103.275 125.675)
		(width 0.2)
		(layer "B.Cu")
		(net 1)
	)
	(segment
		(start 103.71 90.305)
		(end 103.71 89.4)
		(width 0.2)
		(layer "B.Cu")
		(net 1)
	)
	(segment
		(start 123.365 128.815)
		(end 123.365 129.165)
		(width 0.2)
		(layer "B.Cu")
		(net 1)
	)
	(segment
		(start 95.69 177.355)
		(end 95.69 173.774)
		(width 0.2)
		(layer "B.Cu")
		(net 1)
	)
	(segment
		(start 102.275 117.89)
		(end 100.275 117.89)
		(width 0.15)
		(layer "B.Cu")
		(net 1)
	)
	(segment
		(start 90.137667 121.952333)
		(end 90.415 121.675)
		(width 0.15)
		(layer "B.Cu")
		(net 1)
	)
	(segment
		(start 100.005 120.675)
		(end 100.005 121.405)
		(width 0.15)
		(layer "B.Cu")
		(net 1)
	)
	(segment
		(start 110.78 87.44)
		(end 110.78 88.255)
		(width 0.2)
		(layer "B.Cu")
		(net 1)
	)
	(segment
		(start 92.8 120)
		(end 92.875 120.075)
		(width 0.2)
		(layer "B.Cu")
		(net 1)
	)
	(segment
		(start 109.28499 106.74)
		(end 109.29999 106.725)
		(width 0.15)
		(layer "B.Cu")
		(net 1)
	)
	(segment
		(start 103.19 118.19)
		(end 102.89 117.89)
		(width 0.15)
		(layer "B.Cu")
		(net 1)
	)
	(segment
		(start 102.275 112.7225)
		(end 102.765 113.2125)
		(width 0.2)
		(layer "B.Cu")
		(net 1)
	)
	(segment
		(start 90.275 111.99)
		(end 90.275 110.895)
		(width 0.15)
		(layer "B.Cu")
		(net 1)
	)
	(segment
		(start 111.78 87.425)
		(end 111.78 88.205)
		(width 0.2)
		(layer "B.Cu")
		(net 1)
	)
	(segment
		(start 102.275 112.675)
		(end 102.275 112.7225)
		(width 0.2)
		(layer "B.Cu")
		(net 1)
	)
	(segment
		(start 81.69 177.355)
		(end 81.69 175.79)
		(width 0.25)
		(layer "B.Cu")
		(net 1)
	)
	(segment
		(start 96.86 124.075)
		(end 96.86 124.26)
		(width 0.15)
		(layer "B.Cu")
		(net 1)
	)
	(segment
		(start 110.275 118.09)
		(end 110.69 117.675)
		(width 0.15)
		(layer "B.Cu")
		(net 1)
	)
	(segment
		(start 79.725 88.525)
		(end 80.225 88.525)
		(width 0.15)
		(layer "B.Cu")
		(net 1)
	)
	(segment
		(start 136.774 126.524)
		(end 136.784 126.514)
		(width 0.15)
		(layer "B.Cu")
		(net 1)
	)
	(segment
		(start 91.3 120)
		(end 92.8 120)
		(width 0.2)
		(layer "B.Cu")
		(net 1)
	)
	(segment
		(start 122.35 128.43)
		(end 123.065 127.715)
		(width 0.15)
		(layer "B.Cu")
		(net 1)
	)
	(segment
		(start 130.39 177.345)
		(end 130.39 175.87)
		(width 0.2)
		(layer "B.Cu")
		(net 1)
	)
	(segment
		(start 90.415 121.675)
		(end 90.69 121.675)
		(width 0.15)
		(layer "B.Cu")
		(net 1)
	)
	(segment
		(start 90.275 110.895)
		(end 91.495 109.675)
		(width 0.15)
		(layer "B.Cu")
		(net 1)
	)
	(segment
		(start 124.007 128.437)
		(end 123.743 128.437)
		(width 0.2)
		(layer "B.Cu")
		(net 1)
	)
	(segment
		(start 82.425 97.325)
		(end 81.827 97.325)
		(width 0.2)
		(layer "B.Cu")
		(net 1)
	)
	(segment
		(start 93.275 124.36)
		(end 93.29 124.375)
		(width 0.15)
		(layer "B.Cu")
		(net 1)
	)
	(segment
		(start 73.559 84.377)
		(end 75.244 84.377)
		(width 0.2)
		(layer "B.Cu")
		(net 1)
	)
	(segment
		(start 97.045 122.905)
		(end 97.275 122.675)
		(width 0.15)
		(layer "B.Cu")
		(net 1)
	)
	(segment
		(start 108.21 100.11)
		(end 108.225 100.125)
		(width 0.2)
		(layer "B.Cu")
		(net 1)
	)
	(segment
		(start 104.921447 124.675)
		(end 105.275 124.675)
		(width 0.15)
		(layer "B.Cu")
		(net 1)
	)
	(segment
		(start 124.055 109.86)
		(end 124.065 109.85)
		(width 0.2)
		(layer "B.Cu")
		(net 1)
	)
	(segment
		(start 90.137667 122.712667)
		(end 90.175334 122.675)
		(width 0.15)
		(layer "B.Cu")
		(net 1)
	)
	(segment
		(start 112.225 121.625001)
		(end 112.225 121.14)
		(width 0.2)
		(layer "B.Cu")
		(net 1)
	)
	(segment
		(start 75.244 84.377)
		(end 75.254 84.367)
		(width 0.2)
		(layer "B.Cu")
		(net 1)
	)
	(segment
		(start 98.275 117.99)
		(end 97.955 117.99)
		(width 0.15)
		(layer "B.Cu")
		(net 1)
	)
	(segment
		(start 141.774 122.514)
		(end 140.774 121.514)
		(width 0.2)
		(layer "In5.Cu")
		(net 1)
	)
	(segment
		(start 140.774 121.160447)
		(end 140.327553 120.714)
		(width 0.2)
		(layer "In5.Cu")
		(net 1)
	)
	(segment
		(start 137.774 122.160447)
		(end 136.327553 120.714)
		(width 0.2)
		(layer "In5.Cu")
		(net 1)
	)
	(segment
		(start 135.774 122.514)
		(end 135.323999 122.063999)
		(width 0.2)
		(layer "In5.Cu")
		(net 1)
	)
	(segment
		(start 135.774 125.514)
		(end 135.774 125.160447)
		(width 0.2)
		(layer "In5.Cu")
		(net 1)
	)
	(segment
		(start 135.974 120.714)
		(end 140.074 120.714)
		(width 0.2)
		(layer "In5.Cu")
		(net 1)
	)
	(segment
		(start 136.274 123.014)
		(end 135.774 122.514)
		(width 0.2)
		(layer "In5.Cu")
		(net 1)
	)
	(segment
		(start 137.774 122.514)
		(end 137.774 122.160447)
		(width 0.2)
		(layer "In5.Cu")
		(net 1)
	)
	(segment
		(start 135.323999 120.063999)
		(end 135.274 120.014)
		(width 0.2)
		(layer "In5.Cu")
		(net 1)
	)
	(segment
		(start 141.274 123.014)
		(end 141.774 122.514)
		(width 0.2)
		(layer "In5.Cu")
		(net 1)
	)
	(segment
		(start 141.574 120.714)
		(end 142.774 119.514)
		(width 0.2)
		(layer "In5.Cu")
		(net 1)
	)
	(segment
		(start 135.323999 122.063999)
		(end 135.323999 120.063999)
		(width 0.2)
		(layer "In5.Cu")
		(net 1)
	)
	(segment
		(start 136.327553 120.714)
		(end 135.974 120.714)
		(width 0.2)
		(layer "In5.Cu")
		(net 1)
	)
	(segment
		(start 140.774 121.514)
		(end 140.774 121.160447)
		(width 0.2)
		(layer "In5.Cu")
		(net 1)
	)
	(segment
		(start 135.774 125.160447)
		(end 136.274 124.660447)
		(width 0.2)
		(layer "In5.Cu")
		(net 1)
	)
	(segment
		(start 140.074 120.714)
		(end 141.574 120.714)
		(width 0.2)
		(layer "In5.Cu")
		(net 1)
	)
	(segment
		(start 134.774 119.514)
		(end 135.974 120.714)
		(width 0.2)
		(layer "In5.Cu")
		(net 1)
	)
	(segment
		(start 141.274 124.660447)
		(end 141.274 123.014)
		(width 0.2)
		(layer "In5.Cu")
		(net 1)
	)
	(segment
		(start 140.327553 120.714)
		(end 140.074 120.714)
		(width 0.2)
		(layer "In5.Cu")
		(net 1)
	)
	(segment
		(start 141.774 125.514)
		(end 141.774 125.160447)
		(width 0.2)
		(layer "In5.Cu")
		(net 1)
	)
	(segment
		(start 136.274 124.660447)
		(end 136.274 123.014)
		(width 0.2)
		(layer "In5.Cu")
		(net 1)
	)
	(segment
		(start 141.774 125.160447)
		(end 141.274 124.660447)
		(width 0.2)
		(layer "In5.Cu")
		(net 1)
	)
	(segment
		(start 108.775 128.175)
		(end 109.275 128.675)
		(width 0.15)
		(layer "F.Cu")
		(net 2)
	)
	(segment
		(start 102.775 110.175)
		(end 103.275 110.675)
		(width 0.15)
		(layer "F.Cu")
		(net 2)
	)
	(segment
		(start 105.775 109.175)
		(end 106.275 108.675)
		(width 0.15)
		(layer "F.Cu")
		(net 2)
	)
	(segment
		(start 105.775 129.175)
		(end 106.275 128.675)
		(width 0.15)
		(layer "F.Cu")
		(net 2)
	)
	(segment
		(start 72.675 87.875)
		(end 71.951 87.875)
		(width 0.2)
		(layer "F.Cu")
		(net 2)
	)
	(segment
		(start 64.545 124.4801)
		(end 64.545 125.675)
		(width 0.2)
		(layer "F.Cu")
		(net 2)
	)
	(segment
		(start 141.274 120.014)
		(end 141.274 119.424)
		(width 0.1)
		(layer "F.Cu")
		(net 2)
	)
	(segment
		(start 136.274 120.014)
		(end 136.274 119.424)
		(width 0.1)
		(layer "F.Cu")
		(net 2)
	)
	(segment
		(start 142.284 123.014)
		(end 142.774 122.524)
		(width 0.15)
		(layer "F.Cu")
		(net 2)
	)
	(segment
		(start 64.555 143.7401)
		(end 64.555 144.935)
		(width 0.2)
		(layer "F.Cu")
		(net 2)
	)
	(segment
		(start 106.775 112.175)
		(end 107.275 112.675)
		(width 0.15)
		(layer "F.Cu")
		(net 2)
	)
	(segment
		(start 90.775 114.175)
		(end 90.275 113.675)
		(width 0.15)
		(layer "F.Cu")
		(net 2)
	)
	(segment
		(start 104.775 116.175)
		(end 105.275 115.675)
		(width 0.15)
		(layer "F.Cu")
		(net 2)
	)
	(segment
		(start 101.775 117.175)
		(end 102.275 116.675)
		(width 0.15)
		(layer "F.Cu")
		(net 2)
	)
	(segment
		(start 143.05 64.215)
		(end 143.05 65.08)
		(width 0.15)
		(layer "F.Cu")
		(net 2)
	)
	(segment
		(start 107.775 125.175)
		(end 107.275 124.675)
		(width 0.15)
		(layer "F.Cu")
		(net 2)
	)
	(segment
		(start 98.125 116.655)
		(end 95.465 116.655)
		(width 0.15)
		(layer "F.Cu")
		(net 2)
	)
	(segment
		(start 123.225 124.249158)
		(end 123.075565 124.099723)
		(width 0.15)
		(layer "F.Cu")
		(net 2)
	)
	(segment
		(start 129.45 93.0125)
		(end 128.35 94.1125)
		(width 0.1)
		(layer "F.Cu")
		(net 2)
	)
	(segment
		(start 139.625 106.575)
		(end 139.625 105.685)
		(width 0.2)
		(layer "F.Cu")
		(net 2)
	)
	(segment
		(start 136.264 128.014)
		(end 135.774 128.504)
		(width 0.15)
		(layer "F.Cu")
		(net 2)
	)
	(segment
		(start 90.33 169.45)
		(end 90.33 166.35)
		(width 0.2)
		(layer "F.Cu")
		(net 2)
	)
	(segment
		(start 105.775 119.175)
		(end 106.275 118.675)
		(width 0.15)
		(layer "F.Cu")
		(net 2)
	)
	(segment
		(start 105.76 160.275)
		(end 105.76 159.275)
		(width 0.15)
		(layer "F.Cu")
		(net 2)
	)
	(segment
		(start 117 157.2)
		(end 117 156.1)
		(width 0.2)
		(layer "F.Cu")
		(net 2)
	)
	(segment
		(start 96.275 93.55)
		(end 96.275 92.829998)
		(width 0.2)
		(layer "F.Cu")
		(net 2)
	)
	(segment
		(start 130.1875 93.05)
		(end 130.15 93.0125)
		(width 0.1)
		(layer "F.Cu")
		(net 2)
	)
	(segment
		(start 109.775 121.175)
		(end 110.19999 120.75001)
		(width 0.15)
		(layer "F.Cu")
		(net 2)
	)
	(segment
		(start 132.275 154.915)
		(end 132.935 154.915)
		(width 0.2)
		(layer "F.Cu")
		(net 2)
	)
	(segment
		(start 90.105 164.39)
		(end 90.105 164.005)
		(width 0.2)
		(layer "F.Cu")
		(net 2)
	)
	(segment
		(start 132 155.19)
		(end 132.275 154.915)
		(width 0.2)
		(layer "F.Cu")
		(net 2)
	)
	(segment
		(start 82.715 162.915)
		(end 81.395 161.595)
		(width 0.2)
		(layer "F.Cu")
		(net 2)
	)
	(segment
		(start 105.76 159.275)
		(end 106.475 159.275)
		(width 0.2)
		(layer "F.Cu")
		(net 2)
	)
	(segment
		(start 132 157.2)
		(end 132 155.19)
		(width 0.2)
		(layer "F.Cu")
		(net 2)
	)
	(segment
		(start 140.865 98.0125)
		(end 140.45 98.0125)
		(width 0.1)
		(layer "F.Cu")
		(net 2)
	)
	(segment
		(start 123.425 108.325)
		(end 123.075 107.975)
		(width 0.15)
		(layer "F.Cu")
		(net 2)
	)
	(segment
		(start 72.195 97.995)
		(end 72.665 97.995)
		(width 0.2)
		(layer "F.Cu")
		(net 2)
	)
	(segment
		(start 122.5 153.25)
		(end 122.775 152.975)
		(width 0.15)
		(layer "F.Cu")
		(net 2)
	)
	(segment
		(start 134.5 155.235)
		(end 134.77 154.965)
		(width 0.2)
		(layer "F.Cu")
		(net 2)
	)
	(segment
		(start 107.775 115.175)
		(end 107.275 115.675)
		(width 0.15)
		(layer "F.Cu")
		(net 2)
	)
	(segment
		(start 108.775 118.175)
		(end 108.275 118.675)
		(width 0.15)
		(layer "F.Cu")
		(net 2)
	)
	(segment
		(start 131.45 88.2275)
		(end 131.45 87.6125)
		(width 0.2)
		(layer "F.Cu")
		(net 2)
	)
	(segment
		(start 128.35 94.1125)
		(end 127.935 94.1125)
		(width 0.1)
		(layer "F.Cu")
		(net 2)
	)
	(segment
		(start 139.9125 98.55)
		(end 139.45 98.55)
		(width 0.1)
		(layer "F.Cu")
		(net 2)
	)
	(segment
		(start 135 155.195)
		(end 134.77 154.965)
		(width 0.2)
		(layer "F.Cu")
		(net 2)
	)
	(segment
		(start 104.29 158.775)
		(end 104.79 158.275)
		(width 0.2)
		(layer "F.Cu")
		(net 2)
	)
	(segment
		(start 130.46 116.775)
		(end 130.46 117.36)
		(width 0.15)
		(layer "F.Cu")
		(net 2)
	)
	(segment
		(start 68.072 154.35212)
		(end 68.072 153.133)
		(width 0.15)
		(layer "F.Cu")
		(net 2)
	)
	(segment
		(start 111.775 117.175)
		(end 112.275 117.675)
		(width 0.15)
		(layer "F.Cu")
		(net 2)
	)
	(segment
		(start 123.425 108.94)
		(end 123.425 108.325)
		(width 0.15)
		(layer "F.Cu")
		(net 2)
	)
	(segment
		(start 68.572 155.608)
		(end 68.365 155.815)
		(width 0.15)
		(layer "F.Cu")
		(net 2)
	)
	(segment
		(start 90.105 166.125)
		(end 90.105 164.39)
		(width 0.2)
		(layer "F.Cu")
		(net 2)
	)
	(segment
		(start 141.264 128.014)
		(end 140.774 128.504)
		(width 0.15)
		(layer "F.Cu")
		(net 2)
	)
	(segment
		(start 93.775 113.175)
		(end 94.275 112.675)
		(width 0.15)
		(layer "F.Cu")
		(net 2)
	)
	(segment
		(start 90.14 162.865)
		(end 90.465 162.865)
		(width 0.2)
		(layer "F.Cu")
		(net 2)
	)
	(segment
		(start 100.775 114.175)
		(end 101.275 113.675)
		(width 0.15)
		(layer "F.Cu")
		(net 2)
	)
	(segment
		(start 125.725 130.725)
		(end 125.875 130.875)
		(width 0.15)
		(layer "F.Cu")
		(net 2)
	)
	(segment
		(start 136.274 126.014)
		(end 136.274 125.976)
		(width 0.2)
		(layer "F.Cu")
		(net 2)
	)
	(segment
		(start 72.675 93.925)
		(end 71.951 93.925)
		(width 0.2)
		(layer "F.Cu")
		(net 2)
	)
	(segment
		(start 93.264991 109.685009)
		(end 93.275 109.685009)
		(width 0.15)
		(layer "F.Cu")
		(net 2)
	)
	(segment
		(start 141.025 64.19)
		(end 141.025 65.055)
		(width 0.15)
		(layer "F.Cu")
		(net 2)
	)
	(segment
		(start 128.525 110.625)
		(end 128.575 110.675)
		(width 0.15)
		(layer "F.Cu")
		(net 2)
	)
	(segment
		(start 81.167 99.475)
		(end 81.179 99.487)
		(width 0.2)
		(layer "F.Cu")
		(net 2)
	)
	(segment
		(start 90.105 164.005)
		(end 89.79 163.69)
		(width 0.2)
		(layer "F.Cu")
		(net 2)
	)
	(segment
		(start 72.665 89.915)
		(end 71.941 89.915)
		(width 0.2)
		(layer "F.Cu")
		(net 2)
	)
	(segment
		(start 123.225 129.91)
		(end 123.225 130.555)
		(width 0.2)
		(layer "F.Cu")
		(net 2)
	)
	(segment
		(start 127.935 94.7975)
		(end 127.95 94.8125)
		(width 0.1)
		(layer "F.Cu")
		(net 2)
	)
	(segment
		(start 90.36 169.48)
		(end 90.33 169.45)
		(width 0.2)
		(layer "F.Cu")
		(net 2)
	)
	(segment
		(start 91.775 117.175)
		(end 91.275 116.675)
		(width 0.15)
		(layer "F.Cu")
		(net 2)
	)
	(segment
		(start 98.275 116.805)
		(end 98.125 116.655)
		(width 0.15)
		(layer "F.Cu")
		(net 2)
	)
	(segment
		(start 140.865 97.3275)
		(end 140.85 97.3125)
		(width 0.1)
		(layer "F.Cu")
		(net 2)
	)
	(segment
		(start 83.79 164.59)
		(end 83.865 164.515)
		(width 0.2)
		(layer "F.Cu")
		(net 2)
	)
	(segment
		(start 104.79 158.275)
		(end 104.79 157.59)
		(width 0.2)
		(layer "F.Cu")
		(net 2)
	)
	(segment
		(start 95.5 97.605)
		(end 95.3 97.605)
		(width 0.2)
		(layer "F.Cu")
		(net 2)
	)
	(segment
		(start 135.35 101.3275)
		(end 134.565 101.3275)
		(width 0.1)
		(layer "F.Cu")
		(net 2)
	)
	(segment
		(start 103.775 113.175)
		(end 103.275 113.675)
		(width 0.15)
		(layer "F.Cu")
		(net 2)
	)
	(segment
		(start 68.072 153.133)
		(end 68.29 152.915)
		(width 0.15)
		(layer "F.Cu")
		(net 2)
	)
	(segment
		(start 140.865 98.0125)
		(end 140.865 97.3275)
		(width 0.1)
		(layer "F.Cu")
		(net 2)
	)
	(segment
		(start 82.06 109.595)
		(end 82.06 110.58)
		(width 0.5)
		(layer "F.Cu")
		(net 2)
	)
	(segment
		(start 104.775 126.175)
		(end 105.275 125.675)
		(width 0.15)
		(layer "F.Cu")
		(net 2)
	)
	(segment
		(start 135.274 123.004)
		(end 134.784 122.514)
		(width 0.15)
		(layer "F.Cu")
		(net 2)
	)
	(segment
		(start 96.275 96.435)
		(end 96.275 96.83)
		(width 0.2)
		(layer "F.Cu")
		(net 2)
	)
	(segment
		(start 96.275 96.83)
		(end 95.5 97.605)
		(width 0.2)
		(layer "F.Cu")
		(net 2)
	)
	(segment
		(start 123.075 107.975)
		(end 122.975 107.975)
		(width 0.15)
		(layer "F.Cu")
		(net 2)
	)
	(segment
		(start 135.264 128.014)
		(end 134.774 128.504)
		(width 0.15)
		(layer "F.Cu")
		(net 2)
	)
	(segment
		(start 81.395 161.595)
		(end 74.79 161.595)
		(width 0.2)
		(layer "F.Cu")
		(net 2)
	)
	(segment
		(start 118 157.2)
		(end 118 156.1)
		(width 0.2)
		(layer "F.Cu")
		(net 2)
	)
	(segment
		(start 83.86 109.61)
		(end 83.86 110.58)
		(width 0.5)
		(layer "F.Cu")
		(net 2)
	)
	(segment
		(start 136.274 125.976)
		(end 136.775 125.475)
		(width 0.2)
		(layer "F.Cu")
		(net 2)
	)
	(segment
		(start 128.235 98.6125)
		(end 128.235 97.9275)
		(width 0.1)
		(layer "F.Cu")
		(net 2)
	)
	(segment
		(start 128.125 126.725)
		(end 128.175 126.775)
		(width 0.15)
		(layer "F.Cu")
		(net 2)
	)
	(segment
		(start 139.264 128.014)
		(end 138.774 128.504)
		(width 0.15)
		(layer "F.Cu")
		(net 2)
	)
	(segment
		(start 89.79 163.69)
		(end 89.79 163.215)
		(width 0.2)
		(layer "F.Cu")
		(net 2)
	)
	(segment
		(start 139.55 160.465)
		(end 139.55 159.63)
		(width 0.15)
		(layer "F.Cu")
		(net 2)
	)
	(segment
		(start 125.950001 114.350001)
		(end 125.950001 114.950001)
		(width 0.15)
		(layer "F.Cu")
		(net 2)
	)
	(segment
		(start 103.85 99.074502)
		(end 103.85 99.724)
		(width 0.15)
		(layer "F.Cu")
		(net 2)
	)
	(segment
		(start 131 157.2)
		(end 131 155.035)
		(width 0.2)
		(layer "F.Cu")
		(net 2)
	)
	(segment
		(start 73.74 161.575)
		(end 72.38 161.575)
		(width 0.2)
		(layer "F.Cu")
		(net 2)
	)
	(segment
		(start 95.465 116.655)
		(end 95.275 116.465)
		(width 0.15)
		(layer "F.Cu")
		(net 2)
	)
	(segment
		(start 84.89 164.79)
		(end 84.89 164.19)
		(width 0.2)
		(layer "F.Cu")
		(net 2)
	)
	(segment
		(start 94.775 116.175)
		(end 95.275 115.675)
		(width 0.15)
		(layer "F.Cu")
		(net 2)
	)
	(segment
		(start 134.565 101.3275)
		(end 134.55 101.3125)
		(width 0.1)
		(layer "F.Cu")
		(net 2)
	)
	(segment
		(start 98.825 118.225)
		(end 98.275 117.675)
		(width 0.15)
		(layer "F.Cu")
		(net 2)
	)
	(segment
		(start 131 155.035)
		(end 131.175 154.86)
		(width 0.2)
		(layer "F.Cu")
		(net 2)
	)
	(segment
		(start 125.950001 114.950001)
		(end 126.475 115.475)
		(width 0.15)
		(layer "F.Cu")
		(net 2)
	)
	(segment
		(start 68.572 154.35212)
		(end 68.572 155.608)
		(width 0.15)
		(layer "F.Cu")
		(net 2)
	)
	(segment
		(start 103.5125 158.775)
		(end 104.29 158.775)
		(width 0.2)
		(layer "F.Cu")
		(net 2)
	)
	(segment
		(start 141.274 126.004)
		(end 140.784 125.514)
		(width 0.15)
		(layer "F.Cu")
		(net 2)
	)
	(segment
		(start 95.775 119.175)
		(end 96.275 119.675)
		(width 0.15)
		(layer "F.Cu")
		(net 2)
	)
	(segment
		(start 122.64 132.64)
		(end 122.685 132.685)
		(width 0.15)
		(layer "F.Cu")
		(net 2)
	)
	(segment
		(start 110.775 114.175)
		(end 111.275 113.675)
		(width 0.15)
		(layer "F.Cu")
		(net 2)
	)
	(segment
		(start 135.35 99.7125)
		(end 135.35 101.3275)
		(width 0.1)
		(layer "F.Cu")
		(net 2)
	)
	(segment
		(start 95.275 116.465)
		(end 95.275 115.675)
		(width 0.15)
		(layer "F.Cu")
		(net 2)
	)
	(segment
		(start 123.225 125.04)
		(end 123.225 124.249158)
		(width 0.15)
		(layer "F.Cu")
		(net 2)
	)
	(segment
		(start 117 156.1)
		(end 116.975 156.075)
		(width 0.2)
		(layer "F.Cu")
		(net 2)
	)
	(segment
		(start 117.475 155.06)
		(end 117.475 156.075)
		(width 0.2)
		(layer "F.Cu")
		(net 2)
	)
	(segment
		(start 111.775 127.175)
		(end 114.93601 127.175)
		(width 0.15)
		(layer "F.Cu")
		(net 2)
	)
	(segment
		(start 138.625 106.575)
		(end 138.625 105.685)
		(width 0.2)
		(layer "F.Cu")
		(net 2)
	)
	(segment
		(start 138.975 64.19)
		(end 138.975 65.055)
		(width 0.15)
		(layer "F.Cu")
		(net 2)
	)
	(segment
		(start 137.264 128.014)
		(end 136.774 128.504)
		(width 0.15)
		(layer "F.Cu")
		(net 2)
	)
	(segment
		(start 99.775 111.175)
		(end 99.275 110.675)
		(width 0.15)
		(layer "F.Cu")
		(net 2)
	)
	(segment
		(start 127.41 126.725)
		(end 128.125 126.725)
		(width 0.15)
		(layer "F.Cu")
		(net 2)
	)
	(segment
		(start 129.06 132.475)
		(end 129.675 132.475)
		(width 0.15)
		(layer "F.Cu")
		(net 2)
	)
	(segment
		(start 122.85 115.93)
		(end 122.855 115.935)
		(width 0.15)
		(layer "F.Cu")
		(net 2)
	)
	(segment
		(start 140.45 98.0125)
		(end 139.9125 98.55)
		(width 0.1)
		(layer "F.Cu")
		(net 2)
	)
	(segment
		(start 72.665 95.965)
		(end 71.941 95.965)
		(width 0.2)
		(layer "F.Cu")
		(net 2)
	)
	(segment
		(start 140.8275 95.55)
		(end 140.865 95.5125)
		(width 0.1)
		(layer "F.Cu")
		(net 2)
	)
	(segment
		(start 110.19999 120.75001)
		(end 110.275 120.75001)
		(width 0.15)
		(layer "F.Cu")
		(net 2)
	)
	(segment
		(start 134.5 157.2)
		(end 134.5 155.235)
		(width 0.2)
		(layer "F.Cu")
		(net 2)
	)
	(segment
		(start 140.865 95.5125)
		(end 140.865 94.8275)
		(width 0.1)
		(layer "F.Cu")
		(net 2)
	)
	(segment
		(start 125.725 129.91)
		(end 125.725 130.725)
		(width 0.15)
		(layer "F.Cu")
		(net 2)
	)
	(segment
		(start 98.672851 94.975)
		(end 97.875 94.975)
		(width 0.15)
		(layer "F.Cu")
		(net 2)
	)
	(segment
		(start 140.865 94.8275)
		(end 140.85 94.8125)
		(width 0.1)
		(layer "F.Cu")
		(net 2)
	)
	(segment
		(start 72.665 91.905)
		(end 71.941 91.905)
		(width 0.2)
		(layer "F.Cu")
		(net 2)
	)
	(segment
		(start 83.55 163.965)
		(end 84.365 163.965)
		(width 0.2)
		(layer "F.Cu")
		(net 2)
	)
	(segment
		(start 135 157.2)
		(end 135 155.195)
		(width 0.2)
		(layer "F.Cu")
		(net 2)
	)
	(segment
		(start 123.225 130.555)
		(end 122.865 130.915)
		(width 0.2)
		(layer "F.Cu")
		(net 2)
	)
	(segment
		(start 139.0125 95.55)
		(end 140.8275 95.55)
		(width 0.1)
		(layer "F.Cu")
		(net 2)
	)
	(segment
		(start 125.925 114.325)
		(end 125.950001 114.350001)
		(width 0.15)
		(layer "F.Cu")
		(net 2)
	)
	(segment
		(start 127.61 110.625)
		(end 128.525 110.625)
		(width 0.15)
		(layer "F.Cu")
		(net 2)
	)
	(segment
		(start 109.775 111.175)
		(end 110.275 110.675)
		(width 0.15)
		(layer "F.Cu")
		(net 2)
	)
	(segment
		(start 74.79 161.595)
		(end 73.79 161.595)
		(width 0.2)
		(layer "F.Cu")
		(net 2)
	)
	(segment
		(start 92.775 110.175)
		(end 93.264991 109.685009)
		(width 0.15)
		(layer "F.Cu")
		(net 2)
	)
	(segment
		(start 83.115 164.59)
		(end 83.79 164.59)
		(width 0.2)
		(layer "F.Cu")
		(net 2)
	)
	(segment
		(start 131.5 157.2)
		(end 131.5 154.865)
		(width 0.2)
		(layer "F.Cu")
		(net 2)
	)
	(segment
		(start 120.965 132.64)
		(end 122.59 132.64)
		(width 0.2)
		(layer "F.Cu")
		(net 2)
	)
	(segment
		(start 114.93601 127.175)
		(end 114.94401 127.167)
		(width 0.15)
		(layer "F.Cu")
		(net 2)
	)
	(segment
		(start 98.275 117.675)
		(end 98.275 116.805)
		(width 0.15)
		(layer "F.Cu")
		(net 2)
	)
	(segment
		(start 97.875 94.975)
		(end 97.85 95)
		(width 0.15)
		(layer "F.Cu")
		(net 2)
	)
	(segment
		(start 131.275 154.86)
		(end 130.49 154.86)
		(width 0.2)
		(layer "F.Cu")
		(net 2)
	)
	(segment
		(start 110.775 124.175)
		(end 111.225 123.725)
		(width 0.15)
		(layer "F.Cu")
		(net 2)
	)
	(segment
		(start 104.79 157.59)
		(end 104.775 157.575)
		(width 0.2)
		(layer "F.Cu")
		(net 2)
	)
	(segment
		(start 84.89 164.19)
		(end 84.665 163.965)
		(width 0.2)
		(layer "F.Cu")
		(net 2)
	)
	(segment
		(start 128.2975 98.55)
		(end 128.235 98.6125)
		(width 0.1)
		(layer "F.Cu")
		(net 2)
	)
	(segment
		(start 142.264 128.014)
		(end 141.774 128.504)
		(width 0.15)
		(layer "F.Cu")
		(net 2)
	)
	(segment
		(start 134.77 154.965)
		(end 135.465 154.965)
		(width 0.2)
		(layer "F.Cu")
		(net 2)
	)
	(segment
		(start 90.33 166.35)
		(end 90.105 166.125)
		(width 0.2)
		(layer "F.Cu")
		(net 2)
	)
	(segment
		(start 82.065 109.6)
		(end 82.06 109.595)
		(width 0.5)
		(layer "F.Cu")
		(net 2)
	)
	(segment
		(start 123.54 153.01)
		(end 123.575 152.975)
		(width 0.15)
		(layer "F.Cu")
		(net 2)
	)
	(segment
		(start 111.225 123.725)
		(end 111.225 123.674998)
		(width 0.15)
		(layer "F.Cu")
		(net 2)
	)
	(segment
		(start 140.284 123.014)
		(end 140.774 122.524)
		(width 0.15)
		(layer "F.Cu")
		(net 2)
	)
	(segment
		(start 106.454016 97.475)
		(end 106.478668 97.450348)
		(width 0.15)
		(layer "F.Cu")
		(net 2)
	)
	(segment
		(start 132.935 154.915)
		(end 132.975 154.875)
		(width 0.2)
		(layer "F.Cu")
		(net 2)
	)
	(segment
		(start 83.15 163.565)
		(end 83.55 163.965)
		(width 0.2)
		(layer "F.Cu")
		(net 2)
	)
	(segment
		(start 122.685 131.685)
		(end 122.665 131.665)
		(width 0.2)
		(layer "F.Cu")
		(net 2)
	)
	(segment
		(start 122.865 114.915)
		(end 122.865 115.965)
		(width 0.2)
		(layer "F.Cu")
		(net 2)
	)
	(segment
		(start 84.665 163.965)
		(end 84.365 163.965)
		(width 0.2)
		(layer "F.Cu")
		(net 2)
	)
	(segment
		(start 80.175 99.475)
		(end 81.167 99.475)
		(width 0.2)
		(layer "F.Cu")
		(net 2)
	)
	(segment
		(start 130.15 93.0125)
		(end 129.45 93.0125)
		(width 0.1)
		(layer "F.Cu")
		(net 2)
	)
	(segment
		(start 139.45 98.55)
		(end 139.0125 98.55)
		(width 0.1)
		(layer "F.Cu")
		(net 2)
	)
	(segment
		(start 137.274 123.004)
		(end 136.784 122.514)
		(width 0.15)
		(layer "F.Cu")
		(net 2)
	)
	(segment
		(start 123.425 114.355)
		(end 122.865 114.915)
		(width 0.2)
		(layer "F.Cu")
		(net 2)
	)
	(segment
		(start 125.925 113.81)
		(end 125.925 114.325)
		(width 0.15)
		(layer "F.Cu")
		(net 2)
	)
	(segment
		(start 117.475 155.06)
		(end 116.99 155.06)
		(width 0.2)
		(layer "F.Cu")
		(net 2)
	)
	(segment
		(start 122.5 153.725)
		(end 122.5 153.25)
		(width 0.15)
		(layer "F.Cu")
		(net 2)
	)
	(segment
		(start 64.595 114.9601)
		(end 64.595 116.155)
		(width 0.2)
		(layer "F.Cu")
		(net 2)
	)
	(segment
		(start 127.935 94.1125)
		(end 127.935 94.7975)
		(width 0.1)
		(layer "F.Cu")
		(net 2)
	)
	(segment
		(start 105.527149 97.475)
		(end 106.454016 97.475)
		(width 0.15)
		(layer "F.Cu")
		(net 2)
	)
	(segment
		(start 96.775 112.175)
		(end 96.275 111.675)
		(width 0.15)
		(layer "F.Cu")
		(net 2)
	)
	(segment
		(start 89.79 163.215)
		(end 90.14 162.865)
		(width 0.2)
		(layer "F.Cu")
		(net 2)
	)
	(segment
		(start 122.855 117.835)
		(end 122.855 115.935)
		(width 0.15)
		(layer "F.Cu")
		(net 2)
	)
	(segment
		(start 96.275 92.829998)
		(end 96.25 92.804998)
		(width 0.2)
		(layer "F.Cu")
		(net 2)
	)
	(segment
		(start 116.99 155.06)
		(end 116.275 155.775)
		(width 0.2)
		(layer "F.Cu")
		(net 2)
	)
	(segment
		(start 132.5 157.2)
		(end 132.5 155.14)
		(width 0.2)
		(layer "F.Cu")
		(net 2)
	)
	(segment
		(start 118 156.1)
		(end 117.975 156.075)
		(width 0.2)
		(layer "F.Cu")
		(net 2)
	)
	(segment
		(start 140.264 128.014)
		(end 139.774 128.504)
		(width 0.15)
		(layer "F.Cu")
		(net 2)
	)
	(segment
		(start 83.86 110.58)
		(end 85.025 110.58)
		(width 0.5)
		(layer "F.Cu")
		(net 2)
	)
	(segment
		(start 117.5 156.1)
		(end 117.475 156.075)
		(width 0.2)
		(layer "F.Cu")
		(net 2)
	)
	(segment
		(start 132.5 155.14)
		(end 132.275 154.915)
		(width 0.2)
		(layer "F.Cu")
		(net 2)
	)
	(segment
		(start 130.1875 98.55)
		(end 128.2975 98.55)
		(width 0.1)
		(layer "F.Cu")
		(net 2)
	)
	(segment
		(start 97.775 115.175)
		(end 98.275 114.675)
		(width 0.15)
		(layer "F.Cu")
		(net 2)
	)
	(segment
		(start 71.865 97.665)
		(end 72.195 97.995)
		(width 0.2)
		(layer "F.Cu")
		(net 2)
	)
	(segment
		(start 72.38 161.575)
		(end 71.41 162.545)
		(width 0.2)
		(layer "F.Cu")
		(net 2)
	)
	(segment
		(start 123.425 113.81)
		(end 123.425 114.355)
		(width 0.2)
		(layer "F.Cu")
		(net 2)
	)
	(segment
		(start 122.685 132.685)
		(end 122.685 131.685)
		(width 0.2)
		(layer "F.Cu")
		(net 2)
	)
	(segment
		(start 95.775 109.175)
		(end 95.275 109.675)
		(width 0.15)
		(layer "F.Cu")
		(net 2)
	)
	(segment
		(start 121.305 115.93)
		(end 122.85 115.93)
		(width 0.15)
		(layer "F.Cu")
		(net 2)
	)
	(segment
		(start 82.74 162.915)
		(end 82.715 162.915)
		(width 0.2)
		(layer "F.Cu")
		(net 2)
	)
	(segment
		(start 64.565 134.1301)
		(end 64.565 135.325)
		(width 0.2)
		(layer "F.Cu")
		(net 2)
	)
	(segment
		(start 125.875 130.875)
		(end 125.875 131.375)
		(width 0.15)
		(layer "F.Cu")
		(net 2)
	)
	(segment
		(start 117.5 157.2)
		(end 117.5 156.1)
		(width 0.2)
		(layer "F.Cu")
		(net 2)
	)
	(segment
		(start 95.275 109.675)
		(end 95.275 109.685009)
		(width 0.15)
		(layer "F.Cu")
		(net 2)
	)
	(segment
		(start 128.235 97.9275)
		(end 128.25 97.9125)
		(width 0.1)
		(layer "F.Cu")
		(net 2)
	)
	(segment
		(start 83.85 109.6)
		(end 83.86 109.61)
		(width 0.5)
		(layer "F.Cu")
		(net 2)
	)
	(segment
		(start 138.264 128.014)
		(end 137.774 128.504)
		(width 0.15)
		(layer "F.Cu")
		(net 2)
	)
	(segment
		(start 130.49 154.86)
		(end 130.475 154.875)
		(width 0.2)
		(layer "F.Cu")
		(net 2)
	)
	(segment
		(start 131.495 154.86)
		(end 131.175 154.86)
		(width 0.2)
		(layer "F.Cu")
		(net 2)
	)
	(segment
		(start 135.465 154.965)
		(end 135.475 154.975)
		(width 0.2)
		(layer "F.Cu")
		(net 2)
	)
	(segment
		(start 131.5 154.865)
		(end 131.495 154.86)
		(width 0.2)
		(layer "F.Cu")
		(net 2)
	)
	(segment
		(start 116.275 155.775)
		(end 115.775 155.775)
		(width 0.2)
		(layer "F.Cu")
		(net 2)
	)
	(segment
		(start 122.685 134.585)
		(end 122.685 132.685)
		(width 0.15)
		(layer "F.Cu")
		(net 2)
	)
	(segment
		(start 123.54 153.725)
		(end 123.54 153.01)
		(width 0.15)
		(layer "F.Cu")
		(net 2)
	)
	(via blind
		(at 109.275 128.675)
		(size 0.5)
		(drill 0.2)
		(layers "F.Cu" "In1.Cu")
		(net 2)
	)
	(via
		(at 103.85 99.074502)
		(size 0.5)
		(drill 0.2)
		(layers "F.Cu" "B.Cu")
		(net 2)
	)
	(via
		(at 103.275 110.675)
		(size 0.5)
		(drill 0.2)
		(layers "F.Cu" "B.Cu")
		(net 2)
	)
	(via
		(at 106.275 108.675)
		(size 0.5)
		(drill 0.2)
		(layers "F.Cu" "B.Cu")
		(net 2)
	)
	(via
		(at 106.275 128.675)
		(size 0.5)
		(drill 0.2)
		(layers "F.Cu" "B.Cu")
		(net 2)
	)
	(via
		(at 71.69 115.4)
		(size 0.5)
		(drill 0.2)
		(layers "F.Cu" "B.Cu")
		(net 2)
	)
	(via
		(at 71.929 87.897)
		(size 0.5)
		(drill 0.2)
		(layers "F.Cu" "B.Cu")
		(net 2)
	)
	(via
		(at 64.555 125.685)
		(size 0.5)
		(drill 0.2)
		(layers "F.Cu" "B.Cu")
		(net 2)
	)
	(via
		(at 125.875 131.375)
		(size 0.5)
		(drill 0.2)
		(layers "F.Cu" "B.Cu")
		(net 2)
	)
	(via
		(at 144.124 120.974)
		(size 0.5)
		(drill 0.2)
		(layers "F.Cu" "B.Cu")
		(net 2)
	)
	(via
		(at 141.324 119.424)
		(size 0.5)
		(drill 0.2)
		(layers "F.Cu" "B.Cu")
		(net 2)
	)
	(via
		(at 136.274 119.424)
		(size 0.5)
		(drill 0.2)
		(layers "F.Cu" "B.Cu")
		(net 2)
	)
	(via
		(at 142.774 122.524)
		(size 0.5)
		(drill 0.2)
		(layers "F.Cu" "B.Cu")
		(net 2)
	)
	(via
		(at 64.565 144.945)
		(size 0.5)
		(drill 0.2)
		(layers "F.Cu" "B.Cu")
		(net 2)
	)
	(via
		(at 107.275 112.675)
		(size 0.5)
		(drill 0.2)
		(layers "F.Cu" "B.Cu")
		(net 2)
	)
	(via
		(at 90.275 113.675)
		(size 0.5)
		(drill 0.2)
		(layers "F.Cu" "B.Cu")
		(net 2)
	)
	(via
		(at 105.275 115.675)
		(size 0.5)
		(drill 0.2)
		(layers "F.Cu" "B.Cu")
		(net 2)
	)
	(via
		(at 102.275 116.675)
		(size 0.5)
		(drill 0.2)
		(layers "F.Cu" "B.Cu")
		(net 2)
	)
	(via
		(at 143.05 65.08)
		(size 0.5)
		(drill 0.2)
		(layers "F.Cu" "B.Cu")
		(net 2)
	)
	(via
		(at 107.275 124.675)
		(size 0.5)
		(drill 0.2)
		(layers "F.Cu" "B.Cu")
		(net 2)
	)
	(via
		(at 82.74 162.915)
		(size 0.5)
		(drill 0.2)
		(layers "F.Cu" "B.Cu")
		(net 2)
	)
	(via
		(at 112.4 136.4)
		(size 0.5)
		(drill 0.2)
		(layers "F.Cu" "B.Cu")
		(net 2)
	)
	(via
		(at 122.665 131.665)
		(size 0.5)
		(drill 0.2)
		(layers "F.Cu" "B.Cu")
		(net 2)
	)
	(via
		(at 112.4 134)
		(size 0.5)
		(drill 0.2)
		(layers "F.Cu" "B.Cu")
		(net 2)
	)
	(via
		(at 116.975 156.075)
		(size 0.5)
		(drill 0.2)
		(layers "F.Cu" "B.Cu")
		(net 2)
	)
	(via
		(at 94.275 112.675)
		(size 0.5)
		(drill 0.2)
		(layers "F.Cu" "B.Cu")
		(net 2)
	)
	(via
		(at 122.775 152.975)
		(size 0.5)
		(drill 0.2)
		(layers "F.Cu" "B.Cu")
		(net 2)
	)
	(via
		(at 95.275 115.675)
		(size 0.5)
		(drill 0.2)
		(layers "F.Cu" "B.Cu")
		(net 2)
	)
	(via
		(at 110.6 100.8)
		(size 0.5)
		(drill 0.2)
		(layers "F.Cu" "B.Cu")
		(net 2)
	)
	(via
		(at 90.7 131.1)
		(size 0.5)
		(drill 0.2)
		(layers "F.Cu" "B.Cu")
		(net 2)
	)
	(via
		(at 136.774 128.504)
		(size 0.5)
		(drill 0.2)
		(layers "F.Cu" "B.Cu")
		(net 2)
	)
	(via
		(at 126.475 115.475)
		(size 0.5)
		(drill 0.2)
		(layers "F.Cu" "B.Cu")
		(net 2)
	)
	(via
		(at 128.25 97.9125)
		(size 0.5)
		(drill 0.2)
		(layers "F.Cu" "B.Cu")
		(net 2)
	)
	(via
		(at 139.62 105.68)
		(size 0.5)
		(drill 0.2)
		(layers "F.Cu" "B.Cu")
		(net 2)
	)
	(via
		(at 110.275 110.675)
		(size 0.5)
		(drill 0.2)
		(layers "F.Cu" "B.Cu")
		(net 2)
	)
	(via
		(at 90.7 132.1)
		(size 0.5)
		(drill 0.2)
		(layers "F.Cu" "B.Cu")
		(net 2)
	)
	(via
		(at 71.625 124.95)
		(size 0.5)
		(drill 0.2)
		(layers "F.Cu" "B.Cu")
		(net 2)
	)
	(via
		(at 95.275 109.685009)
		(size 0.5)
		(drill 0.2)
		(layers "F.Cu" "B.Cu")
		(net 2)
	)
	(via
		(at 138.62 105.68)
		(size 0.5)
		(drill 0.2)
		(layers "F.Cu" "B.Cu")
		(net 2)
	)
	(via
		(at 71.929 93.947)
		(size 0.5)
		(drill 0.2)
		(layers "F.Cu" "B.Cu")
		(net 2)
	)
	(via
		(at 69.174 87.314)
		(size 0.5)
		(drill 0.2)
		(layers "F.Cu" "B.Cu")
		(net 2)
	)
	(via
		(at 122.865 114.915)
		(size 0.5)
		(drill 0.2)
		(layers "F.Cu" "B.Cu")
		(net 2)
	)
	(via
		(at 105.774 88.814)
		(size 0.5)
		(drill 0.2)
		(layers "F.Cu" "B.Cu")
		(net 2)
	)
	(via
		(at 83.85 109.6)
		(size 0.5)
		(drill 0.2)
		(layers "F.Cu" "B.Cu")
		(net 2)
	)
	(via
		(at 139.774 128.504)
		(size 0.5)
		(drill 0.2)
		(layers "F.Cu" "B.Cu")
		(net 2)
	)
	(via
		(at 111.275 113.675)
		(size 0.5)
		(drill 0.2)
		(layers "F.Cu" "B.Cu")
		(net 2)
	)
	(via
		(at 115.775 155.775)
		(size 0.5)
		(drill 0.2)
		(layers "F.Cu" "B.Cu")
		(net 2)
	)
	(via
		(at 71.675 122.275)
		(size 0.5)
		(drill 0.2)
		(layers "F.Cu" "B.Cu")
		(net 2)
	)
	(via
		(at 71.919 95.987)
		(size 0.5)
		(drill 0.2)
		(layers "F.Cu" "B.Cu")
		(net 2)
	)
	(via
		(at 110.6 102.4)
		(size 0.5)
		(drill 0.2)
		(layers "F.Cu" "B.Cu")
		(net 2)
	)
	(via
		(at 110.6 105.7)
		(size 0.5)
		(drill 0.2)
		(layers "F.Cu" "B.Cu")
		(net 2)
	)
	(via
		(at 81.179 99.487)
		(size 0.5)
		(drill 0.2)
		(layers "F.Cu" "B.Cu")
		(net 2)
	)
	(via
		(at 137.774 128.504)
		(size 0.5)
		(drill 0.2)
		(layers "F.Cu" "B.Cu")
		(net 2)
	)
	(via
		(at 132.975 154.875)
		(size 0.5)
		(drill 0.2)
		(layers "F.Cu" "B.Cu")
		(net 2)
	)
	(via
		(at 105.275 125.675)
		(size 0.5)
		(drill 0.2)
		(layers "F.Cu" "B.Cu")
		(net 2)
	)
	(via
		(at 68.29 152.915)
		(size 0.5)
		(drill 0.2)
		(layers "F.Cu" "B.Cu")
		(net 2)
	)
	(via
		(at 128.175 126.775)
		(size 0.5)
		(drill 0.2)
		(layers "F.Cu" "B.Cu")
		(net 2)
	)
	(via
		(at 82.100004 76.905)
		(size 0.5)
		(drill 0.2)
		(layers "F.Cu" "B.Cu")
		(net 2)
	)
	(via
		(at 112.275 117.675)
		(size 0.5)
		(drill 0.2)
		(layers "F.Cu" "B.Cu")
		(net 2)
	)
	(via
		(at 130.475 154.875)
		(size 0.5)
		(drill 0.2)
		(layers "F.Cu" "B.Cu")
		(net 2)
	)
	(via
		(at 103.275 113.675)
		(size 0.5)
		(drill 0.2)
		(layers "F.Cu" "B.Cu")
		(net 2)
	)
	(via
		(at 110.2 101.5)
		(size 0.5)
		(drill 0.2)
		(layers "F.Cu" "B.Cu")
		(net 2)
	)
	(via
		(at 76.775 147.175)
		(size 0.5)
		(drill 0.2)
		(layers "F.Cu" "B.Cu")
		(net 2)
	)
	(via
		(at 97.85 95)
		(size 0.5)
		(drill 0.2)
		(layers "F.Cu" "B.Cu")
		(net 2)
	)
	(via
		(at 114.94401 127.167)
		(size 0.5)
		(drill 0.2)
		(layers "F.Cu" "B.Cu")
		(net 2)
	)
	(via
		(at 112.4 131.6)
		(size 0.5)
		(drill 0.2)
		(layers "F.Cu" "B.Cu")
		(net 2)
	)
	(via
		(at 91.3 131.6)
		(size 0.5)
		(drill 0.2)
		(layers "F.Cu" "B.Cu")
		(net 2)
	)
	(via
		(at 91.3 132.1)
		(size 0.5)
		(drill 0.2)
		(layers "F.Cu" "B.Cu")
		(net 2)
	)
	(via
		(at 134.784 122.514)
		(size 0.5)
		(drill 0.2)
		(layers "F.Cu" "B.Cu")
		(net 2)
	)
	(via
		(at 139.565 159.615)
		(size 0.5)
		(drill 0.2)
		(layers "F.Cu" "B.Cu")
		(net 2)
	)
	(via
		(at 82.065 109.6)
		(size 0.5)
		(drill 0.2)
		(layers "F.Cu" "B.Cu")
		(net 2)
	)
	(via
		(at 134.774 128.504)
		(size 0.5)
		(drill 0.2)
		(layers "F.Cu" "B.Cu")
		(net 2)
	)
	(via
		(at 64.605 116.165)
		(size 0.5)
		(drill 0.2)
		(layers "F.Cu" "B.Cu")
		(net 2)
	)
	(via
		(at 110.6 99.4)
		(size 0.5)
		(drill 0.2)
		(layers "F.Cu" "B.Cu")
		(net 2)
	)
	(via
		(at 141.025 65.055)
		(size 0.5)
		(drill 0.2)
		(layers "F.Cu" "B.Cu")
		(net 2)
	)
	(via
		(at 112.4 132.2)
		(size 0.5)
		(drill 0.2)
		(layers "F.Cu" "B.Cu")
		(net 2)
	)
	(via
		(at 95.3 97.605)
		(size 0.5)
		(drill 0.2)
		(layers "F.Cu" "B.Cu")
		(net 2)
	)
	(via
		(at 71.41 162.545)
		(size 0.5)
		(drill 0.2)
		(layers "F.Cu" "B.Cu")
		(net 2)
	)
	(via
		(at 91.275 116.675)
		(size 0.5)
		(drill 0.2)
		(layers "F.Cu" "B.Cu")
		(net 2)
	)
	(via
		(at 96.25 92.804998)
		(size 0.5)
		(drill 0.2)
		(layers "F.Cu" "B.Cu")
		(net 2)
	)
	(via
		(at 106.275 118.675)
		(size 0.5)
		(drill 0.2)
		(layers "F.Cu" "B.Cu")
		(net 2)
	)
	(via
		(at 110.1 97.5)
		(size 0.5)
		(drill 0.2)
		(layers "F.Cu" "B.Cu")
		(net 2)
	)
	(via
		(at 136.784 122.514)
		(size 0.5)
		(drill 0.2)
		(layers "F.Cu" "B.Cu")
		(net 2)
	)
	(via
		(at 108.275 118.675)
		(size 0.5)
		(drill 0.2)
		(layers "F.Cu" "B.Cu")
		(net 2)
	)
	(via
		(at 101.275 113.675)
		(size 0.5)
		(drill 0.2)
		(layers "F.Cu" "B.Cu")
		(net 2)
	)
	(via
		(at 128.575 110.675)
		(size 0.5)
		(drill 0.2)
		(layers "F.Cu" "B.Cu")
		(net 2)
	)
	(via
		(at 112.4 132.8)
		(size 0.5)
		(drill 0.2)
		(layers "F.Cu" "B.Cu")
		(net 2)
	)
	(via
		(at 140.85 97.3125)
		(size 0.5)
		(drill 0.2)
		(layers "F.Cu" "B.Cu")
		(net 2)
	)
	(via
		(at 112.4 138.2)
		(size 0.5)
		(drill 0.2)
		(layers "F.Cu" "B.Cu")
		(net 2)
	)
	(via
		(at 106.478668 97.450348)
		(size 0.5)
		(drill 0.2)
		(layers "F.Cu" "B.Cu")
		(net 2)
	)
	(via
		(at 90.36 169.48)
		(size 0.5)
		(drill 0.2)
		(layers "F.Cu" "B.Cu")
		(net 2)
	)
	(via
		(at 140.774 128.504)
		(size 0.5)
		(drill 0.2)
		(layers "F.Cu" "B.Cu")
		(net 2)
	)
	(via
		(at 64.575 135.335)
		(size 0.5)
		(drill 0.2)
		(layers "F.Cu" "B.Cu")
		(net 2)
	)
	(via
		(at 136.775 125.475)
		(size 0.5)
		(drill 0.2)
		(layers "F.Cu" "B.Cu")
		(net 2)
	)
	(via
		(at 135.475 154.975)
		(size 0.5)
		(drill 0.2)
		(layers "F.Cu" "B.Cu")
		(net 2)
	)
	(via
		(at 110.275 120.75001)
		(size 0.5)
		(drill 0.2)
		(layers "F.Cu" "B.Cu")
		(net 2)
	)
	(via
		(at 110.1 100.1)
		(size 0.5)
		(drill 0.2)
		(layers "F.Cu" "B.Cu")
		(net 2)
	)
	(via
		(at 99.275 110.675)
		(size 0.5)
		(drill 0.2)
		(layers "F.Cu" "B.Cu")
		(net 2)
	)
	(via
		(at 71.515 143.985)
		(size 0.5)
		(drill 0.2)
		(layers "F.Cu" "B.Cu")
		(net 2)
	)
	(via
		(at 107.275 115.675)
		(size 0.5)
		(drill 0.2)
		(layers "F.Cu" "B.Cu")
		(net 2)
	)
	(via
		(at 84.365 163.965)
		(size 0.5)
		(drill 0.2)
		(layers "F.Cu" "B.Cu")
		(net 2)
	)
	(via
		(at 112.4 133.4)
		(size 0.5)
		(drill 0.2)
		(layers "F.Cu" "B.Cu")
		(net 2)
	)
	(via
		(at 71.865 97.665)
		(size 0.5)
		(drill 0.2)
		(layers "F.Cu" "B.Cu")
		(net 2)
	)
	(via
		(at 69.275 151.735)
		(size 0.5)
		(drill 0.2)
		(layers "F.Cu" "B.Cu")
		(net 2)
	)
	(via
		(at 96.275 119.675)
		(size 0.5)
		(drill 0.2)
		(layers "F.Cu" "B.Cu")
		(net 2)
	)
	(via
		(at 133.415 119.965)
		(size 0.5)
		(drill 0.2)
		(layers "F.Cu" "B.Cu")
		(net 2)
	)
	(via
		(at 133.774 125.014)
		(size 0.5)
		(drill 0.2)
		(layers "F.Cu" "B.Cu")
		(net 2)
	)
	(via
		(at 131.45 87.6125)
		(size 0.5)
		(drill 0.2)
		(layers "F.Cu" "B.Cu")
		(net 2)
	)
	(via
		(at 141.774 128.504)
		(size 0.5)
		(drill 0.2)
		(layers "F.Cu" "B.Cu")
		(net 2)
	)
	(via
		(at 110.2 103.2)
		(size 0.5)
		(drill 0.2)
		(layers "F.Cu" "B.Cu")
		(net 2)
	)
	(via
		(at 135.774 128.504)
		(size 0.5)
		(drill 0.2)
		(layers "F.Cu" "B.Cu")
		(net 2)
	)
	(via
		(at 110.6 104)
		(size 0.5)
		(drill 0.2)
		(layers "F.Cu" "B.Cu")
		(net 2)
	)
	(via
		(at 83.865 164.515)
		(size 0.5)
		(drill 0.2)
		(layers "F.Cu" "B.Cu")
		(net 2)
	)
	(via
		(at 138.774 128.504)
		(size 0.5)
		(drill 0.2)
		(layers "F.Cu" "B.Cu")
		(net 2)
	)
	(via
		(at 98.275 114.675)
		(size 0.5)
		(drill 0.2)
		(layers "F.Cu" "B.Cu")
		(net 2)
	)
	(via
		(at 122.865 130.915)
		(size 0.5)
		(drill 0.2)
		(layers "F.Cu" "B.Cu")
		(net 2)
	)
	(via
		(at 90.7 131.6)
		(size 0.5)
		(drill 0.2)
		(layers "F.Cu" "B.Cu")
		(net 2)
	)
	(via
		(at 70.975 141.195)
		(size 0.5)
		(drill 0.2)
		(layers "F.Cu" "B.Cu")
		(net 2)
	)
	(via
		(at 111.225 123.674998)
		(size 0.5)
		(drill 0.2)
		(layers "F.Cu" "B.Cu")
		(net 2)
	)
	(via
		(at 71.625 131.475)
		(size 0.5)
		(drill 0.2)
		(layers "F.Cu" "B.Cu")
		(net 2)
	)
	(via
		(at 117.975 156.075)
		(size 0.5)
		(drill 0.2)
		(layers "F.Cu" "B.Cu")
		(net 2)
	)
	(via
		(at 133.775 128.475)
		(size 0.5)
		(drill 0.2)
		(layers "F.Cu" "B.Cu")
		(net 2)
	)
	(via
		(at 92.489734 156.946266)
		(size 0.5)
		(drill 0.2)
		(layers "F.Cu" "B.Cu")
		(net 2)
	)
	(via
		(at 112.4 135.2)
		(size 0.5)
		(drill 0.2)
		(layers "F.Cu" "B.Cu")
		(net 2)
	)
	(via
		(at 106.875 106.075)
		(size 0.5)
		(drill 0.2)
		(layers "F.Cu" "B.Cu")
		(net 2)
	)
	(via
		(at 108.3 104.1)
		(size 0.5)
		(drill 0.2)
		(layers "F.Cu" "B.Cu")
		(net 2)
	)
	(via
		(at 129.675 132.475)
		(size 0.5)
		(drill 0.2)
		(layers "F.Cu" "B.Cu")
		(net 2)
	)
	(via
		(at 112.4 129.7)
		(size 0.5)
		(drill 0.2)
		(layers "F.Cu" "B.Cu")
		(net 2)
	)
	(via
		(at 140.784 125.514)
		(size 0.5)
		(drill 0.2)
		(layers "F.Cu" "B.Cu")
		(net 2)
	)
	(via
		(at 104.775 157.575)
		(size 0.5)
		(drill 0.2)
		(layers "F.Cu" "B.Cu")
		(net 2)
	)
	(via
		(at 134.55 101.3125)
		(size 0.5)
		(drill 0.2)
		(layers "F.Cu" "B.Cu")
		(net 2)
	)
	(via
		(at 71.685 134.59)
		(size 0.5)
		(drill 0.2)
		(layers "F.Cu" "B.Cu")
		(net 2)
	)
	(via
		(at 112.4 138.8)
		(size 0.5)
		(drill 0.2)
		(layers "F.Cu" "B.Cu")
		(net 2)
	)
	(via
		(at 122.975 107.975)
		(size 0.5)
		(drill 0.2)
		(layers "F.Cu" "B.Cu")
		(net 2)
	)
	(via
		(at 112.4 135.8)
		(size 0.5)
		(drill 0.2)
		(layers "F.Cu" "B.Cu")
		(net 2)
	)
	(via
		(at 112.4 134.6)
		(size 0.5)
		(drill 0.2)
		(layers "F.Cu" "B.Cu")
		(net 2)
	)
	(via
		(at 110.1 98.7)
		(size 0.5)
		(drill 0.2)
		(layers "F.Cu" "B.Cu")
		(net 2)
	)
	(via
		(at 123.075565 124.099723)
		(size 0.5)
		(drill 0.2)
		(layers "F.Cu" "B.Cu")
		(net 2)
	)
	(via
		(at 110.6 98.1)
		(size 0.5)
		(drill 0.2)
		(layers "F.Cu" "B.Cu")
		(net 2)
	)
	(via
		(at 138.975 65.055)
		(size 0.5)
		(drill 0.2)
		(layers "F.Cu" "B.Cu")
		(net 2)
	)
	(via
		(at 123.575 152.975)
		(size 0.5)
		(drill 0.2)
		(layers "F.Cu" "B.Cu")
		(net 2)
	)
	(via
		(at 93.275 109.685009)
		(size 0.5)
		(drill 0.2)
		(layers "F.Cu" "B.Cu")
		(net 2)
	)
	(via
		(at 112.4 137.6)
		(size 0.5)
		(drill 0.2)
		(layers "F.Cu" "B.Cu")
		(net 2)
	)
	(via
		(at 71.919 91.927)
		(size 0.5)
		(drill 0.2)
		(layers "F.Cu" "B.Cu")
		(net 2)
	)
	(via
		(at 139.85 88.7125)
		(size 0.5)
		(drill 0.2)
		(layers "F.Cu" "B.Cu")
		(net 2)
	)
	(via
		(at 130.469 117.467)
		(size 0.5)
		(drill 0.2)
		(layers "F.Cu" "B.Cu")
		(net 2)
	)
	(via
		(at 140.774 122.524)
		(size 0.5)
		(drill 0.2)
		(layers "F.Cu" "B.Cu")
		(net 2)
	)
	(via
		(at 112.4 139.4)
		(size 0.5)
		(drill 0.2)
		(layers "F.Cu" "B.Cu")
		(net 2)
	)
	(via
		(at 106.475 159.275)
		(size 0.5)
		(drill 0.2)
		(layers "F.Cu" "B.Cu")
		(net 2)
	)
	(via
		(at 96.275 111.675)
		(size 0.5)
		(drill 0.2)
		(layers "F.Cu" "B.Cu")
		(net 2)
	)
	(via
		(at 68.365 155.815)
		(size 0.5)
		(drill 0.2)
		(layers "F.Cu" "B.Cu")
		(net 2)
	)
	(via
		(at 127.95 94.8125)
		(size 0.5)
		(drill 0.2)
		(layers "F.Cu" "B.Cu")
		(net 2)
	)
	(via
		(at 112.4 137)
		(size 0.5)
		(drill 0.2)
		(layers "F.Cu" "B.Cu")
		(net 2)
	)
	(via
		(at 110.2 104.8)
		(size 0.5)
		(drill 0.2)
		(layers "F.Cu" "B.Cu")
		(net 2)
	)
	(via
		(at 71.919 89.937)
		(size 0.5)
		(drill 0.2)
		(layers "F.Cu" "B.Cu")
		(net 2)
	)
	(via
		(at 140.85 94.8125)
		(size 0.5)
		(drill 0.2)
		(layers "F.Cu" "B.Cu")
		(net 2)
	)
	(via
		(at 74.175 157.075)
		(size 0.5)
		(drill 0.2)
		(layers "F.Cu" "B.Cu")
		(net 2)
	)
	(via
		(at 69.174 85.214)
		(size 0.5)
		(drill 0.2)
		(layers "F.Cu" "B.Cu")
		(net 2)
	)
	(segment
		(start 71.675 116.125)
		(end 71.675 121.125)
		(width 0.2)
		(layer "B.Cu")
		(net 2)
	)
	(segment
		(start 71.675 116.125)
		(end 71.675 115.415)
		(width 0.2)
		(layer "B.Cu")
		(net 2)
	)
	(segment
		(start 64.555 126.585)
		(end 64.555 125.685)
		(width 0.2)
		(layer "B.Cu")
		(net 2)
	)
	(segment
		(start 140.299 121.014)
		(end 140.299 120.054)
		(width 0.2)
		(layer "B.Cu")
		(net 2)
	)
	(segment
		(start 140.299 120.054)
		(end 140.249 120.004)
		(width 0.2)
		(layer "B.Cu")
		(net 2)
	)
	(segment
		(start 141.274 119.424)
		(end 140.829 119.424)
		(width 0.2)
		(layer "B.Cu")
		(net 2)
	)
	(segment
		(start 140.829 119.424)
		(end 140.249 120.004)
		(width 0.2)
		(layer "B.Cu")
		(net 2)
	)
	(segment
		(start 136.274 119.424)
		(end 136.699 119.424)
		(width 0.2)
		(layer "B.Cu")
		(net 2)
	)
	(segment
		(start 136.699 119.424)
		(end 137.289 120.014)
		(width 0.2)
		(layer "B.Cu")
		(net 2)
	)
	(segment
		(start 137.259 121.024)
		(end 137.259 120.044)
		(width 0.2)
		(layer "B.Cu")
		(net 2)
	)
	(segment
		(start 137.259 120.044)
		(end 137.289 120.014)
		(width 0.2)
		(layer "B.Cu")
		(net 2)
	)
	(segment
		(start 64.565 145.845)
		(end 64.565 144.945)
		(width 0.2)
		(layer "B.Cu")
		(net 2)
	)
	(segment
		(start 71.68 134.595)
		(end 71.685 134.59)
		(width 0.2)
		(layer "B.Cu")
		(net 2)
	)
	(segment
		(start 108.3 103.385)
		(end 108.3 104.1)
		(width 0.2)
		(layer "B.Cu")
		(net 2)
	)
	(segment
		(start 71.725 150.311)
		(end 71.409 150.627)
		(width 0.2)
		(layer "B.Cu")
		(net 2)
	)
	(segment
		(start 140.275 123.023)
		(end 140.275 123.175)
		(width 0.2)
		(layer "B.Cu")
		(net 2)
	)
	(segment
		(start 68.575 85.24)
		(end 69.148 85.24)
		(width 0.2)
		(layer "B.Cu")
		(net 2)
	)
	(segment
		(start 135.294 122.004)
		(end 134.784 122.514)
		(width 0.15)
		(layer "B.Cu")
		(net 2)
	)
	(segment
		(start 105.336 88.814)
		(end 105.774 88.814)
		(width 0.2)
		(layer "B.Cu")
		(net 2)
	)
	(segment
		(start 121.35 130.15)
		(end 121.365 130.165)
		(width 0.2)
		(layer "B.Cu")
		(net 2)
	)
	(segment
		(start 103.275 113.535)
		(end 103.735 113.075)
		(width 0.15)
		(layer "B.Cu")
		(net 2)
	)
	(segment
		(start 126.945 113.925)
		(end 126.945 115.005)
		(width 0.15)
		(layer "B.Cu")
		(net 2)
	)
	(segment
		(start 111.66 117.675)
		(end 112.275 117.675)
		(width 0.15)
		(layer "B.Cu")
		(net 2)
	)
	(segment
		(start 142.774 123.044)
		(end 142.774 122.524)
		(width 0.2)
		(layer "B.Cu")
		(net 2)
	)
	(segment
		(start 103.29 116.675)
		(end 102.275 116.675)
		(width 0.15)
		(layer "B.Cu")
		(net 2)
	)
	(segment
		(start 92.46 158.875)
		(end 92.46 159.875)
		(width 0.15)
		(layer "B.Cu")
		(net 2)
	)
	(segment
		(start 71.68 135.315)
		(end 71.68 134.595)
		(width 0.2)
		(layer "B.Cu")
		(net 2)
	)
	(segment
		(start 71.635 124.96)
		(end 71.625 124.95)
		(width 0.2)
		(layer "B.Cu")
		(net 2)
	)
	(segment
		(start 71.675 121.135)
		(end 71.675 122.275)
		(width 0.2)
		(layer "B.Cu")
		(net 2)
	)
	(segment
		(start 107.29 112.675)
		(end 107.79 112.175)
		(width 0.15)
		(layer "B.Cu")
		(net 2)
	)
	(segment
		(start 140.774 127.999)
		(end 140.774 128.504)
		(width 0.15)
		(layer "B.Cu")
		(net 2)
	)
	(segment
		(start 71.635 125.675)
		(end 71.635 124.96)
		(width 0.2)
		(layer "B.Cu")
		(net 2)
	)
	(segment
		(start 64.615 117.075)
		(end 64.605 117.065)
		(width 0.2)
		(layer "B.Cu")
		(net 2)
	)
	(segment
		(start 142.759 124.214)
		(end 142.759 123.059)
		(width 0.2)
		(layer "B.Cu")
		(net 2)
	)
	(segment
		(start 93.264991 109.675)
		(end 93.275 109.685009)
		(width 0.15)
		(layer "B.Cu")
		(net 2)
	)
	(segment
		(start 108.79 118.675)
		(end 108.275 118.675)
		(width 0.15)
		(layer "B.Cu")
		(net 2)
	)
	(segment
		(start 95.955 118.96)
		(end 93.895 116.9)
		(width 0.2)
		(layer "B.Cu")
		(net 2)
	)
	(segment
		(start 140.774 122.524)
		(end 140.275 123.023)
		(width 0.2)
		(layer "B.Cu")
		(net 2)
	)
	(segment
		(start 94.725 115.675)
		(end 95.275 115.675)
		(width 0.2)
		(layer "B.Cu")
		(net 2)
	)
	(segment
		(start 123 124.175288)
		(end 123.075565 124.099723)
		(width 0.15)
		(layer "B.Cu")
		(net 2)
	)
	(segment
		(start 103.85 98.75)
		(end 103.995 98.605)
		(width 0.15)
		(layer "B.Cu")
		(net 2)
	)
	(segment
		(start 94.275 112.675)
		(end 95.09 112.675)
		(width 0.15)
		(layer "B.Cu")
		(net 2)
	)
	(segment
		(start 111.275 113.06)
		(end 111.275 113.675)
		(width 0.15)
		(layer "B.Cu")
		(net 2)
	)
	(segment
		(start 69.173 87.315)
		(end 69.174 87.314)
		(width 0.2)
		(layer "B.Cu")
		(net 2)
	)
	(segment
		(start 74.175 158.175)
		(end 74.175 157.075)
		(width 0.15)
		(layer "B.Cu")
		(net 2)
	)
	(segment
		(start 110.29999 120.775)
		(end 110.275 120.75001)
		(width 0.2)
		(layer "B.Cu")
		(net 2)
	)
	(segment
		(start 110.925 120.775)
		(end 110.29999 120.775)
		(width 0.2)
		(layer "B.Cu")
		(net 2)
	)
	(segment
		(start 104.76 115.675)
		(end 105.275 115.675)
		(width 0.15)
		(layer "B.Cu")
		(net 2)
	)
	(segment
		(start 99.275 110.675)
		(end 99.275 109.69)
		(width 0.15)
		(layer "B.Cu")
		(net 2)
	)
	(segment
		(start 95.79 109.675)
		(end 95.285009 109.675)
		(width 0.15)
		(layer "B.Cu")
		(net 2)
	)
	(segment
		(start 110.64 124.66)
		(end 111.225 124.075)
		(width 0.2)
		(layer "B.Cu")
		(net 2)
	)
	(segment
		(start 93.275 109.685009)
		(end 95.275 109.685009)
		(width 0.2)
		(layer "B.Cu")
		(net 2)
	)
	(segment
		(start 134.774 127.999)
		(end 134.774 128.504)
		(width 0.15)
		(layer "B.Cu")
		(net 2)
	)
	(segment
		(start 71.725 149.925)
		(end 71.725 150.311)
		(width 0.2)
		(layer "B.Cu")
		(net 2)
	)
	(segment
		(start 142.759 123.059)
		(end 142.774 123.044)
		(width 0.2)
		(layer "B.Cu")
		(net 2)
	)
	(segment
		(start 128.575 110.675)
		(end 127.66 110.675)
		(width 0.15)
		(layer "B.Cu")
		(net 2)
	)
	(segment
		(start 99.75 103.385)
		(end 108.3 103.385)
		(width 0.2)
		(layer "B.Cu")
		(net 2)
	)
	(segment
		(start 110.19 110.76)
		(end 110.275 110.675)
		(width 0.15)
		(layer "B.Cu")
		(net 2)
	)
	(segment
		(start 97.175 95.94)
		(end 97.175 95.01)
		(width 0.15)
		(layer "B.Cu")
		(net 2)
	)
	(segment
		(start 71.635 130.675)
		(end 71.635 131.465)
		(width 0.2)
		(layer "B.Cu")
		(net 2)
	)
	(segment
		(start 92.46 158.875)
		(end 92.46 157.875)
		(width 0.15)
		(layer "B.Cu")
		(net 2)
	)
	(segment
		(start 91.31 117.325)
		(end 93.075 117.325)
		(width 0.2)
		(layer "B.Cu")
		(net 2)
	)
	(segment
		(start 109.375 110.76)
		(end 110.19 110.76)
		(width 0.15)
		(layer "B.Cu")
		(net 2)
	)
	(segment
		(start 92.46 156.976)
		(end 92.489734 156.946266)
		(width 0.15)
		(layer "B.Cu")
		(net 2)
	)
	(segment
		(start 71.409 150.627)
		(end 70.019 150.627)
		(width 0.2)
		(layer "B.Cu")
		(net 2)
	)
	(segment
		(start 126.945 115.005)
		(end 126.475 115.475)
		(width 0.15)
		(layer "B.Cu")
		(net 2)
	)
	(segment
		(start 107.315 126.6)
		(end 107.315 125.55)
		(width 0.2)
		(layer "B.Cu")
		(net 2)
	)
	(segment
		(start 74.175 157.075)
		(end 73.821447 157.075)
		(width 0.15)
		(layer "B.Cu")
		(net 2)
	)
	(segment
		(start 138.289 122.004)
		(end 135.294 122.004)
		(width 0.15)
		(layer "B.Cu")
		(net 2)
	)
	(segment
		(start 90.275 112.96)
		(end 90.275 113.675)
		(width 0.15)
		(layer "B.Cu")
		(net 2)
	)
	(segment
		(start 70.019 150.627)
		(end 69.799 150.847)
		(width 0.2)
		(layer "B.Cu")
		(net 2)
	)
	(segment
		(start 73.09 156.343553)
		(end 73.09 156.095)
		(width 0.15)
		(layer "B.Cu")
		(net 2)
	)
	(segment
		(start 97.175 95.01)
		(end 97.185 95)
		(width 0.15)
		(layer "B.Cu")
		(net 2)
	)
	(segment
		(start 90.275 112.96)
		(end 93.99 112.96)
		(width 0.2)
		(layer "B.Cu")
		(net 2)
	)
	(segment
		(start 106.478668 97.450348)
		(end 107.239652 97.450348)
		(width 0.15)
		(layer "B.Cu")
		(net 2)
	)
	(segment
		(start 107.315 125.55)
		(end 107.29 125.525)
		(width 0.2)
		(layer "B.Cu")
		(net 2)
	)
	(segment
		(start 93.075 117.325)
		(end 93.5 116.9)
		(width 0.2)
		(layer "B.Cu")
		(net 2)
	)
	(segment
		(start 104.9 89.75)
		(end 104.9 89.25)
		(width 0.2)
		(layer "B.Cu")
		(net 2)
	)
	(segment
		(start 69.551 151.735)
		(end 69.275 151.735)
		(width 0.2)
		(layer "B.Cu")
		(net 2)
	)
	(segment
		(start 96.09 115.675)
		(end 95.275 115.675)
		(width 0.15)
		(layer "B.Cu")
		(net 2)
	)
	(segment
		(start 69.148 85.24)
		(end 69.174 85.214)
		(width 0.2)
		(layer "B.Cu")
		(net 2)
	)
	(segment
		(start 107.275 123.71)
		(end 107.275 124.675)
		(width 0.2)
		(layer "B.Cu")
		(net 2)
	)
	(segment
		(start 139.835 88.7275)
		(end 139.85 88.7125)
		(width 0.1)
		(layer "B.Cu")
		(net 2)
	)
	(segment
		(start 71.695 140.315)
		(end 71.695 140.475)
		(width 0.2)
		(layer "B.Cu")
		(net 2)
	)
	(segment
		(start 104.9 89.25)
		(end 105.336 88.814)
		(width 0.2)
		(layer "B.Cu")
		(net 2)
	)
	(segment
		(start 76.675 158.96)
		(end 75.575 158.96)
		(width 0.15)
		(layer "B.Cu")
		(net 2)
	)
	(segment
		(start 91.31 117.325)
		(end 91.31 118.59)
		(width 0.2)
		(layer "B.Cu")
		(net 2)
	)
	(segment
		(start 121.875 108.875)
		(end 122.96 108.875)
		(width 0.15)
		(layer "B.Cu")
		(net 2)
	)
	(segment
		(start 136.775 124.23)
		(end 136.759 124.214)
		(width 0.2)
		(layer "B.Cu")
		(net 2)
	)
	(segment
		(start 123 124.915)
		(end 123 124.175288)
		(width 0.15)
		(layer "B.Cu")
		(net 2)
	)
	(segment
		(start 99.29 114.675)
		(end 98.275 114.675)
		(width 0.15)
		(layer "B.Cu")
		(net 2)
	)
	(segment
		(start 71.725 144.195)
		(end 71.515 143.985)
		(width 0.2)
		(layer "B.Cu")
		(net 2)
	)
	(segment
		(start 122.975 107.975)
		(end 122.975 108.89)
		(width 0.15)
		(layer "B.Cu")
		(net 2)
	)
	(segment
		(start 122.365 130.665)
		(end 122.365 130.165)
		(width 0.2)
		(layer "B.Cu")
		(net 2)
	)
	(segment
		(start 136.774 127.999)
		(end 136.774 128.504)
		(width 0.15)
		(layer "B.Cu")
		(net 2)
	)
	(segment
		(start 99.275 109.69)
		(end 99.26 109.675)
		(width 0.15)
		(layer "B.Cu")
		(net 2)
	)
	(segment
		(start 122.615 130.915)
		(end 122.365 130.665)
		(width 0.2)
		(layer "B.Cu")
		(net 2)
	)
	(segment
		(start 105.985 125.715)
		(end 106.025 125.675)
		(width 0.2)
		(layer "B.Cu")
		(net 2)
	)
	(segment
		(start 71.725 144.925)
		(end 71.725 144.195)
		(width 0.2)
		(layer "B.Cu")
		(net 2)
	)
	(segment
		(start 140.784 125.514)
		(end 140.259 125.514)
		(width 0.1)
		(layer "B.Cu")
		(net 2)
	)
	(segment
		(start 71.695 140.475)
		(end 70.975 141.195)
		(width 0.2)
		(layer "B.Cu")
		(net 2)
	)
	(segment
		(start 91.31 118.59)
		(end 91.3 118.6)
		(width 0.2)
		(layer "B.Cu")
		(net 2)
	)
	(segment
		(start 68.575 87.315)
		(end 69.173 87.315)
		(width 0.2)
		(layer "B.Cu")
		(net 2)
	)
	(segment
		(start 91.275 117.19)
		(end 91.275 116.675)
		(width 0.15)
		(layer "B.Cu")
		(net 2)
	)
	(segment
		(start 106.835 106.115)
		(end 106.875 106.075)
		(width 0.15)
		(layer "B.Cu")
		(net 2)
	)
	(segment
		(start 107.275 114.96)
		(end 107.275 115.675)
		(width 0.15)
		(layer "B.Cu")
		(net 2)
	)
	(segment
		(start 106.99 118.675)
		(end 106.975 118.66)
		(width 0.2)
		(layer "B.Cu")
		(net 2)
	)
	(segment
		(start 122.96 108.875)
		(end 122.975 108.89)
		(width 0.15)
		(layer "B.Cu")
		(net 2)
	)
	(segment
		(start 107.275 112.675)
		(end 107.29 112.675)
		(width 0.15)
		(layer "B.Cu")
		(net 2)
	)
	(segment
		(start 128.175 126.775)
		(end 128.69 126.775)
		(width 0.15)
		(layer "B.Cu")
		(net 2)
	)
	(segment
		(start 133.959 122.514)
		(end 134.784 122.514)
		(width 0.15)
		(layer "B.Cu")
		(net 2)
	)
	(segment
		(start 122.845 114.935)
		(end 122.865 114.915)
		(width 0.15)
		(layer "B.Cu")
		(net 2)
	)
	(segment
		(start 103.29 109.975)
		(end 103.29 110.66)
		(width 0.15)
		(layer "B.Cu")
		(net 2)
	)
	(segment
		(start 64.605 117.065)
		(end 64.605 116.165)
		(width 0.2)
		(layer "B.Cu")
		(net 2)
	)
	(segment
		(start 106.835 106.73)
		(end 106.835 106.115)
		(width 0.15)
		(layer "B.Cu")
		(net 2)
	)
	(segment
		(start 71.68 135.315)
		(end 71.68 140.3)
		(width 0.2)
		(layer "B.Cu")
		(net 2)
	)
	(segment
		(start 106.025 125.675)
		(end 105.275 125.675)
		(width 0.2)
		(layer "B.Cu")
		(net 2)
	)
	(segment
		(start 107.14 125.675)
		(end 107.29 125.525)
		(width 0.2)
		(layer "B.Cu")
		(net 2)
	)
	(segment
		(start 133.775 128)
		(end 133.775 128.475)
		(width 0.2)
		(layer "B.Cu")
		(net 2)
	)
	(segment
		(start 107.29 125.525)
		(end 107.29 124.69)
		(width 0.2)
		(layer "B.Cu")
		(net 2)
	)
	(segment
		(start 103.85 99.074502)
		(end 103.85 98.75)
		(width 0.15)
		(layer "B.Cu")
		(net 2)
	)
	(segment
		(start 121.865 114.935)
		(end 122.845 114.935)
		(width 0.15)
		(layer "B.Cu")
		(net 2)
	)
	(segment
		(start 71.675 121.125)
		(end 71.675 121.135)
		(width 0.2)
		(layer "B.Cu")
		(net 2)
	)
	(segment
		(start 73.09 156.095)
		(end 73.09 155.775)
		(width 0.15)
		(layer "B.Cu")
		(net 2)
	)
	(segment
		(start 141.774 127.999)
		(end 141.774 128.504)
		(width 0.15)
		(layer "B.Cu")
		(net 2)
	)
	(segment
		(start 75.255 158.96)
		(end 74.96 158.96)
		(width 0.15)
		(layer "B.Cu")
		(net 2)
	)
	(segment
		(start 106.025 125.675)
		(end 107.14 125.675)
		(width 0.2)
		(layer "B.Cu")
		(net 2)
	)
	(segment
		(start 143.519 121.004)
		(end 144.094 121.004)
		(width 0.2)
		(layer "B.Cu")
		(net 2)
	)
	(segment
		(start 140.275 123.175)
		(end 139.789 123.661)
		(width 0.2)
		(layer "B.Cu")
		(net 2)
	)
	(segment
		(start 93.895 116.9)
		(end 93.5 116.9)
		(width 0.2)
		(layer "B.Cu")
		(net 2)
	)
	(segment
		(start 93.99 112.96)
		(end 94.275 112.675)
		(width 0.2)
		(layer "B.Cu")
		(net 2)
	)
	(segment
		(start 133.789 124.214)
		(end 133.789 124.999)
		(width 0.2)
		(layer "B.Cu")
		(net 2)
	)
	(segment
		(start 139.774 127.999)
		(end 139.774 128.304)
		(width 0.15)
		(layer "B.Cu")
		(net 2)
	)
	(segment
		(start 144.094 121.004)
		(end 144.124 120.974)
		(width 0.2)
		(layer "B.Cu")
		(net 2)
	)
	(segment
		(start 103.995 98.605)
		(end 105.76 98.605)
		(width 0.15)
		(layer "B.Cu")
		(net 2)
	)
	(segment
		(start 121.315 130.15)
		(end 121.35 130.15)
		(width 0.2)
		(layer "B.Cu")
		(net 2)
	)
	(segment
		(start 64.575 136.235)
		(end 64.575 135.335)
		(width 0.2)
		(layer "B.Cu")
		(net 2)
	)
	(segment
		(start 92.46 157.875)
		(end 92.46 156.976)
		(width 0.15)
		(layer "B.Cu")
		(net 2)
	)
	(segment
		(start 96.275 118.96)
		(end 95.955 118.96)
		(width 0.2)
		(layer "B.Cu")
		(net 2)
	)
	(segment
		(start 133.865 120.265)
		(end 133.565 119.965)
		(width 0.15)
		(layer "B.Cu")
		(net 2)
	)
	(segment
		(start 97.185 95)
		(end 97.85 95)
		(width 0.15)
		(layer "B.Cu")
		(net 2)
	)
	(segment
		(start 97.29 111.675)
		(end 96.275 111.675)
		(width 0.15)
		(layer "B.Cu")
		(net 2)
	)
	(segment
		(start 96.275 118.96)
		(end 96.275 119.675)
		(width 0.15)
		(layer "B.Cu")
		(net 2)
	)
	(segment
		(start 139.835 89.4125)
		(end 139.835 88.7275)
		(width 0.1)
		(layer "B.Cu")
		(net 2)
	)
	(segment
		(start 133.789 124.999)
		(end 133.774 125.014)
		(width 0.2)
		(layer "B.Cu")
		(net 2)
	)
	(segment
		(start 108.275 118.675)
		(end 106.99 118.675)
		(width 0.2)
		(layer "B.Cu")
		(net 2)
	)
	(segment
		(start 107.239652 97.450348)
		(end 107.24 97.45)
		(width 0.15)
		(layer "B.Cu")
		(net 2)
	)
	(segment
		(start 69.799 151.487)
		(end 69.551 151.735)
		(width 0.2)
		(layer "B.Cu")
		(net 2)
	)
	(segment
		(start 107.29 124.69)
		(end 107.275 124.675)
		(width 0.2)
		(layer "B.Cu")
		(net 2)
	)
	(segment
		(start 69.799 150.847)
		(end 69.799 151.487)
		(width 0.2)
		(layer "B.Cu")
		(net 2)
	)
	(segment
		(start 93.5 116.9)
		(end 94.725 115.675)
		(width 0.2)
		(layer "B.Cu")
		(net 2)
	)
	(segment
		(start 77.475 147.175)
		(end 76.775 147.175)
		(width 0.15)
		(layer "B.Cu")
		(net 2)
	)
	(segment
		(start 111.225 124.075)
		(end 111.225 123.674998)
		(width 0.2)
		(layer "B.Cu")
		(net 2)
	)
	(segment
		(start 71.635 131.465)
		(end 71.625 131.475)
		(width 0.2)
		(layer "B.Cu")
		(net 2)
	)
	(segment
		(start 106.275 118.675)
		(end 106.96 118.675)
		(width 0.15)
		(layer "B.Cu")
		(net 2)
	)
	(segment
		(start 139.789 123.661)
		(end 139.789 124.214)
		(width 0.2)
		(layer "B.Cu")
		(net 2)
	)
	(segment
		(start 133.865 120.915)
		(end 133.865 120.265)
		(width 0.15)
		(layer "B.Cu")
		(net 2)
	)
	(segment
		(start 136.775 125.475)
		(end 136.775 124.23)
		(width 0.2)
		(layer "B.Cu")
		(net 2)
	)
	(segment
		(start 121.365 130.165)
		(end 122.365 130.165)
		(width 0.2)
		(layer "B.Cu")
		(net 2)
	)
	(segment
		(start 74.96 158.96)
		(end 74.175 158.175)
		(width 0.15)
		(layer "B.Cu")
		(net 2)
	)
	(segment
		(start 81.506 80.3)
		(end 81.51 80.296)
		(width 0.2)
		(layer "B.Cu")
		(net 2)
	)
	(segment
		(start 103.275 113.675)
		(end 103.275 113.535)
		(width 0.15)
		(layer "B.Cu")
		(net 2)
	)
	(segment
		(start 81.51 77.495004)
		(end 82.100004 76.905)
		(width 0.2)
		(layer "B.Cu")
		(net 2)
	)
	(segment
		(start 106.96 118.675)
		(end 106.975 118.66)
		(width 0.15)
		(layer "B.Cu")
		(net 2)
	)
	(segment
		(start 103.29 110.66)
		(end 103.275 110.675)
		(width 0.15)
		(layer "B.Cu")
		(net 2)
	)
	(segment
		(start 75.575 158.96)
		(end 75.255 158.96)
		(width 0.15)
		(layer "B.Cu")
		(net 2)
	)
	(segment
		(start 71.635 125.675)
		(end 71.635 130.675)
		(width 0.2)
		(layer "B.Cu")
		(net 2)
	)
	(segment
		(start 105.985 126.7)
		(end 105.985 125.715)
		(width 0.2)
		(layer "B.Cu")
		(net 2)
	)
	(segment
		(start 109.925 124.66)
		(end 110.64 124.66)
		(width 0.2)
		(layer "B.Cu")
		(net 2)
	)
	(segment
		(start 137.299 123.029)
		(end 136.784 122.514)
		(width 0.15)
		(layer "B.Cu")
		(net 2)
	)
	(segment
		(start 71.68 140.3)
		(end 71.695 140.315)
		(width 0.2)
		(layer "B.Cu")
		(net 2)
	)
	(segment
		(start 139.774 128.304)
		(end 139.874 128.404)
		(width 0.15)
		(layer "B.Cu")
		(net 2)
	)
	(segment
		(start 122.865 130.915)
		(end 122.615 130.915)
		(width 0.2)
		(layer "B.Cu")
		(net 2)
	)
	(segment
		(start 73.821447 157.075)
		(end 73.09 156.343553)
		(width 0.15)
		(layer "B.Cu")
		(net 2)
	)
	(segment
		(start 81.51 80.296)
		(end 81.51 77.495004)
		(width 0.2)
		(layer "B.Cu")
		(net 2)
	)
	(segment
		(start 92.76 109.675)
		(end 93.264991 109.675)
		(width 0.15)
		(layer "B.Cu")
		(net 2)
	)
	(segment
		(start 135.774 127.999)
		(end 135.774 128.504)
		(width 0.15)
		(layer "B.Cu")
		(net 2)
	)
	(segment
		(start 71.725 144.925)
		(end 71.725 149.925)
		(width 0.2)
		(layer "B.Cu")
		(net 2)
	)
	(segment
		(start 137.774 127.999)
		(end 137.774 128.504)
		(width 0.15)
		(layer "B.Cu")
		(net 2)
	)
	(segment
		(start 95.285009 109.675)
		(end 95.275 109.685009)
		(width 0.15)
		(layer "B.Cu")
		(net 2)
	)
	(segment
		(start 138.774 127.999)
		(end 138.774 128.504)
		(width 0.15)
		(layer "B.Cu")
		(net 2)
	)
	(segment
		(start 133.565 119.965)
		(end 133.415 119.965)
		(width 0.15)
		(layer "B.Cu")
		(net 2)
	)
	(segment
		(start 138.174 123.029)
		(end 137.299 123.029)
		(width 0.15)
		(layer "B.Cu")
		(net 2)
	)
	(segment
		(start 111.825001 129.125001)
		(end 112.4 129.7)
		(width 0.2)
		(layer "In1.Cu")
		(net 2)
	)
	(segment
		(start 109.275 128.675)
		(end 109.725001 129.125001)
		(width 0.2)
		(layer "In1.Cu")
		(net 2)
	)
	(segment
		(start 109.725001 129.125001)
		(end 111.825001 129.125001)
		(width 0.2)
		(layer "In1.Cu")
		(net 2)
	)
	(segment
		(start 101.775 127.175)
		(end 101.275 127.675)
		(width 0.15)
		(layer "F.Cu")
		(net 3)
	)
	(segment
		(start 92.775 130.175)
		(end 92.275 129.675)
		(width 0.15)
		(layer "F.Cu")
		(net 3)
	)
	(segment
		(start 95.775 129.175)
		(end 95.275 129.675)
		(width 0.15)
		(layer "F.Cu")
		(net 3)
	)
	(segment
		(start 96.975 145.575)
		(end 96.975 146.175)
		(width 0.1)
		(layer "F.Cu")
		(net 3)
	)
	(segment
		(start 92.174 154.19)
		(end 92.174 150.376)
		(width 0.15)
		(layer "F.Cu")
		(net 3)
	)
	(segment
		(start 100.675 154.19)
		(end 100.675 153.575)
		(width 0.2)
		(layer "F.Cu")
		(net 3)
	)
	(segment
		(start 98.97399 149.97601)
		(end 98.97399 151.075)
		(width 0.1)
		(layer "F.Cu")
		(net 3)
	)
	(segment
		(start 102.005 142.545)
		(end 101.775 142.775)
		(width 0.1)
		(layer "F.Cu")
		(net 3)
	)
	(segment
		(start 95.375 143.975)
		(end 95.674 143.676)
		(width 0.1)
		(layer "F.Cu")
		(net 3)
	)
	(segment
		(start 97.374 149.976)
		(end 97.374 154.19)
		(width 0.1)
		(layer "F.Cu")
		(net 3)
	)
	(segment
		(start 91.774 140.56)
		(end 90.99 140.56)
		(width 0.2)
		(layer "F.Cu")
		(net 3)
	)
	(segment
		(start 101.774 140.56)
		(end 101.775 140.561)
		(width 0.1)
		(layer "F.Cu")
		(net 3)
	)
	(segment
		(start 93.775 143.975)
		(end 93.775 143.692158)
		(width 0.1)
		(layer "F.Cu")
		(net 3)
	)
	(segment
		(start 99.375 159.29)
		(end 99.375 158.575)
		(width 0.15)
		(layer "F.Cu")
		(net 3)
	)
	(segment
		(start 102.375054 129.775054)
		(end 102.375054 129.675)
		(width 0.15)
		(layer "F.Cu")
		(net 3)
	)
	(segment
		(start 104.62 140.56)
		(end 105.665 141.605)
		(width 0.2)
		(layer "F.Cu")
		(net 3)
	)
	(segment
		(start 97.774 140.56)
		(end 98.774 140.56)
		(width 0.2)
		(layer "F.Cu")
		(net 3)
	)
	(segment
		(start 93.775 153.225)
		(end 93.775 150.375)
		(width 0.15)
		(layer "F.Cu")
		(net 3)
	)
	(segment
		(start 98.774 140.56)
		(end 91.774 140.56)
		(width 0.2)
		(layer "F.Cu")
		(net 3)
	)
	(segment
		(start 101.775 141.658969)
		(end 102.005 141.888969)
		(width 0.1)
		(layer "F.Cu")
		(net 3)
	)
	(segment
		(start 96.174 154.19)
		(end 96.174 150.376)
		(width 0.15)
		(layer "F.Cu")
		(net 3)
	)
	(segment
		(start 91.295 143.895)
		(end 91.295 142.555)
		(width 0.1)
		(layer "F.Cu")
		(net 3)
	)
	(segment
		(start 100.6375 159.275)
		(end 99.39 159.275)
		(width 0.2)
		(layer "F.Cu")
		(net 3)
	)
	(segment
		(start 103.374 154.19)
		(end 103.374 150.376)
		(width 0.15)
		(layer "F.Cu")
		(net 3)
	)
	(segment
		(start 101.774 154.19)
		(end 101.774 150.376)
		(width 0.15)
		(layer "F.Cu")
		(net 3)
	)
	(segment
		(start 93.674 143.591158)
		(end 93.674 140.855)
		(width 0.1)
		(layer "F.Cu")
		(net 3)
	)
	(segment
		(start 93.674 140.56)
		(end 95.674 140.56)
		(width 0.2)
		(layer "F.Cu")
		(net 3)
	)
	(segment
		(start 102.005 141.888969)
		(end 102.005 142.545)
		(width 0.1)
		(layer "F.Cu")
		(net 3)
	)
	(segment
		(start 93.775 150.375)
		(end 92.975 149.575)
		(width 0.15)
		(layer "F.Cu")
		(net 3)
	)
	(segment
		(start 98.775 128.175)
		(end 98.275 128.675)
		(width 0.15)
		(layer "F.Cu")
		(net 3)
	)
	(segment
		(start 97.775 143.975)
		(end 97.775 140.561)
		(width 0.1)
		(layer "F.Cu")
		(net 3)
	)
	(segment
		(start 92.175 144.775)
		(end 91.295 143.895)
		(width 0.1)
		(layer "F.Cu")
		(net 3)
	)
	(segment
		(start 99.375 144.775)
		(end 98.974999 144.374999)
		(width 0.1)
		(layer "F.Cu")
		(net 3)
	)
	(segment
		(start 101.775 142.775)
		(end 101.775 143.975)
		(width 0.1)
		(layer "F.Cu")
		(net 3)
	)
	(segment
		(start 102.775 130.175)
		(end 102.375054 129.775054)
		(width 0.15)
		(layer "F.Cu")
		(net 3)
	)
	(segment
		(start 97.775 140.561)
		(end 97.774 140.56)
		(width 0.1)
		(layer "F.Cu")
		(net 3)
	)
	(segment
		(start 99.39 159.275)
		(end 99.375 159.29)
		(width 0.2)
		(layer "F.Cu")
		(net 3)
	)
	(segment
		(start 98.974999 144.374999)
		(end 98.974999 142.674999)
		(width 0.1)
		(layer "F.Cu")
		(net 3)
	)
	(segment
		(start 94.974 149.974)
		(end 94.974 154.19)
		(width 0.1)
		(layer "F.Cu")
		(net 3)
	)
	(segment
		(start 93.374 154.19)
		(end 93.374 153.626)
		(width 0.15)
		(layer "F.Cu")
		(net 3)
	)
	(segment
		(start 105.665 141.605)
		(end 105.665 142.765)
		(width 0.2)
		(layer "F.Cu")
		(net 3)
	)
	(segment
		(start 98.974999 142.674999)
		(end 98.774 142.474)
		(width 0.1)
		(layer "F.Cu")
		(net 3)
	)
	(segment
		(start 97.775 125.175)
		(end 97.275 125.675)
		(width 0.15)
		(layer "F.Cu")
		(net 3)
	)
	(segment
		(start 99.375 149.575)
		(end 98.97399 149.97601)
		(width 0.1)
		(layer "F.Cu")
		(net 3)
	)
	(segment
		(start 93.775 143.692158)
		(end 93.674 143.591158)
		(width 0.1)
		(layer "F.Cu")
		(net 3)
	)
	(segment
		(start 98.774 142.474)
		(end 98.774 140.56)
		(width 0.1)
		(layer "F.Cu")
		(net 3)
	)
	(segment
		(start 90.99 140.56)
		(end 90.975 140.575)
		(width 0.2)
		(layer "F.Cu")
		(net 3)
	)
	(segment
		(start 103.375 143.975)
		(end 103.375 141.335)
		(width 0.1)
		(layer "F.Cu")
		(net 3)
	)
	(segment
		(start 103.375 141.335)
		(end 103.374 141.334)
		(width 0.1)
		(layer "F.Cu")
		(net 3)
	)
	(segment
		(start 93.674 140.855)
		(end 93.674 140.56)
		(width 0.1)
		(layer "F.Cu")
		(net 3)
	)
	(segment
		(start 101.775 140.561)
		(end 101.775 141.658969)
		(width 0.1)
		(layer "F.Cu")
		(net 3)
	)
	(segment
		(start 94.575 140.659)
		(end 94.674 140.56)
		(width 0.1)
		(layer "F.Cu")
		(net 3)
	)
	(segment
		(start 93.374 153.626)
		(end 93.775 153.225)
		(width 0.15)
		(layer "F.Cu")
		(net 3)
	)
	(segment
		(start 95.674 143.676)
		(end 95.674 140.56)
		(width 0.1)
		(layer "F.Cu")
		(net 3)
	)
	(segment
		(start 94.575 149.575)
		(end 94.974 149.974)
		(width 0.1)
		(layer "F.Cu")
		(net 3)
	)
	(segment
		(start 97.775 149.575)
		(end 97.374 149.976)
		(width 0.1)
		(layer "F.Cu")
		(net 3)
	)
	(segment
		(start 103.374 140.56)
		(end 104.62 140.56)
		(width 0.2)
		(layer "F.Cu")
		(net 3)
	)
	(segment
		(start 103.374 141.334)
		(end 103.374 140.56)
		(width 0.1)
		(layer "F.Cu")
		(net 3)
	)
	(segment
		(start 94.575 143.975)
		(end 94.575 140.659)
		(width 0.1)
		(layer "F.Cu")
		(net 3)
	)
	(segment
		(start 105.665 142.765)
		(end 105.665 143.205)
		(width 0.2)
		(layer "F.Cu")
		(net 3)
	)
	(segment
		(start 101.774 140.56)
		(end 103.374 140.56)
		(width 0.2)
		(layer "F.Cu")
		(net 3)
	)
	(via
		(at 101.275 127.675)
		(size 0.5)
		(drill 0.2)
		(layers "F.Cu" "B.Cu")
		(net 3)
	)
	(via
		(at 92.17399 151.075)
		(size 0.5)
		(drill 0.2)
		(layers "F.Cu" "B.Cu")
		(net 3)
	)
	(via
		(at 91.295 142.555)
		(size 0.5)
		(drill 0.2)
		(layers "F.Cu" "B.Cu")
		(net 3)
	)
	(via
		(at 92.275 129.675)
		(size 0.5)
		(drill 0.2)
		(layers "F.Cu" "B.Cu")
		(net 3)
	)
	(via
		(at 95.275 129.675)
		(size 0.5)
		(drill 0.2)
		(layers "F.Cu" "B.Cu")
		(net 3)
	)
	(via
		(at 96.975 146.175)
		(size 0.5)
		(drill 0.2)
		(layers "F.Cu" "B.Cu")
		(net 3)
	)
	(via
		(at 81.319 83.187)
		(size 0.5)
		(drill 0.2)
		(layers "F.Cu" "B.Cu")
		(net 3)
	)
	(via
		(at 80.445 83.19)
		(size 0.5)
		(drill 0.2)
		(layers "F.Cu" "B.Cu")
		(net 3)
	)
	(via
		(at 79.585 83.19)
		(size 0.5)
		(drill 0.2)
		(layers "F.Cu" "B.Cu")
		(net 3)
	)
	(via
		(at 81.299 84.217)
		(size 0.5)
		(drill 0.2)
		(layers "F.Cu" "B.Cu")
		(net 3)
	)
	(via
		(at 94.97399 152.2)
		(size 0.5)
		(drill 0.2)
		(layers "F.Cu" "B.Cu")
		(net 3)
	)
	(via
		(at 90.975 140.575)
		(size 0.5)
		(drill 0.2)
		(layers "F.Cu" "B.Cu")
		(net 3)
	)
	(via
		(at 93.2 152.8)
		(size 0.5)
		(drill 0.2)
		(layers "F.Cu" "B.Cu")
		(net 3)
	)
	(via
		(at 98.97399 151.075)
		(size 0.5)
		(drill 0.2)
		(layers "F.Cu" "B.Cu")
		(net 3)
	)
	(via
		(at 99.375 158.575)
		(size 0.5)
		(drill 0.2)
		(layers "F.Cu" "B.Cu")
		(net 3)
	)
	(via
		(at 96.155 152.195)
		(size 0.5)
		(drill 0.2)
		(layers "F.Cu" "B.Cu")
		(net 3)
	)
	(via
		(at 102.375054 129.675)
		(size 0.5)
		(drill 0.2)
		(layers "F.Cu" "B.Cu")
		(net 3)
	)
	(via
		(at 92.8 153.1)
		(size 0.5)
		(drill 0.2)
		(layers "F.Cu" "B.Cu")
		(net 3)
	)
	(via
		(at 98.275 128.675)
		(size 0.5)
		(drill 0.2)
		(layers "F.Cu" "B.Cu")
		(net 3)
	)
	(via
		(at 93.77399 151.075)
		(size 0.5)
		(drill 0.2)
		(layers "F.Cu" "B.Cu")
		(net 3)
	)
	(via
		(at 97.37399 152.2)
		(size 0.5)
		(drill 0.2)
		(layers "F.Cu" "B.Cu")
		(net 3)
	)
	(via
		(at 100.675 153.575)
		(size 0.5)
		(drill 0.2)
		(layers "F.Cu" "B.Cu")
		(net 3)
	)
	(via
		(at 93.2 152.2)
		(size 0.5)
		(drill 0.2)
		(layers "F.Cu" "B.Cu")
		(net 3)
	)
	(via
		(at 105.665 143.205)
		(size 0.5)
		(drill 0.2)
		(layers "F.Cu" "B.Cu")
		(net 3)
	)
	(via
		(at 103.37399 151.075)
		(size 0.5)
		(drill 0.2)
		(layers "F.Cu" "B.Cu")
		(net 3)
	)
	(via
		(at 92.8 151.9)
		(size 0.5)
		(drill 0.2)
		(layers "F.Cu" "B.Cu")
		(net 3)
	)
	(via
		(at 92.8 152.5)
		(size 0.5)
		(drill 0.2)
		(layers "F.Cu" "B.Cu")
		(net 3)
	)
	(via
		(at 97.275 125.675)
		(size 0.5)
		(drill 0.2)
		(layers "F.Cu" "B.Cu")
		(net 3)
	)
	(via
		(at 101.775 151.005)
		(size 0.5)
		(drill 0.2)
		(layers "F.Cu" "B.Cu")
		(net 3)
	)
	(segment
		(start 97.31 125.71)
		(end 97.275 125.675)
		(width 0.2)
		(layer "B.Cu")
		(net 3)
	)
	(segment
		(start 95.225 128.91)
		(end 95.225 129.625)
		(width 0.2)
		(layer "B.Cu")
		(net 3)
	)
	(segment
		(start 98.29 128.66)
		(end 98.275 128.675)
		(width 0.2)
		(layer "B.Cu")
		(net 3)
	)
	(segment
		(start 102.31 129.609946)
		(end 102.375054 129.675)
		(width 0.2)
		(layer "B.Cu")
		(net 3)
	)
	(segment
		(start 95.225 129.625)
		(end 95.275 129.675)
		(width 0.2)
		(layer "B.Cu")
		(net 3)
	)
	(segment
		(start 102.31 128.825)
		(end 102.31 129.609946)
		(width 0.2)
		(layer "B.Cu")
		(net 3)
	)
	(segment
		(start 92.34 129.61)
		(end 92.275 129.675)
		(width 0.2)
		(layer "B.Cu")
		(net 3)
	)
	(segment
		(start 97.31 126.575)
		(end 97.31 125.71)
		(width 0.2)
		(layer "B.Cu")
		(net 3)
	)
	(segment
		(start 101.29 127.66)
		(end 101.275 127.675)
		(width 0.2)
		(layer "B.Cu")
		(net 3)
	)
	(segment
		(start 99.025 128.66)
		(end 98.29 128.66)
		(width 0.2)
		(layer "B.Cu")
		(net 3)
	)
	(segment
		(start 93.025 129.61)
		(end 92.34 129.61)
		(width 0.2)
		(layer "B.Cu")
		(net 3)
	)
	(segment
		(start 101.29 127.025)
		(end 101.29 127.66)
		(width 0.2)
		(layer "B.Cu")
		(net 3)
	)
	(segment
		(start 67.741143 90.705143)
		(end 67.737 90.701)
		(width 0.2)
		(layer "F.Cu")
		(net 4)
	)
	(segment
		(start 68.742 90.705143)
		(end 67.741143 90.705143)
		(width 0.2)
		(layer "F.Cu")
		(net 4)
	)
	(segment
		(start 76 67.2)
		(end 77.185 67.2)
		(width 0.15)
		(layer "F.Cu")
		(net 4)
	)
	(segment
		(start 130.269 119.027)
		(end 131.369 117.927)
		(width 0.15)
		(layer "F.Cu")
		(net 4)
	)
	(segment
		(start 129.775 112.66)
		(end 129.775 113.425)
		(width 0.2)
		(layer "F.Cu")
		(net 4)
	)
	(segment
		(start 129.075 129.455)
		(end 129.08 129.46)
		(width 0.2)
		(layer "F.Cu")
		(net 4)
	)
	(segment
		(start 71.009 89.461)
		(end 71.145 89.461)
		(width 0.2)
		(layer "F.Cu")
		(net 4)
	)
	(segment
		(start 75.6 67.6)
		(end 76 67.2)
		(width 0.15)
		(layer "F.Cu")
		(net 4)
	)
	(segment
		(start 70.692 90.705143)
		(end 70.692 89.778)
		(width 0.2)
		(layer "F.Cu")
		(net 4)
	)
	(segment
		(start 75.6 68.3)
		(end 75.6 67.6)
		(width 0.15)
		(layer "F.Cu")
		(net 4)
	)
	(segment
		(start 81.822 98.1)
		(end 81.249 97.527)
		(width 0.2)
		(layer "F.Cu")
		(net 4)
	)
	(segment
		(start 129.775 113.425)
		(end 129.78 113.43)
		(width 0.2)
		(layer "F.Cu")
		(net 4)
	)
	(segment
		(start 130.442 112.66)
		(end 129.775 112.66)
		(width 0.15)
		(layer "F.Cu")
		(net 4)
	)
	(segment
		(start 82.5 98.1)
		(end 81.822 98.1)
		(width 0.2)
		(layer "F.Cu")
		(net 4)
	)
	(segment
		(start 131.329 128.247)
		(end 131.329 126.787)
		(width 0.15)
		(layer "F.Cu")
		(net 4)
	)
	(segment
		(start 81.249 97.527)
		(end 81.249 95.617)
		(width 0.2)
		(layer "F.Cu")
		(net 4)
	)
	(segment
		(start 81.249 95.617)
		(end 80.889 95.257)
		(width 0.2)
		(layer "F.Cu")
		(net 4)
	)
	(segment
		(start 131.329 126.787)
		(end 130.269 125.727)
		(width 0.15)
		(layer "F.Cu")
		(net 4)
	)
	(segment
		(start 131.369 117.927)
		(end 131.359 113.577)
		(width 0.15)
		(layer "F.Cu")
		(net 4)
	)
	(segment
		(start 129.075 128.66)
		(end 129.075 129.455)
		(width 0.2)
		(layer "F.Cu")
		(net 4)
	)
	(segment
		(start 77.185 67.2)
		(end 77.2 67.215)
		(width 0.15)
		(layer "F.Cu")
		(net 4)
	)
	(segment
		(start 70.692 89.778)
		(end 71.009 89.461)
		(width 0.2)
		(layer "F.Cu")
		(net 4)
	)
	(segment
		(start 130.269 125.727)
		(end 130.269 119.027)
		(width 0.15)
		(layer "F.Cu")
		(net 4)
	)
	(segment
		(start 80.889 95.257)
		(end 80.699 95.257)
		(width 0.2)
		(layer "F.Cu")
		(net 4)
	)
	(segment
		(start 131.359 113.577)
		(end 130.442 112.66)
		(width 0.15)
		(layer "F.Cu")
		(net 4)
	)
	(via
		(at 67.737 91.366)
		(size 0.5)
		(drill 0.2)
		(layers "F.Cu" "B.Cu")
		(net 4)
	)
	(via
		(at 67.737 90.701)
		(size 0.5)
		(drill 0.2)
		(layers "F.Cu" "B.Cu")
		(net 4)
	)
	(via
		(at 80.809 87.747)
		(size 0.5)
		(drill 0.2)
		(layers "F.Cu" "B.Cu")
		(net 4)
	)
	(via
		(at 83.869 83.227)
		(size 0.5)
		(drill 0.2)
		(layers "F.Cu" "B.Cu")
		(net 4)
	)
	(via
		(at 83.87 84.177)
		(size 0.5)
		(drill 0.2)
		(layers "F.Cu" "B.Cu")
		(net 4)
	)
	(via
		(at 85.07 83.25)
		(size 0.5)
		(drill 0.2)
		(layers "F.Cu" "B.Cu")
		(net 4)
	)
	(via
		(at 85.07 84.17)
		(size 0.5)
		(drill 0.2)
		(layers "F.Cu" "B.Cu")
		(net 4)
	)
	(via
		(at 84.3 91.3)
		(size 0.5)
		(drill 0.2)
		(layers "F.Cu" "B.Cu")
		(net 4)
	)
	(via
		(at 84.95 90.65)
		(size 0.5)
		(drill 0.2)
		(layers "F.Cu" "B.Cu")
		(net 4)
	)
	(via
		(at 83.65 90.65)
		(size 0.5)
		(drill 0.2)
		(layers "F.Cu" "B.Cu")
		(net 4)
	)
	(via
		(at 84.3 90.65)
		(size 0.5)
		(drill 0.2)
		(layers "F.Cu" "B.Cu")
		(net 4)
	)
	(via
		(at 83.6 75.955)
		(size 0.5)
		(drill 0.2)
		(layers "F.Cu" "B.Cu")
		(net 4)
	)
	(via
		(at 84.4 75.955)
		(size 0.5)
		(drill 0.2)
		(layers "F.Cu" "B.Cu")
		(net 4)
	)
	(via
		(at 83.6 76.755)
		(size 0.5)
		(drill 0.2)
		(layers "F.Cu" "B.Cu")
		(net 4)
	)
	(via
		(at 84.4 76.755)
		(size 0.5)
		(drill 0.2)
		(layers "F.Cu" "B.Cu")
		(net 4)
	)
	(via
		(at 85.2 75.955)
		(size 0.5)
		(drill 0.2)
		(layers "F.Cu" "B.Cu")
		(net 4)
	)
	(via
		(at 83.575 105.21)
		(size 0.5)
		(drill 0.2)
		(layers "F.Cu" "B.Cu")
		(net 4)
	)
	(via
		(at 71.779 91.077)
		(size 0.5)
		(drill 0.2)
		(layers "F.Cu" "B.Cu")
		(net 4)
	)
	(via
		(at 129.78 113.43)
		(size 0.5)
		(drill 0.2)
		(layers "F.Cu" "B.Cu")
		(net 4)
	)
	(via
		(at 129.08 129.46)
		(size 0.5)
		(drill 0.2)
		(layers "F.Cu" "B.Cu")
		(net 4)
	)
	(via
		(at 70.645 88.365)
		(size 0.5)
		(drill 0.2)
		(layers "F.Cu" "B.Cu")
		(net 4)
	)
	(via
		(at 84.895 97.915)
		(size 0.5)
		(drill 0.2)
		(layers "F.Cu" "B.Cu")
		(net 4)
	)
	(via
		(at 83.65 91.3)
		(size 0.5)
		(drill 0.2)
		(layers "F.Cu" "B.Cu")
		(net 4)
	)
	(via
		(at 84.95 91.3)
		(size 0.5)
		(drill 0.2)
		(layers "F.Cu" "B.Cu")
		(net 4)
	)
	(via
		(at 82.5 98.1)
		(size 0.5)
		(drill 0.2)
		(layers "F.Cu" "B.Cu")
		(net 4)
	)
	(via
		(at 84.775 105.21)
		(size 0.5)
		(drill 0.2)
		(layers "F.Cu" "B.Cu")
		(net 4)
	)
	(via
		(at 82.8 75.955)
		(size 0.5)
		(drill 0.2)
		(layers "F.Cu" "B.Cu")
		(net 4)
	)
	(via
		(at 83.695 97.915)
		(size 0.5)
		(drill 0.2)
		(layers "F.Cu" "B.Cu")
		(net 4)
	)
	(via
		(at 81.425 103.305)
		(size 0.5)
		(drill 0.2)
		(layers "F.Cu" "B.Cu")
		(net 4)
	)
	(via
		(at 84.775 106.21)
		(size 0.5)
		(drill 0.2)
		(layers "F.Cu" "B.Cu")
		(net 4)
	)
	(via
		(at 82.8 76.75)
		(size 0.5)
		(drill 0.2)
		(layers "F.Cu" "B.Cu")
		(net 4)
	)
	(via
		(at 131.329 128.247)
		(size 0.5)
		(drill 0.2)
		(layers "F.Cu" "B.Cu")
		(net 4)
	)
	(via
		(at 71.145 89.461)
		(size 0.5)
		(drill 0.2)
		(layers "F.Cu" "B.Cu")
		(net 4)
	)
	(via
		(at 80.699 95.257)
		(size 0.5)
		(drill 0.2)
		(layers "F.Cu" "B.Cu")
		(net 4)
	)
	(via
		(at 82.4 105.4)
		(size 0.5)
		(drill 0.2)
		(layers "F.Cu" "B.Cu")
		(net 4)
	)
	(via
		(at 82.7 84.15)
		(size 0.5)
		(drill 0.2)
		(layers "F.Cu" "B.Cu")
		(net 4)
	)
	(via
		(at 75.6 68.3)
		(size 0.5)
		(drill 0.2)
		(layers "F.Cu" "B.Cu")
		(net 4)
	)
	(via
		(at 84.895 98.915)
		(size 0.5)
		(drill 0.2)
		(layers "F.Cu" "B.Cu")
		(net 4)
	)
	(segment
		(start 70.967 91.071)
		(end 71.727 91.071)
		(width 0.2)
		(layer "B.Cu")
		(net 4)
	)
	(segment
		(start 68.032 91.071)
		(end 67.737 91.366)
		(width 0.2)
		(layer "B.Cu")
		(net 4)
	)
	(segment
		(start 68.967 91.071)
		(end 68.032 91.071)
		(width 0.2)
		(layer "B.Cu")
		(net 4)
	)
	(segment
		(start 81.493999 87.765001)
		(end 81.501 87.758)
		(width 0.15)
		(layer "B.Cu")
		(net 4)
	)
	(segment
		(start 71.727 91.071)
		(end 71.773 91.071)
		(width 0.2)
		(layer "B.Cu")
		(net 4)
	)
	(segment
		(start 92.275 110.075)
		(end 92.275 109.323)
		(width 0.15)
		(layer "B.Cu")
		(net 4)
	)
	(segment
		(start 71.773 91.071)
		(end 71.779 91.077)
		(width 0.2)
		(layer "B.Cu")
		(net 4)
	)
	(segment
		(start 129.107 129.487)
		(end 129.08 129.46)
		(width 0.15)
		(layer "B.Cu")
		(net 4)
	)
	(segment
		(start 130.089 129.487)
		(end 129.107 129.487)
		(width 0.15)
		(layer "B.Cu")
		(net 4)
	)
	(segment
		(start 81.092 87.5)
		(end 80.827 87.765)
		(width 0.15)
		(layer "B.Cu")
		(net 4)
	)
	(segment
		(start 83.645 90.655)
		(end 81.927 90.655)
		(width 0.15)
		(layer "B.Cu")
		(net 4)
	)
	(segment
		(start 108.8981 111.537)
		(end 108.461101 111.100001)
		(width 0.15)
		(layer "B.Cu")
		(net 4)
	)
	(segment
		(start 81.5 87.765)
		(end 81.5 87.5)
		(width 0.15)
		(layer "B.Cu")
		(net 4)
	)
	(segment
		(start 92.717 110.517)
		(end 92.275 110.075)
		(width 0.15)
		(layer "B.Cu")
		(net 4)
	)
	(segment
		(start 131.329 128.247)
		(end 130.089 129.487)
		(width 0.15)
		(layer "B.Cu")
		(net 4)
	)
	(segment
		(start 89.167 106.215)
		(end 84.78 106.215)
		(width 0.15)
		(layer "B.Cu")
		(net 4)
	)
	(segment
		(start 84.78 106.215)
		(end 84.775 106.21)
		(width 0.15)
		(layer "B.Cu")
		(net 4)
	)
	(segment
		(start 83.65 90.65)
		(end 83.645 90.655)
		(width 0.15)
		(layer "B.Cu")
		(net 4)
	)
	(segment
		(start 94.989 110.517)
		(end 92.717 110.517)
		(width 0.15)
		(layer "B.Cu")
		(net 4)
	)
	(segment
		(start 81.395 94.9)
		(end 81.038 95.257)
		(width 0.15)
		(layer "B.Cu")
		(net 4)
	)
	(segment
		(start 92.275 109.323)
		(end 89.167 106.215)
		(width 0.15)
		(layer "B.Cu")
		(net 4)
	)
	(segment
		(start 69.967 89.043)
		(end 70.645 88.365)
		(width 0.2)
		(layer "B.Cu")
		(net 4)
	)
	(segment
		(start 108.461101 111.100001)
		(end 95.572001 111.100001)
		(width 0.15)
		(layer "B.Cu")
		(net 4)
	)
	(segment
		(start 69.967 91.071)
		(end 69.967 89.043)
		(width 0.2)
		(layer "B.Cu")
		(net 4)
	)
	(segment
		(start 95.572001 111.100001)
		(end 94.989 110.517)
		(width 0.15)
		(layer "B.Cu")
		(net 4)
	)
	(segment
		(start 129.78 112.498)
		(end 128.819 111.537)
		(width 0.15)
		(layer "B.Cu")
		(net 4)
	)
	(segment
		(start 81.5 87.5)
		(end 81.092 87.5)
		(width 0.15)
		(layer "B.Cu")
		(net 4)
	)
	(segment
		(start 81.44 102.502)
		(end 81.44 103.29)
		(width 0.2)
		(layer "B.Cu")
		(net 4)
	)
	(segment
		(start 81.038 95.257)
		(end 80.699 95.257)
		(width 0.15)
		(layer "B.Cu")
		(net 4)
	)
	(segment
		(start 129.78 113.43)
		(end 129.78 112.498)
		(width 0.15)
		(layer "B.Cu")
		(net 4)
	)
	(segment
		(start 128.819 111.537)
		(end 108.8981 111.537)
		(width 0.15)
		(layer "B.Cu")
		(net 4)
	)
	(segment
		(start 81.927 90.655)
		(end 81.493999 90.221999)
		(width 0.15)
		(layer "B.Cu")
		(net 4)
	)
	(segment
		(start 81.493999 90.221999)
		(end 81.493999 87.765001)
		(width 0.15)
		(layer "B.Cu")
		(net 4)
	)
	(segment
		(start 103.775 119.175)
		(end 104.275 119.675)
		(width 0.15)
		(layer "F.Cu")
		(net 5)
	)
	(segment
		(start 104.775 120.175)
		(end 105.275 120.675)
		(width 0.15)
		(layer "F.Cu")
		(net 5)
	)
	(segment
		(start 132.939 142.927)
		(end 124.575 151.291)
		(width 0.15)
		(layer "F.Cu")
		(net 5)
	)
	(segment
		(start 99.775 121.175)
		(end 99.29999 121.65001)
		(width 0.15)
		(layer "F.Cu")
		(net 5)
	)
	(segment
		(start 101.775 119.175)
		(end 102.275 119.675)
		(width 0.15)
		(layer "F.Cu")
		(net 5)
	)
	(segment
		(start 92.84 162.59)
		(end 92.765 162.59)
		(width 0.2)
		(layer "F.Cu")
		(net 5)
	)
	(segment
		(start 124.57 153.735)
		(end 124.57 153.08)
		(width 0.15)
		(layer "F.Cu")
		(net 5)
	)
	(segment
		(start 124.575 151.291)
		(end 124.575 153.075)
		(width 0.15)
		(layer "F.Cu")
		(net 5)
	)
	(segment
		(start 84.115 167.54)
		(end 83.115 167.54)
		(width 0.2)
		(layer "F.Cu")
		(net 5)
	)
	(segment
		(start 90.515 137.765)
		(end 90.515 153.19)
		(width 0.2)
		(layer "F.Cu")
		(net 5)
	)
	(segment
		(start 83.115 167.54)
		(end 83.09 167.54)
		(width 0.2)
		(layer "F.Cu")
		(net 5)
	)
	(segment
		(start 94.775 119.175)
		(end 95.275 119.675)
		(width 0.15)
		(layer "F.Cu")
		(net 5)
	)
	(segment
		(start 97.775 119.175)
		(end 98.275 119.675)
		(width 0.15)
		(layer "F.Cu")
		(net 5)
	)
	(segment
		(start 99.775 119.175)
		(end 100.25001 119.65001)
		(width 0.15)
		(layer "F.Cu")
		(net 5)
	)
	(segment
		(start 93.015 158.99)
		(end 93.015 162.415)
		(width 0.2)
		(layer "F.Cu")
		(net 5)
	)
	(segment
		(start 84.455 167.2)
		(end 84.115 167.54)
		(width 0.2)
		(layer "F.Cu")
		(net 5)
	)
	(segment
		(start 89.66 124.22)
		(end 89.465 124.415)
		(width 0.2)
		(layer "F.Cu")
		(net 5)
	)
	(segment
		(start 89.915 155.89)
		(end 93.015 158.99)
		(width 0.2)
		(layer "F.Cu")
		(net 5)
	)
	(segment
		(start 90.515 153.19)
		(end 89.915 153.79)
		(width 0.2)
		(layer "F.Cu")
		(net 5)
	)
	(segment
		(start 132.939 125.437)
		(end 132.939 142.927)
		(width 0.15)
		(layer "F.Cu")
		(net 5)
	)
	(segment
		(start 93.015 162.415)
		(end 92.84 162.59)
		(width 0.2)
		(layer "F.Cu")
		(net 5)
	)
	(segment
		(start 92.49 162.865)
		(end 91.065 162.865)
		(width 0.2)
		(layer "F.Cu")
		(net 5)
	)
	(segment
		(start 100.25001 119.65001)
		(end 100.284975 119.65001)
		(width 0.15)
		(layer "F.Cu")
		(net 5)
	)
	(segment
		(start 92.765 162.59)
		(end 92.49 162.865)
		(width 0.2)
		(layer "F.Cu")
		(net 5)
	)
	(segment
		(start 89.465 124.415)
		(end 89.465 136.715)
		(width 0.2)
		(layer "F.Cu")
		(net 5)
	)
	(segment
		(start 89.465 136.715)
		(end 90.515 137.765)
		(width 0.2)
		(layer "F.Cu")
		(net 5)
	)
	(segment
		(start 84.89 167.2)
		(end 84.455 167.2)
		(width 0.2)
		(layer "F.Cu")
		(net 5)
	)
	(segment
		(start 124.57 153.08)
		(end 124.575 153.075)
		(width 0.15)
		(layer "F.Cu")
		(net 5)
	)
	(segment
		(start 89.915 153.79)
		(end 89.915 155.89)
		(width 0.2)
		(layer "F.Cu")
		(net 5)
	)
	(via
		(at 104.275 119.675)
		(size 0.5)
		(drill 0.2)
		(layers "F.Cu" "B.Cu")
		(net 5)
	)
	(via
		(at 105.275 120.675)
		(size 0.5)
		(drill 0.2)
		(layers "F.Cu" "B.Cu")
		(net 5)
	)
	(via
		(at 79.355 90.07)
		(size 0.5)
		(drill 0.2)
		(layers "F.Cu" "B.Cu")
		(net 5)
	)
	(via
		(at 80.119 90.07)
		(size 0.5)
		(drill 0.2)
		(layers "F.Cu" "B.Cu")
		(net 5)
	)
	(via
		(at 81.075 92.09)
		(size 0.5)
		(drill 0.2)
		(layers "F.Cu" "B.Cu")
		(net 5)
	)
	(via
		(at 81.935 91.08)
		(size 0.5)
		(drill 0.2)
		(layers "F.Cu" "B.Cu")
		(net 5)
	)
	(via
		(at 92.9 102.4)
		(size 0.5)
		(drill 0.2)
		(layers "F.Cu" "B.Cu")
		(net 5)
	)
	(via
		(at 95.275 119.675)
		(size 0.5)
		(drill 0.2)
		(layers "F.Cu" "B.Cu")
		(net 5)
	)
	(via
		(at 92.9 103)
		(size 0.5)
		(drill 0.2)
		(layers "F.Cu" "B.Cu")
		(net 5)
	)
	(via
		(at 99.29999 121.675)
		(size 0.5)
		(drill 0.2)
		(layers "F.Cu" "B.Cu")
		(net 5)
	)
	(via
		(at 92.84 162.59)
		(size 0.5)
		(drill 0.2)
		(layers "F.Cu" "B.Cu")
		(net 5)
	)
	(via
		(at 132.925 125.405)
		(size 0.5)
		(drill 0.2)
		(layers "F.Cu" "B.Cu")
		(net 5)
	)
	(via
		(at 79.355 91.08)
		(size 0.5)
		(drill 0.2)
		(layers "F.Cu" "B.Cu")
		(net 5)
	)
	(via
		(at 98.275 119.675)
		(size 0.5)
		(drill 0.2)
		(layers "F.Cu" "B.Cu")
		(net 5)
	)
	(via
		(at 92.9 101.8)
		(size 0.5)
		(drill 0.2)
		(layers "F.Cu" "B.Cu")
		(net 5)
	)
	(via
		(at 100.284975 119.65001)
		(size 0.5)
		(drill 0.2)
		(layers "F.Cu" "B.Cu")
		(net 5)
	)
	(via
		(at 89.66 124.22)
		(size 0.5)
		(drill 0.2)
		(layers "F.Cu" "B.Cu")
		(net 5)
	)
	(via
		(at 81.075 91.08)
		(size 0.5)
		(drill 0.2)
		(layers "F.Cu" "B.Cu")
		(net 5)
	)
	(via
		(at 102.275 119.675)
		(size 0.5)
		(drill 0.2)
		(layers "F.Cu" "B.Cu")
		(net 5)
	)
	(via
		(at 84.115 167.54)
		(size 0.5)
		(drill 0.2)
		(layers "F.Cu" "B.Cu")
		(net 5)
	)
	(via
		(at 80.119 91.08)
		(size 0.5)
		(drill 0.2)
		(layers "F.Cu" "B.Cu")
		(net 5)
	)
	(via
		(at 81.935 92.09)
		(size 0.5)
		(drill 0.2)
		(layers "F.Cu" "B.Cu")
		(net 5)
	)
	(segment
		(start 102.275 118.86)
		(end 102.275 119.675)
		(width 0.15)
		(layer "B.Cu")
		(net 5)
	)
	(segment
		(start 106.367 121.767)
		(end 111.119 121.767)
		(width 0.15)
		(layer "B.Cu")
		(net 5)
	)
	(segment
		(start 112.139 122.787)
		(end 130.307 122.787)
		(width 0.15)
		(layer "B.Cu")
		(net 5)
	)
	(segment
		(start 104.275 119.16)
		(end 104.275 119.675)
		(width 0.15)
		(layer "B.Cu")
		(net 5)
	)
	(segment
		(start 105.275 120.675)
		(end 106.367 121.767)
		(width 0.15)
		(layer "B.Cu")
		(net 5)
	)
	(segment
		(start 130.307 122.787)
		(end 132.925 125.405)
		(width 0.15)
		(layer "B.Cu")
		(net 5)
	)
	(segment
		(start 100.284975 119.65001)
		(end 100.284975 118.869975)
		(width 0.15)
		(layer "B.Cu")
		(net 5)
	)
	(segment
		(start 87.89 167.54)
		(end 84.115 167.54)
		(width 0.2)
		(layer "B.Cu")
		(net 5)
	)
	(segment
		(start 92.84 162.59)
		(end 87.89 167.54)
		(width 0.2)
		(layer "B.Cu")
		(net 5)
	)
	(segment
		(start 100.284975 118.869975)
		(end 100.275 118.86)
		(width 0.15)
		(layer "B.Cu")
		(net 5)
	)
	(segment
		(start 104.645 120.675)
		(end 105.275 120.675)
		(width 0.15)
		(layer "B.Cu")
		(net 5)
	)
	(segment
		(start 98.275 118.96)
		(end 98.275 119.675)
		(width 0.15)
		(layer "B.Cu")
		(net 5)
	)
	(segment
		(start 111.119 121.767)
		(end 112.139 122.787)
		(width 0.15)
		(layer "B.Cu")
		(net 5)
	)
	(segment
		(start 98.645 121.675)
		(end 99.29999 121.675)
		(width 0.15)
		(layer "B.Cu")
		(net 5)
	)
	(segment
		(start 89.58 124.22)
		(end 88.87 123.51)
		(width 0.15)
		(layer "In6.Cu")
		(net 5)
	)
	(segment
		(start 89.66 124.22)
		(end 89.58 124.22)
		(width 0.15)
		(layer "In6.Cu")
		(net 5)
	)
	(segment
		(start 94.775 123.175)
		(end 94.275 123.675)
		(width 0.15)
		(layer "F.Cu")
		(net 6)
	)
	(segment
		(start 100.775 120.175)
		(end 101.275 120.675)
		(width 0.15)
		(layer "F.Cu")
		(net 6)
	)
	(segment
		(start 95.775 122.175)
		(end 96.275 122.675)
		(width 0.15)
		(layer "F.Cu")
		(net 6)
	)
	(segment
		(start 102.775 120.175)
		(end 103.275 120.675)
		(width 0.15)
		(layer "F.Cu")
		(net 6)
	)
	(segment
		(start 101.775 123.175)
		(end 102.275 123.675)
		(width 0.15)
		(layer "F.Cu")
		(net 6)
	)
	(segment
		(start 103.775 123.175)
		(end 103.275 123.675)
		(width 0.15)
		(layer "F.Cu")
		(net 6)
	)
	(segment
		(start 97.775 123.175)
		(end 98.275 123.675)
		(width 0.15)
		(layer "F.Cu")
		(net 6)
	)
	(segment
		(start 105.775 121.175)
		(end 106.275 120.675)
		(width 0.15)
		(layer "F.Cu")
		(net 6)
	)
	(segment
		(start 93.8 125.165)
		(end 94.3 125.665)
		(width 0.15)
		(layer "F.Cu")
		(net 6)
	)
	(segment
		(start 104.775 124.175)
		(end 104.275 124.675)
		(width 0.15)
		(layer "F.Cu")
		(net 6)
	)
	(segment
		(start 94.3 125.665)
		(end 94.3 125.690547)
		(width 0.15)
		(layer "F.Cu")
		(net 6)
	)
	(segment
		(start 95.775 124.175)
		(end 96.275 124.675)
		(width 0.15)
		(layer "F.Cu")
		(net 6)
	)
	(segment
		(start 93.775 121.175)
		(end 94.275 121.675)
		(width 0.15)
		(layer "F.Cu")
		(net 6)
	)
	(segment
		(start 104.775 122.175)
		(end 105.275 122.675)
		(width 0.15)
		(layer "F.Cu")
		(net 6)
	)
	(segment
		(start 94.3 125.690547)
		(end 94.293629 125.696918)
		(width 0.15)
		(layer "F.Cu")
		(net 6)
	)
	(segment
		(start 105.775 123.175)
		(end 105.275 123.675)
		(width 0.15)
		(layer "F.Cu")
		(net 6)
	)
	(segment
		(start 75.965 167.915)
		(end 75.865 167.915)
		(width 0.15)
		(layer "F.Cu")
		(net 6)
	)
	(segment
		(start 98.775 122.175)
		(end 99.275 122.675)
		(width 0.15)
		(layer "F.Cu")
		(net 6)
	)
	(segment
		(start 99.775 123.175)
		(end 100.275 123.675)
		(width 0.15)
		(layer "F.Cu")
		(net 6)
	)
	(segment
		(start 98.775 124.175)
		(end 99.275 124.675)
		(width 0.15)
		(layer "F.Cu")
		(net 6)
	)
	(segment
		(start 103.775 121.175)
		(end 103.275 120.675)
		(width 0.15)
		(layer "F.Cu")
		(net 6)
	)
	(segment
		(start 100.775 124.175)
		(end 101.275 124.675)
		(width 0.15)
		(layer "F.Cu")
		(net 6)
	)
	(segment
		(start 98.775 120.175)
		(end 99.275 120.675)
		(width 0.15)
		(layer "F.Cu")
		(net 6)
	)
	(segment
		(start 76.265 167.3)
		(end 76.265 167.615)
		(width 0.15)
		(layer "F.Cu")
		(net 6)
	)
	(segment
		(start 75.55 168.23)
		(end 75.865 167.915)
		(width 0.15)
		(layer "F.Cu")
		(net 6)
	)
	(segment
		(start 76.265 167.615)
		(end 75.965 167.915)
		(width 0.15)
		(layer "F.Cu")
		(net 6)
	)
	(segment
		(start 102.775 124.175)
		(end 103.275 123.675)
		(width 0.15)
		(layer "F.Cu")
		(net 6)
	)
	(segment
		(start 75.55 168.715)
		(end 75.55 168.23)
		(width 0.15)
		(layer "F.Cu")
		(net 6)
	)
	(segment
		(start 80.075 80.075)
		(end 77.575 80.075)
		(width 0.5)
		(layer "F.Cu")
		(net 6)
	)
	(segment
		(start 97.775 121.175)
		(end 97.275 121.675)
		(width 0.15)
		(layer "F.Cu")
		(net 6)
	)
	(via
		(at 94.275 123.675)
		(size 0.5)
		(drill 0.2)
		(layers "F.Cu" "B.Cu")
		(net 6)
	)
	(via
		(at 101.275 120.675)
		(size 0.5)
		(drill 0.2)
		(layers "F.Cu" "B.Cu")
		(net 6)
	)
	(via
		(at 96.275 122.675)
		(size 0.5)
		(drill 0.2)
		(layers "F.Cu" "B.Cu")
		(net 6)
	)
	(via
		(at 103.275 120.675)
		(size 0.5)
		(drill 0.2)
		(layers "F.Cu" "B.Cu")
		(net 6)
	)
	(via
		(at 102.275 123.675)
		(size 0.5)
		(drill 0.2)
		(layers "F.Cu" "B.Cu")
		(net 6)
	)
	(via
		(at 103.275 123.675)
		(size 0.5)
		(drill 0.2)
		(layers "F.Cu" "B.Cu")
		(net 6)
	)
	(via
		(at 79.185 81.4)
		(size 0.5)
		(drill 0.2)
		(layers "F.Cu" "B.Cu")
		(net 6)
	)
	(via
		(at 76.865 81.98)
		(size 0.5)
		(drill 0.2)
		(layers "F.Cu" "B.Cu")
		(net 6)
	)
	(via
		(at 98.275 123.675)
		(size 0.5)
		(drill 0.2)
		(layers "F.Cu" "B.Cu")
		(net 6)
	)
	(via
		(at 106.275 120.675)
		(size 0.5)
		(drill 0.2)
		(layers "F.Cu" "B.Cu")
		(net 6)
	)
	(via
		(at 76.015 81.98)
		(size 0.5)
		(drill 0.2)
		(layers "F.Cu" "B.Cu")
		(net 6)
	)
	(via
		(at 94.1 105)
		(size 0.5)
		(drill 0.2)
		(layers "F.Cu" "B.Cu")
		(net 6)
	)
	(via
		(at 79.9 81.4)
		(size 0.5)
		(drill 0.2)
		(layers "F.Cu" "B.Cu")
		(net 6)
	)
	(via
		(at 94.1 105.6)
		(size 0.5)
		(drill 0.2)
		(layers "F.Cu" "B.Cu")
		(net 6)
	)
	(via
		(at 99.275 124.675)
		(size 0.5)
		(drill 0.2)
		(layers "F.Cu" "B.Cu")
		(net 6)
	)
	(via
		(at 75.865 167.915)
		(size 0.5)
		(drill 0.2)
		(layers "F.Cu" "B.Cu")
		(net 6)
	)
	(via
		(at 94.1 103.2)
		(size 0.5)
		(drill 0.2)
		(layers "F.Cu" "B.Cu")
		(net 6)
	)
	(via
		(at 105.275 122.675)
		(size 0.5)
		(drill 0.2)
		(layers "F.Cu" "B.Cu")
		(net 6)
	)
	(via
		(at 104.275 124.675)
		(size 0.5)
		(drill 0.2)
		(layers "F.Cu" "B.Cu")
		(net 6)
	)
	(via
		(at 101.275 124.675)
		(size 0.5)
		(drill 0.2)
		(layers "F.Cu" "B.Cu")
		(net 6)
	)
	(via
		(at 79.185 80.7)
		(size 0.5)
		(drill 0.2)
		(layers "F.Cu" "B.Cu")
		(net 6)
	)
	(via
		(at 94.275 121.675)
		(size 0.5)
		(drill 0.2)
		(layers "F.Cu" "B.Cu")
		(net 6)
	)
	(via
		(at 97.275 121.675)
		(size 0.5)
		(drill 0.2)
		(layers "F.Cu" "B.Cu")
		(net 6)
	)
	(via
		(at 94.1 103.8)
		(size 0.5)
		(drill 0.2)
		(layers "F.Cu" "B.Cu")
		(net 6)
	)
	(via
		(at 94.1 106.2)
		(size 0.5)
		(drill 0.2)
		(layers "F.Cu" "B.Cu")
		(net 6)
	)
	(via
		(at 105.275 123.675)
		(size 0.5)
		(drill 0.2)
		(layers "F.Cu" "B.Cu")
		(net 6)
	)
	(via
		(at 100.275 123.675)
		(size 0.5)
		(drill 0.2)
		(layers "F.Cu" "B.Cu")
		(net 6)
	)
	(via
		(at 94.1 102)
		(size 0.5)
		(drill 0.2)
		(layers "F.Cu" "B.Cu")
		(net 6)
	)
	(via
		(at 94.1 104.4)
		(size 0.5)
		(drill 0.2)
		(layers "F.Cu" "B.Cu")
		(net 6)
	)
	(via
		(at 99.275 120.675)
		(size 0.5)
		(drill 0.2)
		(layers "F.Cu" "B.Cu")
		(net 6)
	)
	(via
		(at 94.1 102.6)
		(size 0.5)
		(drill 0.2)
		(layers "F.Cu" "B.Cu")
		(net 6)
	)
	(via
		(at 99.275 122.675)
		(size 0.5)
		(drill 0.2)
		(layers "F.Cu" "B.Cu")
		(net 6)
	)
	(via
		(at 94.1 106.8)
		(size 0.5)
		(drill 0.2)
		(layers "F.Cu" "B.Cu")
		(net 6)
	)
	(via
		(at 96.275 124.675)
		(size 0.5)
		(drill 0.2)
		(layers "F.Cu" "B.Cu")
		(net 6)
	)
	(via
		(at 75.175 81.98)
		(size 0.5)
		(drill 0.2)
		(layers "F.Cu" "B.Cu")
		(net 6)
	)
	(via
		(at 79.9 80.7)
		(size 0.5)
		(drill 0.2)
		(layers "F.Cu" "B.Cu")
		(net 6)
	)
	(via
		(at 94.293629 125.696918)
		(size 0.5)
		(drill 0.2)
		(layers "F.Cu" "B.Cu")
		(net 6)
	)
	(segment
		(start 104.645 123.625)
		(end 105.225 123.625)
		(width 0.2)
		(layer "B.Cu")
		(net 6)
	)
	(segment
		(start 77.835 165.945)
		(end 75.865 167.915)
		(width 0.15)
		(layer "B.Cu")
		(net 6)
	)
	(segment
		(start 96.405 123.175)
		(end 96.405 122.805)
		(width 0.15)
		(layer "B.Cu")
		(net 6)
	)
	(segment
		(start 93.849999 126.785001)
		(end 93.849999 128.726001)
		(width 0.15)
		(layer "B.Cu")
		(net 6)
	)
	(segment
		(start 98.905 123.675)
		(end 98.275 123.675)
		(width 0.15)
		(layer "B.Cu")
		(net 6)
	)
	(segment
		(start 95.89 124.29)
		(end 96.275 124.675)
		(width 0.15)
		(layer "B.Cu")
		(net 6)
	)
	(segment
		(start 96.405 122.805)
		(end 96.275 122.675)
		(width 0.15)
		(layer "B.Cu")
		(net 6)
	)
	(segment
		(start 94.275 123.675)
		(end 94.275 124.36)
		(width 0.15)
		(layer "B.Cu")
		(net 6)
	)
	(segment
		(start 100.645 120.675)
		(end 101.275 120.675)
		(width 0.15)
		(layer "B.Cu")
		(net 6)
	)
	(segment
		(start 99.26 124.69)
		(end 99.275 124.675)
		(width 0.15)
		(layer "B.Cu")
		(net 6)
	)
	(segment
		(start 93.849999 128.726001)
		(end 93.849 128.727)
		(width 0.15)
		(layer "B.Cu")
		(net 6)
	)
	(segment
		(start 94.275 120.675)
		(end 94.275 121.675)
		(width 0.15)
		(layer "B.Cu")
		(net 6)
	)
	(segment
		(start 83.215 165.945)
		(end 77.835 165.945)
		(width 0.15)
		(layer "B.Cu")
		(net 6)
	)
	(segment
		(start 99.26 125.275)
		(end 99.26 124.69)
		(width 0.15)
		(layer "B.Cu")
		(net 6)
	)
	(segment
		(start 105.225 123.625)
		(end 105.275 123.675)
		(width 0.2)
		(layer "B.Cu")
		(net 6)
	)
	(segment
		(start 102.595 120.675)
		(end 103.275 120.675)
		(width 0.15)
		(layer "B.Cu")
		(net 6)
	)
	(segment
		(start 106.295 120.695)
		(end 106.275 120.675)
		(width 0.15)
		(layer "B.Cu")
		(net 6)
	)
	(segment
		(start 106.875 120.695)
		(end 106.295 120.695)
		(width 0.15)
		(layer "B.Cu")
		(net 6)
	)
	(segment
		(start 93.855 139.215)
		(end 85.695 147.375)
		(width 0.15)
		(layer "B.Cu")
		(net 6)
	)
	(segment
		(start 93.849 128.727)
		(end 93.855 128.733)
		(width 0.15)
		(layer "B.Cu")
		(net 6)
	)
	(segment
		(start 94.26 124.375)
		(end 94.26 125.663289)
		(width 0.2)
		(layer "B.Cu")
		(net 6)
	)
	(segment
		(start 85.695 163.465)
		(end 83.215 165.945)
		(width 0.15)
		(layer "B.Cu")
		(net 6)
	)
	(segment
		(start 94.26 126.375)
		(end 94.26 125.730547)
		(width 0.15)
		(layer "B.Cu")
		(net 6)
	)
	(segment
		(start 95.89 124.075)
		(end 95.89 124.29)
		(width 0.15)
		(layer "B.Cu")
		(net 6)
	)
	(segment
		(start 98.595 120.675)
		(end 99.275 120.675)
		(width 0.15)
		(layer "B.Cu")
		(net 6)
	)
	(segment
		(start 94.26 125.730547)
		(end 94.293629 125.696918)
		(width 0.15)
		(layer "B.Cu")
		(net 6)
	)
	(segment
		(start 85.695 147.375)
		(end 85.695 163.465)
		(width 0.15)
		(layer "B.Cu")
		(net 6)
	)
	(segment
		(start 96.695 121.675)
		(end 97.275 121.675)
		(width 0.15)
		(layer "B.Cu")
		(net 6)
	)
	(segment
		(start 94.26 126.375)
		(end 93.849999 126.785001)
		(width 0.15)
		(layer "B.Cu")
		(net 6)
	)
	(segment
		(start 94.26 125.663289)
		(end 94.293629 125.696918)
		(width 0.2)
		(layer "B.Cu")
		(net 6)
	)
	(segment
		(start 94.3 119.1)
		(end 94.3 120.65)
		(width 0.2)
		(layer "B.Cu")
		(net 6)
	)
	(segment
		(start 77.544 84.367)
		(end 77.544 82.342)
		(width 0.5)
		(layer "B.Cu")
		(net 6)
	)
	(segment
		(start 94.275 124.36)
		(end 94.26 124.375)
		(width 0.15)
		(layer "B.Cu")
		(net 6)
	)
	(segment
		(start 104.595 122.675)
		(end 105.275 122.675)
		(width 0.15)
		(layer "B.Cu")
		(net 6)
	)
	(segment
		(start 94.3 120.65)
		(end 94.275 120.675)
		(width 0.2)
		(layer "B.Cu")
		(net 6)
	)
	(segment
		(start 100.275 123.675)
		(end 101.005 123.675)
		(width 0.15)
		(layer "B.Cu")
		(net 6)
	)
	(segment
		(start 103.645 124.675)
		(end 104.275 124.675)
		(width 0.15)
		(layer "B.Cu")
		(net 6)
	)
	(segment
		(start 77.544 82.342)
		(end 77.179 81.977)
		(width 0.5)
		(layer "B.Cu")
		(net 6)
	)
	(segment
		(start 77.179 81.977)
		(end 75.149 81.977)
		(width 0.5)
		(layer "B.Cu")
		(net 6)
	)
	(segment
		(start 95.255 103.2)
		(end 94.1 103.2)
		(width 0.2)
		(layer "B.Cu")
		(net 6)
	)
	(segment
		(start 93.855 128.733)
		(end 93.855 139.215)
		(width 0.15)
		(layer "B.Cu")
		(net 6)
	)
	(segment
		(start 76.265 164.93)
		(end 74.965 164.93)
		(width 0.15)
		(layer "F.Cu")
		(net 7)
	)
	(segment
		(start 75 165.865)
		(end 74.515 165.38)
		(width 0.15)
		(layer "F.Cu")
		(net 7)
	)
	(segment
		(start 73.515 165.38)
		(end 74.515 165.38)
		(width 0.15)
		(layer "F.Cu")
		(net 7)
	)
	(segment
		(start 74.965 164.93)
		(end 74.515 165.38)
		(width 0.15)
		(layer "F.Cu")
		(net 7)
	)
	(segment
		(start 75.83 165.865)
		(end 75 165.865)
		(width 0.15)
		(layer "F.Cu")
		(net 7)
	)
	(segment
		(start 77.725 65.25)
		(end 77.205 65.25)
		(width 0.15)
		(layer "F.Cu")
		(net 8)
	)
	(segment
		(start 82.755 67.129)
		(end 82.734 67.15)
		(width 0.15)
		(layer "F.Cu")
		(net 8)
	)
	(segment
		(start 77.205 65.25)
		(end 76.865 65.59)
		(width 0.15)
		(layer "F.Cu")
		(net 8)
	)
	(segment
		(start 82.755 66.28)
		(end 82.755 67.129)
		(width 0.15)
		(layer "F.Cu")
		(net 8)
	)
	(via
		(at 82.755 66.28)
		(size 0.5)
		(drill 0.2)
		(layers "F.Cu" "B.Cu")
		(net 8)
	)
	(via
		(at 76.865 65.59)
		(size 0.5)
		(drill 0.2)
		(layers "F.Cu" "B.Cu")
		(net 8)
	)
	(segment
		(start 76.865 65.59)
		(end 82.065 65.59)
		(width 0.15)
		(layer "B.Cu")
		(net 8)
	)
	(segment
		(start 82.065 65.59)
		(end 82.755 66.28)
		(width 0.15)
		(layer "B.Cu")
		(net 8)
	)
	(segment
		(start 100.6375 158.775)
		(end 100.6375 155.1975)
		(width 0.2)
		(layer "F.Cu")
		(net 9)
	)
	(segment
		(start 99.675 155.16)
		(end 100.675 155.16)
		(width 0.2)
		(layer "F.Cu")
		(net 9)
	)
	(segment
		(start 100.6375 155.1975)
		(end 100.675 155.16)
		(width 0.2)
		(layer "F.Cu")
		(net 9)
	)
	(segment
		(start 89.52 74.885)
		(end 90.52 74.885)
		(width 0.25)
		(layer "F.Cu")
		(net 10)
	)
	(segment
		(start 89.485 74.85)
		(end 89.52 74.885)
		(width 0.25)
		(layer "F.Cu")
		(net 10)
	)
	(segment
		(start 87.645 74.85)
		(end 89.485 74.85)
		(width 0.25)
		(layer "F.Cu")
		(net 10)
	)
	(segment
		(start 90.52 74.885)
		(end 91.52 74.885)
		(width 0.25)
		(layer "F.Cu")
		(net 10)
	)
	(segment
		(start 125.225 130.825)
		(end 125.275 130.875)
		(width 0.2)
		(layer "F.Cu")
		(net 11)
	)
	(segment
		(start 125.225 129.91)
		(end 125.225 130.825)
		(width 0.2)
		(layer "F.Cu")
		(net 11)
	)
	(via
		(at 125.275 130.875)
		(size 0.5)
		(drill 0.2)
		(layers "F.Cu" "B.Cu")
		(net 11)
	)
	(segment
		(start 125.285 130.15)
		(end 125.275 130.16)
		(width 0.15)
		(layer "B.Cu")
		(net 11)
	)
	(segment
		(start 126.315 130.15)
		(end 125.285 130.15)
		(width 0.15)
		(layer "B.Cu")
		(net 11)
	)
	(segment
		(start 125.275 130.875)
		(end 125.275 130.16)
		(width 0.2)
		(layer "B.Cu")
		(net 11)
	)
	(segment
		(start 125.425 113.81)
		(end 125.425 114.625)
		(width 0.15)
		(layer "F.Cu")
		(net 12)
	)
	(segment
		(start 125.425 114.625)
		(end 125.475 114.675)
		(width 0.15)
		(layer "F.Cu")
		(net 12)
	)
	(via
		(at 125.475 114.675)
		(size 0.5)
		(drill 0.2)
		(layers "F.Cu" "B.Cu")
		(net 12)
	)
	(segment
		(start 125.925 113.95)
		(end 124.91 113.95)
		(width 0.15)
		(layer "B.Cu")
		(net 12)
	)
	(segment
		(start 125.915 113.965)
		(end 125.915 114.425)
		(width 0.15)
		(layer "B.Cu")
		(net 12)
	)
	(segment
		(start 125.915 114.425)
		(end 125.665 114.675)
		(width 0.15)
		(layer "B.Cu")
		(net 12)
	)
	(segment
		(start 125.935 113.945)
		(end 125.915 113.965)
		(width 0.15)
		(layer "B.Cu")
		(net 12)
	)
	(segment
		(start 124.91 113.95)
		(end 124.9 113.96)
		(width 0.15)
		(layer "B.Cu")
		(net 12)
	)
	(segment
		(start 125.665 114.675)
		(end 125.475 114.675)
		(width 0.15)
		(layer "B.Cu")
		(net 12)
	)
	(segment
		(start 134.625 70.555)
		(end 136.025 71.955)
		(width 0.15)
		(layer "F.Cu")
		(net 13)
	)
	(segment
		(start 126.965 90.845833)
		(end 126.183333 90.845833)
		(width 0.1)
		(layer "F.Cu")
		(net 13)
	)
	(segment
		(start 136.025 77.655)
		(end 136.05 77.68)
		(width 0.15)
		(layer "F.Cu")
		(net 13)
	)
	(segment
		(start 126.183333 90.845833)
		(end 126.15 90.8125)
		(width 0.1)
		(layer "F.Cu")
		(net 13)
	)
	(segment
		(start 136.025 75.905)
		(end 136.025 77.655)
		(width 0.15)
		(layer "F.Cu")
		(net 13)
	)
	(segment
		(start 104.775 118.175)
		(end 105.275 118.675)
		(width 0.15)
		(layer "F.Cu")
		(net 13)
	)
	(segment
		(start 136.025 71.955)
		(end 136.025 75.905)
		(width 0.15)
		(layer "F.Cu")
		(net 13)
	)
	(via
		(at 114.275 119.875)
		(size 0.5)
		(drill 0.2)
		(layers "F.Cu" "B.Cu")
		(net 13)
	)
	(via
		(at 114.27 161.66)
		(size 0.5)
		(drill 0.2)
		(layers "F.Cu" "B.Cu")
		(net 13)
	)
	(via
		(at 126.15 90.8125)
		(size 0.5)
		(drill 0.2)
		(layers "F.Cu" "B.Cu")
		(net 13)
	)
	(via blind
		(at 105.275 118.675)
		(size 0.5)
		(drill 0.2)
		(layers "F.Cu" "In2.Cu")
		(net 13)
	)
	(via
		(at 136.05 77.68)
		(size 0.5)
		(drill 0.2)
		(layers "F.Cu" "B.Cu")
		(net 13)
	)
	(segment
		(start 111.09 167.828556)
		(end 114.95 163.968556)
		(width 0.15)
		(layer "B.Cu")
		(net 13)
	)
	(segment
		(start 111.09 177.345)
		(end 111.09 167.828556)
		(width 0.15)
		(layer "B.Cu")
		(net 13)
	)
	(segment
		(start 114.95 163.968556)
		(end 114.95 162.34)
		(width 0.15)
		(layer "B.Cu")
		(net 13)
	)
	(segment
		(start 114.95 162.34)
		(end 114.27 161.66)
		(width 0.15)
		(layer "B.Cu")
		(net 13)
	)
	(segment
		(start 113.59 119.19)
		(end 114.275 119.875)
		(width 0.15)
		(layer "In2.Cu")
		(net 13)
	)
	(segment
		(start 105.275 118.675)
		(end 105.79 119.19)
		(width 0.15)
		(layer "In2.Cu")
		(net 13)
	)
	(segment
		(start 105.79 119.19)
		(end 113.59 119.19)
		(width 0.15)
		(layer "In2.Cu")
		(net 13)
	)
	(segment
		(start 125.575 90.775)
		(end 126.1125 90.775)
		(width 0.15)
		(layer "In5.Cu")
		(net 13)
	)
	(segment
		(start 114.419 157.377)
		(end 114.419 128.962728)
		(width 0.15)
		(layer "In5.Cu")
		(net 13)
	)
	(segment
		(start 114.275 119.875)
		(end 114.275 118.775)
		(width 0.15)
		(layer "In5.Cu")
		(net 13)
	)
	(segment
		(start 136.05 77.68)
		(end 136.05 80.8125)
		(width 0.15)
		(layer "In5.Cu")
		(net 13)
	)
	(segment
		(start 126.1125 90.775)
		(end 126.15 90.8125)
		(width 0.15)
		(layer "In5.Cu")
		(net 13)
	)
	(segment
		(start 119.175 97.175)
		(end 125.575 90.775)
		(width 0.15)
		(layer "In5.Cu")
		(net 13)
	)
	(segment
		(start 127.75 89.1125)
		(end 127.75 90.1125)
		(width 0.15)
		(layer "In5.Cu")
		(net 13)
	)
	(segment
		(start 114.275 121.180721)
		(end 114.275 119.875)
		(width 0.15)
		(layer "In5.Cu")
		(net 13)
	)
	(segment
		(start 114.27 161.66)
		(end 113.799989 161.189989)
		(width 0.15)
		(layer "In5.Cu")
		(net 13)
	)
	(segment
		(start 114.419 128.962728)
		(end 113.81868 128.362408)
		(width 0.15)
		(layer "In5.Cu")
		(net 13)
	)
	(segment
		(start 114.275 118.775)
		(end 119.175 113.875)
		(width 0.15)
		(layer "In5.Cu")
		(net 13)
	)
	(segment
		(start 127.75 90.1125)
		(end 127.05 90.8125)
		(width 0.15)
		(layer "In5.Cu")
		(net 13)
	)
	(segment
		(start 113.799989 161.189989)
		(end 113.799989 157.996011)
		(width 0.15)
		(layer "In5.Cu")
		(net 13)
	)
	(segment
		(start 136.05 80.8125)
		(end 127.75 89.1125)
		(width 0.15)
		(layer "In5.Cu")
		(net 13)
	)
	(segment
		(start 127.05 90.8125)
		(end 126.15 90.8125)
		(width 0.15)
		(layer "In5.Cu")
		(net 13)
	)
	(segment
		(start 113.799989 157.996011)
		(end 114.419 157.377)
		(width 0.15)
		(layer "In5.Cu")
		(net 13)
	)
	(segment
		(start 119.175 113.875)
		(end 119.175 97.175)
		(width 0.15)
		(layer "In5.Cu")
		(net 13)
	)
	(segment
		(start 113.81868 128.362408)
		(end 113.799989 121.655732)
		(width 0.15)
		(layer "In5.Cu")
		(net 13)
	)
	(segment
		(start 113.799989 121.655732)
		(end 114.275 121.180721)
		(width 0.15)
		(layer "In5.Cu")
		(net 13)
	)
	(segment
		(start 106.775 118.175)
		(end 107.275 118.675)
		(width 0.15)
		(layer "F.Cu")
		(net 14)
	)
	(segment
		(start 136.525 75.905)
		(end 136.525 78.13)
		(width 0.15)
		(layer "F.Cu")
		(net 14)
	)
	(segment
		(start 136.525 70.655)
		(end 136.525 75.905)
		(width 0.15)
		(layer "F.Cu")
		(net 14)
	)
	(segment
		(start 136.625 70.555)
		(end 136.525 70.655)
		(width 0.15)
		(layer "F.Cu")
		(net 14)
	)
	(segment
		(start 126.965 91.979166)
		(end 126.183334 91.979166)
		(width 0.1)
		(layer "F.Cu")
		(net 14)
	)
	(segment
		(start 126.183334 91.979166)
		(end 126.15 92.0125)
		(width 0.1)
		(layer "F.Cu")
		(net 14)
	)
	(via blind
		(at 107.275 118.675)
		(size 0.5)
		(drill 0.2)
		(layers "F.Cu" "In2.Cu")
		(net 14)
	)
	(via
		(at 114.782566 119.468947)
		(size 0.5)
		(drill 0.2)
		(layers "F.Cu" "B.Cu")
		(net 14)
	)
	(via
		(at 126.15 92.0125)
		(size 0.5)
		(drill 0.2)
		(layers "F.Cu" "B.Cu")
		(net 14)
	)
	(via
		(at 114.274999 160.79)
		(size 0.5)
		(drill 0.2)
		(layers "F.Cu" "B.Cu")
		(net 14)
	)
	(via
		(at 136.525 78.13)
		(size 0.5)
		(drill 0.2)
		(layers "F.Cu" "B.Cu")
		(net 14)
	)
	(segment
		(start 115.27 161.785001)
		(end 114.274999 160.79)
		(width 0.15)
		(layer "B.Cu")
		(net 14)
	)
	(segment
		(start 111.69 167.652834)
		(end 115.27 164.072834)
		(width 0.15)
		(layer "B.Cu")
		(net 14)
	)
	(segment
		(start 111.69 177.345)
		(end 111.69 167.652834)
		(width 0.15)
		(layer "B.Cu")
		(net 14)
	)
	(segment
		(start 115.27 164.072834)
		(end 115.27 161.785001)
		(width 0.15)
		(layer "B.Cu")
		(net 14)
	)
	(segment
		(start 114.088619 118.775)
		(end 114.782566 119.468947)
		(width 0.15)
		(layer "In2.Cu")
		(net 14)
	)
	(segment
		(start 111.175 118.775)
		(end 114.088619 118.775)
		(width 0.15)
		(layer "In2.Cu")
		(net 14)
	)
	(segment
		(start 107.275 118.675)
		(end 107.975 117.975)
		(width 0.15)
		(layer "In2.Cu")
		(net 14)
	)
	(segment
		(start 110.375 117.975)
		(end 111.175 118.775)
		(width 0.15)
		(layer "In2.Cu")
		(net 14)
	)
	(segment
		(start 107.975 117.975)
		(end 110.375 117.975)
		(width 0.15)
		(layer "In2.Cu")
		(net 14)
	)
	(segment
		(start 114.1 121.78)
		(end 114.1 128.29016)
		(width 0.15)
		(layer "In5.Cu")
		(net 14)
	)
	(segment
		(start 114.782566 118.928432)
		(end 119.475 114.235998)
		(width 0.15)
		(layer "In5.Cu")
		(net 14)
	)
	(segment
		(start 114.1 160.261448)
		(end 114.274999 160.436447)
		(width 0.15)
		(layer "In5.Cu")
		(net 14)
	)
	(segment
		(start 119.475 97.375)
		(end 124.8375 92.0125)
		(width 0.15)
		(layer "In5.Cu")
		(net 14)
	)
	(segment
		(start 128.35 89.0125)
		(end 128.35 90.8125)
		(width 0.15)
		(layer "In5.Cu")
		(net 14)
	)
	(segment
		(start 114.719 128.90916)
		(end 114.719 157.477)
		(width 0.15)
		(layer "In5.Cu")
		(net 14)
	)
	(segment
		(start 114.719 157.477)
		(end 114.1 158.096)
		(width 0.15)
		(layer "In5.Cu")
		(net 14)
	)
	(segment
		(start 114.1 128.29016)
		(end 114.719 128.90916)
		(width 0.15)
		(layer "In5.Cu")
		(net 14)
	)
	(segment
		(start 114.782566 119.468947)
		(end 114.782566 118.928432)
		(width 0.15)
		(layer "In5.Cu")
		(net 14)
	)
	(segment
		(start 114.1 158.096)
		(end 114.1 160.261448)
		(width 0.15)
		(layer "In5.Cu")
		(net 14)
	)
	(segment
		(start 128.35 90.8125)
		(end 127.15 92.0125)
		(width 0.15)
		(layer "In5.Cu")
		(net 14)
	)
	(segment
		(start 114.274999 160.436447)
		(end 114.274999 160.79)
		(width 0.15)
		(layer "In5.Cu")
		(net 14)
	)
	(segment
		(start 114.782566 119.468947)
		(end 114.782566 121.097434)
		(width 0.15)
		(layer "In5.Cu")
		(net 14)
	)
	(segment
		(start 119.475 114.235998)
		(end 119.475 97.375)
		(width 0.15)
		(layer "In5.Cu")
		(net 14)
	)
	(segment
		(start 124.8375 92.0125)
		(end 126.15 92.0125)
		(width 0.15)
		(layer "In5.Cu")
		(net 14)
	)
	(segment
		(start 136.45 80.9125)
		(end 128.35 89.0125)
		(width 0.15)
		(layer "In5.Cu")
		(net 14)
	)
	(segment
		(start 114.782566 121.097434)
		(end 114.1 121.78)
		(width 0.15)
		(layer "In5.Cu")
		(net 14)
	)
	(segment
		(start 127.15 92.0125)
		(end 126.15 92.0125)
		(width 0.15)
		(layer "In5.Cu")
		(net 14)
	)
	(segment
		(start 136.45 78.205)
		(end 136.45 80.9125)
		(width 0.15)
		(layer "In5.Cu")
		(net 14)
	)
	(segment
		(start 136.525 78.13)
		(end 136.45 78.205)
		(width 0.15)
		(layer "In5.Cu")
		(net 14)
	)
	(segment
		(start 137.05 77.18)
		(end 137.925 77.18)
		(width 0.15)
		(layer "F.Cu")
		(net 15)
	)
	(segment
		(start 137.925 77.18)
		(end 138.525 76.58)
		(width 0.15)
		(layer "F.Cu")
		(net 15)
	)
	(segment
		(start 138.525 70.655)
		(end 138.525 75.905)
		(width 0.15)
		(layer "F.Cu")
		(net 15)
	)
	(segment
		(start 108.26999 119.66999)
		(end 108.275 119.66999)
		(width 0.15)
		(layer "F.Cu")
		(net 15)
	)
	(segment
		(start 138.525 76.58)
		(end 138.525 75.905)
		(width 0.15)
		(layer "F.Cu")
		(net 15)
	)
	(segment
		(start 107.775 119.175)
		(end 108.26999 119.66999)
		(width 0.15)
		(layer "F.Cu")
		(net 15)
	)
	(segment
		(start 126.965 89.7125)
		(end 126.15 89.7125)
		(width 0.1)
		(layer "F.Cu")
		(net 15)
	)
	(segment
		(start 138.625 70.555)
		(end 138.525 70.655)
		(width 0.15)
		(layer "F.Cu")
		(net 15)
	)
	(via
		(at 137.05 77.18)
		(size 0.5)
		(drill 0.2)
		(layers "F.Cu" "B.Cu")
		(net 15)
	)
	(via
		(at 114.27 162.53)
		(size 0.5)
		(drill 0.2)
		(layers "F.Cu" "B.Cu")
		(net 15)
	)
	(via
		(at 126.15 89.7125)
		(size 0.5)
		(drill 0.2)
		(layers "F.Cu" "B.Cu")
		(net 15)
	)
	(via
		(at 113.774994 120.375)
		(size 0.5)
		(drill 0.2)
		(layers "F.Cu" "B.Cu")
		(net 15)
	)
	(via blind
		(at 108.275 119.66999)
		(size 0.5)
		(drill 0.2)
		(layers "F.Cu" "In2.Cu")
		(net 15)
	)
	(segment
		(start 114.27 162.54)
		(end 114.27 162.53)
		(width 0.15)
		(layer "B.Cu")
		(net 15)
	)
	(segment
		(start 109.89 168.18)
		(end 113.7 164.37)
		(width 0.15)
		(layer "B.Cu")
		(net 15)
	)
	(segment
		(start 109.89 177.345)
		(end 109.89 168.18)
		(width 0.15)
		(layer "B.Cu")
		(net 15)
	)
	(segment
		(start 113.7 163.11)
		(end 114.27 162.54)
		(width 0.15)
		(layer "B.Cu")
		(net 15)
	)
	(segment
		(start 113.7 164.37)
		(end 113.7 163.11)
		(width 0.15)
		(layer "B.Cu")
		(net 15)
	)
	(segment
		(start 113.069984 119.66999)
		(end 108.275 119.66999)
		(width 0.15)
		(layer "In2.Cu")
		(net 15)
	)
	(segment
		(start 113.774994 120.375)
		(end 113.069984 119.66999)
		(width 0.15)
		(layer "In2.Cu")
		(net 15)
	)
	(segment
		(start 113.774994 118.675006)
		(end 118.875 113.575)
		(width 0.15)
		(layer "In5.Cu")
		(net 15)
	)
	(segment
		(start 118.875 96.9875)
		(end 126.15 89.7125)
		(width 0.15)
		(layer "In5.Cu")
		(net 15)
	)
	(segment
		(start 137.05 77.18)
		(end 135.85 77.18)
		(width 0.15)
		(layer "In5.Cu")
		(net 15)
	)
	(segment
		(start 113.499978 157.796022)
		(end 113.499978 161.759978)
		(width 0.15)
		(layer "In5.Cu")
		(net 15)
	)
	(segment
		(start 113.774994 120.375)
		(end 113.774994 118.675006)
		(width 0.15)
		(layer "In5.Cu")
		(net 15)
	)
	(segment
		(start 114.119 129.016296)
		(end 114.119 157.177)
		(width 0.15)
		(layer "In5.Cu")
		(net 15)
	)
	(segment
		(start 113.774994 120.375)
		(end 113.499978 120.650016)
		(width 0.15)
		(layer "In5.Cu")
		(net 15)
	)
	(segment
		(start 126.65 89.7125)
		(end 126.15 89.7125)
		(width 0.15)
		(layer "In5.Cu")
		(net 15)
	)
	(segment
		(start 135.6 77.415)
		(end 135.6 80.7625)
		(width 0.15)
		(layer "In5.Cu")
		(net 15)
	)
	(segment
		(start 113.499978 120.650016)
		(end 113.499978 128.397274)
		(width 0.15)
		(layer "In5.Cu")
		(net 15)
	)
	(segment
		(start 114.119 157.177)
		(end 113.499978 157.796022)
		(width 0.15)
		(layer "In5.Cu")
		(net 15)
	)
	(segment
		(start 118.875 113.575)
		(end 118.875 96.9875)
		(width 0.15)
		(layer "In5.Cu")
		(net 15)
	)
	(segment
		(start 135.85 77.18)
		(end 135.615 77.415)
		(width 0.15)
		(layer "In5.Cu")
		(net 15)
	)
	(segment
		(start 135.8 77.215)
		(end 135.6 77.415)
		(width 0.15)
		(layer "In5.Cu")
		(net 15)
	)
	(segment
		(start 113.499978 128.397274)
		(end 114.119 129.016296)
		(width 0.15)
		(layer "In5.Cu")
		(net 15)
	)
	(segment
		(start 135.6 80.7625)
		(end 126.65 89.7125)
		(width 0.15)
		(layer "In5.Cu")
		(net 15)
	)
	(segment
		(start 113.499978 161.759978)
		(end 114.27 162.53)
		(width 0.15)
		(layer "In5.Cu")
		(net 15)
	)
	(segment
		(start 139.025 72.155)
		(end 139.025 75.905)
		(width 0.15)
		(layer "F.Cu")
		(net 16)
	)
	(segment
		(start 137 78.605)
		(end 139.025 76.58)
		(width 0.15)
		(layer "F.Cu")
		(net 16)
	)
	(segment
		(start 140.625 70.555)
		(end 139.025 72.155)
		(width 0.15)
		(layer "F.Cu")
		(net 16)
	)
	(segment
		(start 126.965 93.1125)
		(end 126.15 93.1125)
		(width 0.1)
		(layer "F.Cu")
		(net 16)
	)
	(segment
		(start 139.025 76.58)
		(end 139.025 75.905)
		(width 0.15)
		(layer "F.Cu")
		(net 16)
	)
	(segment
		(start 105.775 118.175)
		(end 105.275 117.675)
		(width 0.15)
		(layer "F.Cu")
		(net 16)
	)
	(via
		(at 126.15 93.1125)
		(size 0.5)
		(drill 0.2)
		(layers "F.Cu" "B.Cu")
		(net 16)
	)
	(via blind
		(at 105.275 117.675)
		(size 0.5)
		(drill 0.2)
		(layers "F.Cu" "In2.Cu")
		(net 16)
	)
	(via
		(at 137 78.605)
		(size 0.5)
		(drill 0.2)
		(layers "F.Cu" "B.Cu")
		(net 16)
	)
	(via
		(at 114.27 163.4)
		(size 0.5)
		(drill 0.2)
		(layers "F.Cu" "B.Cu")
		(net 16)
	)
	(via
		(at 115.32 119.02)
		(size 0.5)
		(drill 0.2)
		(layers "F.Cu" "B.Cu")
		(net 16)
	)
	(segment
		(start 110.49 168.004278)
		(end 114.27 164.224278)
		(width 0.15)
		(layer "B.Cu")
		(net 16)
	)
	(segment
		(start 110.49 177.345)
		(end 110.49 168.004278)
		(width 0.15)
		(layer "B.Cu")
		(net 16)
	)
	(segment
		(start 114.27 164.224278)
		(end 114.27 163.4)
		(width 0.15)
		(layer "B.Cu")
		(net 16)
	)
	(segment
		(start 110.250722 117.675)
		(end 110.250731 117.674991)
		(width 0.15)
		(layer "In2.Cu")
		(net 16)
	)
	(segment
		(start 108.975 117.675)
		(end 110.250722 117.675)
		(width 0.15)
		(layer "In2.Cu")
		(net 16)
	)
	(segment
		(start 114.774991 118.474991)
		(end 115.32 119.02)
		(width 0.15)
		(layer "In2.Cu")
		(net 16)
	)
	(segment
		(start 110.250731 117.674991)
		(end 110.874991 117.674991)
		(width 0.15)
		(layer "In2.Cu")
		(net 16)
	)
	(segment
		(start 113.964341 118.475)
		(end 113.96435 118.474991)
		(width 0.15)
		(layer "In2.Cu")
		(net 16)
	)
	(segment
		(start 105.775 118.175)
		(end 107.275 118.175)
		(width 0.15)
		(layer "In2.Cu")
		(net 16)
	)
	(segment
		(start 111.675 118.475)
		(end 113.964341 118.475)
		(width 0.15)
		(layer "In2.Cu")
		(net 16)
	)
	(segment
		(start 107.775009 117.674991)
		(end 108.974991 117.674991)
		(width 0.15)
		(layer "In2.Cu")
		(net 16)
	)
	(segment
		(start 105.275 117.675)
		(end 105.775 118.175)
		(width 0.15)
		(layer "In2.Cu")
		(net 16)
	)
	(segment
		(start 113.96435 118.474991)
		(end 114.774991 118.474991)
		(width 0.15)
		(layer "In2.Cu")
		(net 16)
	)
	(segment
		(start 107.275 118.175)
		(end 107.775009 117.674991)
		(width 0.15)
		(layer "In2.Cu")
		(net 16)
	)
	(segment
		(start 108.974991 117.674991)
		(end 108.975 117.675)
		(width 0.15)
		(layer "In2.Cu")
		(net 16)
	)
	(segment
		(start 110.874991 117.674991)
		(end 111.675 118.475)
		(width 0.15)
		(layer "In2.Cu")
		(net 16)
	)
	(segment
		(start 119.775 114.575)
		(end 119.775 97.575)
		(width 0.15)
		(layer "In5.Cu")
		(net 16)
	)
	(segment
		(start 129.05 91.6125)
		(end 129.05 88.797999)
		(width 0.15)
		(layer "In5.Cu")
		(net 16)
	)
	(segment
		(start 114.519 121.937998)
		(end 115.32 121.136998)
		(width 0.15)
		(layer "In5.Cu")
		(net 16)
	)
	(segment
		(start 124.2375 93.1125)
		(end 126.15 93.1125)
		(width 0.15)
		(layer "In5.Cu")
		(net 16)
	)
	(segment
		(start 115.32 121.136998)
		(end 115.32 119.02)
		(width 0.15)
		(layer "In5.Cu")
		(net 16)
	)
	(segment
		(start 114.98 162.69)
		(end 114.98 160.69)
		(width 0.15)
		(layer "In5.Cu")
		(net 16)
	)
	(segment
		(start 114.27 163.4)
		(end 114.98 162.69)
		(width 0.15)
		(layer "In5.Cu")
		(net 16)
	)
	(segment
		(start 114.519 128.277)
		(end 114.519 121.937998)
		(width 0.15)
		(layer "In5.Cu")
		(net 16)
	)
	(segment
		(start 114.519 158.177)
		(end 115.019 157.677)
		(width 0.15)
		(layer "In5.Cu")
		(net 16)
	)
	(segment
		(start 114.98 160.69)
		(end 114.519 160.229)
		(width 0.15)
		(layer "In5.Cu")
		(net 16)
	)
	(segment
		(start 137 80.847999)
		(end 137 78.605)
		(width 0.15)
		(layer "In5.Cu")
		(net 16)
	)
	(segment
		(start 114.519 160.229)
		(end 114.519 158.177)
		(width 0.15)
		(layer "In5.Cu")
		(net 16)
	)
	(segment
		(start 115.579999 118.770001)
		(end 119.775 114.575)
		(width 0.15)
		(layer "In5.Cu")
		(net 16)
	)
	(segment
		(start 126.15 93.1125)
		(end 127.55 93.1125)
		(width 0.15)
		(layer "In5.Cu")
		(net 16)
	)
	(segment
		(start 119.775 97.575)
		(end 124.2375 93.1125)
		(width 0.15)
		(layer "In5.Cu")
		(net 16)
	)
	(segment
		(start 115.019 128.777)
		(end 114.519 128.277)
		(width 0.15)
		(layer "In5.Cu")
		(net 16)
	)
	(segment
		(start 129.05 88.797999)
		(end 137 80.847999)
		(width 0.15)
		(layer "In5.Cu")
		(net 16)
	)
	(segment
		(start 115.569999 118.770001)
		(end 115.579999 118.770001)
		(width 0.15)
		(layer "In5.Cu")
		(net 16)
	)
	(segment
		(start 115.32 119.02)
		(end 115.569999 118.770001)
		(width 0.15)
		(layer "In5.Cu")
		(net 16)
	)
	(segment
		(start 127.55 93.1125)
		(end 129.05 91.6125)
		(width 0.15)
		(layer "In5.Cu")
		(net 16)
	)
	(segment
		(start 115.019 157.677)
		(end 115.019 128.777)
		(width 0.15)
		(layer "In5.Cu")
		(net 16)
	)
	(segment
		(start 102.775 117.175)
		(end 103.275 117.675)
		(width 0.15)
		(layer "F.Cu")
		(net 17)
	)
	(via blind
		(at 103.275 117.675)
		(size 0.5)
		(drill 0.2)
		(layers "F.Cu" "In2.Cu")
		(net 17)
	)
	(via
		(at 92.934 164.92)
		(size 0.5)
		(drill 0.2)
		(layers "F.Cu" "B.Cu")
		(net 17)
	)
	(segment
		(start 93.29 177.155)
		(end 93.29 168.631)
		(width 0.15)
		(layer "B.Cu")
		(net 17)
	)
	(segment
		(start 92.934 168.275)
		(end 92.934 164.92)
		(width 0.15)
		(layer "B.Cu")
		(net 17)
	)
	(segment
		(start 93.29 168.631)
		(end 92.934 168.275)
		(width 0.15)
		(layer "B.Cu")
		(net 17)
	)
	(segment
		(start 88.885022 122.864978)
		(end 88.885022 161.145022)
		(width 0.15)
		(layer "In2.Cu")
		(net 17)
	)
	(segment
		(start 98.475022 120.174978)
		(end 97.046999 120.174978)
		(width 0.15)
		(layer "In2.Cu")
		(net 17)
	)
	(segment
		(start 103.275 117.675)
		(end 101.775 119.175)
		(width 0.15)
		(layer "In2.Cu")
		(net 17)
	)
	(segment
		(start 97.046977 120.175)
		(end 94.065 120.175)
		(width 0.15)
		(layer "In2.Cu")
		(net 17)
	)
	(segment
		(start 99.475 119.175)
		(end 98.475022 120.174978)
		(width 0.15)
		(layer "In2.Cu")
		(net 17)
	)
	(segment
		(start 92.66 164.92)
		(end 92.934 164.92)
		(width 0.15)
		(layer "In2.Cu")
		(net 17)
	)
	(segment
		(start 93.865 120.375)
		(end 91.375 120.375)
		(width 0.15)
		(layer "In2.Cu")
		(net 17)
	)
	(segment
		(start 101.775 119.175)
		(end 99.475 119.175)
		(width 0.15)
		(layer "In2.Cu")
		(net 17)
	)
	(segment
		(start 97.046999 120.174978)
		(end 97.046977 120.175)
		(width 0.15)
		(layer "In2.Cu")
		(net 17)
	)
	(segment
		(start 94.065 120.175)
		(end 93.865 120.375)
		(width 0.15)
		(layer "In2.Cu")
		(net 17)
	)
	(segment
		(start 91.375 120.375)
		(end 88.885022 122.864978)
		(width 0.15)
		(layer "In2.Cu")
		(net 17)
	)
	(segment
		(start 88.885022 161.145022)
		(end 92.66 164.92)
		(width 0.15)
		(layer "In2.Cu")
		(net 17)
	)
	(segment
		(start 102.775 118.175)
		(end 103.275 118.675)
		(width 0.15)
		(layer "F.Cu")
		(net 18)
	)
	(via
		(at 92.755 164.338)
		(size 0.5)
		(drill 0.2)
		(layers "F.Cu" "B.Cu")
		(net 18)
	)
	(via blind
		(at 103.275 118.675)
		(size 0.5)
		(drill 0.2)
		(layers "F.Cu" "In2.Cu")
		(net 18)
	)
	(segment
		(start 92.426 168.656)
		(end 92.426 164.667)
		(width 0.15)
		(layer "B.Cu")
		(net 18)
	)
	(segment
		(start 92.426 164.667)
		(end 92.755 164.338)
		(width 0.15)
		(layer "B.Cu")
		(net 18)
	)
	(segment
		(start 92.815001 171.187999)
		(end 92.815001 169.045001)
		(width 0.15)
		(layer "B.Cu")
		(net 18)
	)
	(segment
		(start 92.69 171.313)
		(end 92.815001 171.187999)
		(width 0.15)
		(layer "B.Cu")
		(net 18)
	)
	(segment
		(start 92.815001 169.045001)
		(end 92.426 168.656)
		(width 0.15)
		(layer "B.Cu")
		(net 18)
	)
	(segment
		(start 92.69 177.155)
		(end 92.69 171.313)
		(width 0.15)
		(layer "B.Cu")
		(net 18)
	)
	(segment
		(start 89.185033 123.064967)
		(end 91.125011 121.124989)
		(width 0.15)
		(layer "In2.Cu")
		(net 18)
	)
	(segment
		(start 89.185033 160.970033)
		(end 89.185033 123.064967)
		(width 0.15)
		(layer "In2.Cu")
		(net 18)
	)
	(segment
		(start 102.775 119.975)
		(end 102.775 119.175)
		(width 0.15)
		(layer "In2.Cu")
		(net 18)
	)
	(segment
		(start 92.5362 121.15001)
		(end 97.924269 121.15001)
		(width 0.15)
		(layer "In2.Cu")
		(net 18)
	)
	(segment
		(start 102.775 119.175)
		(end 103.275 118.675)
		(width 0.15)
		(layer "In2.Cu")
		(net 18)
	)
	(segment
		(start 91.125011 121.124989)
		(end 92.511179 121.124989)
		(width 0.15)
		(layer "In2.Cu")
		(net 18)
	)
	(segment
		(start 92.553 164.338)
		(end 89.185033 160.970033)
		(width 0.15)
		(layer "In2.Cu")
		(net 18)
	)
	(segment
		(start 92.755 164.338)
		(end 92.553 164.338)
		(width 0.15)
		(layer "In2.Cu")
		(net 18)
	)
	(segment
		(start 92.511179 121.124989)
		(end 92.5362 121.15001)
		(width 0.15)
		(layer "In2.Cu")
		(net 18)
	)
	(segment
		(start 102.575 120.175)
		(end 102.775 119.975)
		(width 0.15)
		(layer "In2.Cu")
		(net 18)
	)
	(segment
		(start 98.899279 120.175)
		(end 102.575 120.175)
		(width 0.15)
		(layer "In2.Cu")
		(net 18)
	)
	(segment
		(start 97.924269 121.15001)
		(end 98.899279 120.175)
		(width 0.15)
		(layer "In2.Cu")
		(net 18)
	)
	(segment
		(start 99.775 117.175)
		(end 100.275 117.675)
		(width 0.15)
		(layer "F.Cu")
		(net 19)
	)
	(via blind
		(at 100.275 117.675)
		(size 0.5)
		(drill 0.2)
		(layers "F.Cu" "In5.Cu")
		(net 19)
	)
	(via
		(at 90.3 170.17)
		(size 0.5)
		(drill 0.2)
		(layers "F.Cu" "B.Cu")
		(net 19)
	)
	(segment
		(start 90.29 172.55)
		(end 90.29 177.395)
		(width 0.15)
		(layer "B.Cu")
		(net 19)
	)
	(segment
		(start 90.3 170.17)
		(end 90.3 172.54)
		(width 0.15)
		(layer "B.Cu")
		(net 19)
	)
	(segment
		(start 90.3 172.54)
		(end 90.29 172.55)
		(width 0.15)
		(layer "B.Cu")
		(net 19)
	)
	(segment
		(start 83.950245 155.489541)
		(end 83.950245 124.099755)
		(width 0.15)
		(layer "In5.Cu")
		(net 19)
	)
	(segment
		(start 99.521469 118.074978)
		(end 99.921447 117.675)
		(width 0.15)
		(layer "In5.Cu")
		(net 19)
	)
	(segment
		(start 89.8 169.67)
		(end 89.8 161.339296)
		(width 0.15)
		(layer "In5.Cu")
		(net 19)
	)
	(segment
		(start 83.950245 124.099755)
		(end 89.975022 118.074978)
		(width 0.15)
		(layer "In5.Cu")
		(net 19)
	)
	(segment
		(start 89.8 161.339296)
		(end 83.950245 155.489541)
		(width 0.15)
		(layer "In5.Cu")
		(net 19)
	)
	(segment
		(start 99.921447 117.675)
		(end 100.275 117.675)
		(width 0.15)
		(layer "In5.Cu")
		(net 19)
	)
	(segment
		(start 89.975022 118.074978)
		(end 99.521469 118.074978)
		(width 0.15)
		(layer "In5.Cu")
		(net 19)
	)
	(segment
		(start 90.3 170.17)
		(end 89.8 169.67)
		(width 0.15)
		(layer "In5.Cu")
		(net 19)
	)
	(segment
		(start 95.775 118.175)
		(end 96.275 117.675)
		(width 0.15)
		(layer "F.Cu")
		(net 20)
	)
	(via
		(at 101.085 164.645)
		(size 0.5)
		(drill 0.2)
		(layers "F.Cu" "B.Cu")
		(net 20)
	)
	(via blind
		(at 96.275 117.675)
		(size 0.5)
		(drill 0.2)
		(layers "F.Cu" "In2.Cu")
		(net 20)
	)
	(segment
		(start 101.09 177.345)
		(end 101.09 164.65)
		(width 0.15)
		(layer "B.Cu")
		(net 20)
	)
	(segment
		(start 100.185 165.945)
		(end 92.360721 165.945)
		(width 0.15)
		(layer "In2.Cu")
		(net 20)
	)
	(segment
		(start 94.435021 118.574979)
		(end 95.375021 118.574979)
		(width 0.15)
		(layer "In2.Cu")
		(net 20)
	)
	(segment
		(start 87.984989 122.340732)
		(end 90.850752 119.474969)
		(width 0.15)
		(layer "In2.Cu")
		(net 20)
	)
	(segment
		(start 101.085 164.645)
		(end 101.085 165.045)
		(width 0.15)
		(layer "In2.Cu")
		(net 20)
	)
	(segment
		(start 101.085 165.045)
		(end 100.185 165.945)
		(width 0.15)
		(layer "In2.Cu")
		(net 20)
	)
	(segment
		(start 93.535031 119.474969)
		(end 94.435021 118.574979)
		(width 0.15)
		(layer "In2.Cu")
		(net 20)
	)
	(segment
		(start 87.98499 161.569269)
		(end 87.984989 122.340732)
		(width 0.15)
		(layer "In2.Cu")
		(net 20)
	)
	(segment
		(start 90.850752 119.474969)
		(end 93.535031 119.474969)
		(width 0.15)
		(layer "In2.Cu")
		(net 20)
	)
	(segment
		(start 92.360721 165.945)
		(end 87.98499 161.569269)
		(width 0.15)
		(layer "In2.Cu")
		(net 20)
	)
	(segment
		(start 95.375021 118.574979)
		(end 96.275 117.675)
		(width 0.15)
		(layer "In2.Cu")
		(net 20)
	)
	(segment
		(start 101.775 118.175)
		(end 102.275 117.675)
		(width 0.15)
		(layer "F.Cu")
		(net 21)
	)
	(via blind
		(at 102.275 117.675)
		(size 0.5)
		(drill 0.2)
		(layers "F.Cu" "In5.Cu")
		(net 21)
	)
	(via
		(at 90.92 169.91)
		(size 0.5)
		(drill 0.2)
		(layers "F.Cu" "B.Cu")
		(net 21)
	)
	(segment
		(start 90.92 172.45)
		(end 90.89 172.48)
		(width 0.15)
		(layer "B.Cu")
		(net 21)
	)
	(segment
		(start 90.89 172.48)
		(end 90.89 177.395)
		(width 0.15)
		(layer "B.Cu")
		(net 21)
	)
	(segment
		(start 90.92 169.91)
		(end 90.92 172.45)
		(width 0.15)
		(layer "B.Cu")
		(net 21)
	)
	(segment
		(start 92.278013 118.374989)
		(end 99.872009 118.374989)
		(width 0.15)
		(layer "In5.Cu")
		(net 21)
	)
	(segment
		(start 90.94 162.08)
		(end 84.250256 155.390256)
		(width 0.15)
		(layer "In5.Cu")
		(net 21)
	)
	(segment
		(start 84.250256 124.251186)
		(end 89.126464 119.374978)
		(width 0.15)
		(layer "In5.Cu")
		(net 21)
	)
	(segment
		(start 90.92 169.91)
		(end 90.94 169.89)
		(width 0.15)
		(layer "In5.Cu")
		(net 21)
	)
	(segment
		(start 90.94 169.89)
		(end 90.94 162.08)
		(width 0.15)
		(layer "In5.Cu")
		(net 21)
	)
	(segment
		(start 89.126464 119.374978)
		(end 91.278024 119.374978)
		(width 0.15)
		(layer "In5.Cu")
		(net 21)
	)
	(segment
		(start 91.278024 119.374978)
		(end 92.278013 118.374989)
		(width 0.15)
		(layer "In5.Cu")
		(net 21)
	)
	(segment
		(start 99.872009 118.374989)
		(end 100.096997 118.150001)
		(width 0.15)
		(layer "In5.Cu")
		(net 21)
	)
	(segment
		(start 100.096997 118.150001)
		(end 101.799999 118.150001)
		(width 0.15)
		(layer "In5.Cu")
		(net 21)
	)
	(segment
		(start 84.250256 155.390256)
		(end 84.250256 124.251186)
		(width 0.15)
		(layer "In5.Cu")
		(net 21)
	)
	(segment
		(start 101.799999 118.150001)
		(end 102.275 117.675)
		(width 0.15)
		(layer "In5.Cu")
		(net 21)
	)
	(segment
		(start 100.775 116.175)
		(end 101.275 115.675)
		(width 0.15)
		(layer "F.Cu")
		(net 22)
	)
	(via
		(at 87.87 170.19)
		(size 0.5)
		(drill 0.2)
		(layers "F.Cu" "B.Cu")
		(net 22)
	)
	(via blind
		(at 101.275 115.675)
		(size 0.5)
		(drill 0.2)
		(layers "F.Cu" "In5.Cu")
		(net 22)
	)
	(segment
		(start 87.89 177.155)
		(end 87.89 170.21)
		(width 0.15)
		(layer "B.Cu")
		(net 22)
	)
	(segment
		(start 87.89 170.21)
		(end 87.87 170.19)
		(width 0.15)
		(layer "B.Cu")
		(net 22)
	)
	(segment
		(start 82.750201 157.325201)
		(end 82.750201 123.526962)
		(width 0.15)
		(layer "In5.Cu")
		(net 22)
	)
	(segment
		(start 100.47502 116.47498)
		(end 101.275 115.675)
		(width 0.15)
		(layer "In5.Cu")
		(net 22)
	)
	(segment
		(start 94.026464 116.17502)
		(end 94.626462 116.775018)
		(width 0.15)
		(layer "In5.Cu")
		(net 22)
	)
	(segment
		(start 94.875022 116.775022)
		(end 98.1507 116.775022)
		(width 0.15)
		(layer "In5.Cu")
		(net 22)
	)
	(segment
		(start 98.450742 116.47498)
		(end 100.47502 116.47498)
		(width 0.15)
		(layer "In5.Cu")
		(net 22)
	)
	(segment
		(start 98.1507 116.775022)
		(end 98.450742 116.47498)
		(width 0.15)
		(layer "In5.Cu")
		(net 22)
	)
	(segment
		(start 94.875019 116.775019)
		(end 94.875022 116.775022)
		(width 0.15)
		(layer "In5.Cu")
		(net 22)
	)
	(segment
		(start 87.89 170.17)
		(end 87.89 161.69)
		(width 0.15)
		(layer "In5.Cu")
		(net 22)
	)
	(segment
		(start 84.865 158.665)
		(end 84.09 158.665)
		(width 0.15)
		(layer "In5.Cu")
		(net 22)
	)
	(segment
		(start 90.102143 116.17502)
		(end 94.026464 116.17502)
		(width 0.15)
		(layer "In5.Cu")
		(net 22)
	)
	(segment
		(start 87.89 161.69)
		(end 84.865 158.665)
		(width 0.15)
		(layer "In5.Cu")
		(net 22)
	)
	(segment
		(start 82.750201 123.526962)
		(end 90.102143 116.17502)
		(width 0.15)
		(layer "In5.Cu")
		(net 22)
	)
	(segment
		(start 94.626462 116.775018)
		(end 94.875019 116.775019)
		(width 0.15)
		(layer "In5.Cu")
		(net 22)
	)
	(segment
		(start 87.87 170.19)
		(end 87.89 170.17)
		(width 0.15)
		(layer "In5.Cu")
		(net 22)
	)
	(segment
		(start 84.09 158.665)
		(end 82.750201 157.325201)
		(width 0.15)
		(layer "In5.Cu")
		(net 22)
	)
	(segment
		(start 101.775 116.175)
		(end 101.275 116.675)
		(width 0.15)
		(layer "F.Cu")
		(net 23)
	)
	(via blind
		(at 101.275 116.675)
		(size 0.5)
		(drill 0.2)
		(layers "F.Cu" "In5.Cu")
		(net 23)
	)
	(via
		(at 88.39 170.71)
		(size 0.5)
		(drill 0.2)
		(layers "F.Cu" "B.Cu")
		(net 23)
	)
	(segment
		(start 88.49 170.81)
		(end 88.49 177.22)
		(width 0.15)
		(layer "B.Cu")
		(net 23)
	)
	(segment
		(start 88.39 170.71)
		(end 88.49 170.81)
		(width 0.15)
		(layer "B.Cu")
		(net 23)
	)
	(segment
		(start 88.4 161.43)
		(end 88.4 170.7)
		(width 0.15)
		(layer "In5.Cu")
		(net 23)
	)
	(segment
		(start 98.225001 117.125)
		(end 89.576442 117.125)
		(width 0.15)
		(layer "In5.Cu")
		(net 23)
	)
	(segment
		(start 84.97 158)
		(end 88.4 161.43)
		(width 0.15)
		(layer "In5.Cu")
		(net 23)
	)
	(segment
		(start 84.97 157.57)
		(end 84.97 158)
		(width 0.15)
		(layer "In5.Cu")
		(net 23)
	)
	(segment
		(start 100.67501 116.77499)
		(end 100.775 116.675)
		(width 0.15)
		(layer "In5.Cu")
		(net 23)
	)
	(segment
		(start 83.050212 123.65123)
		(end 83.050212 155.650212)
		(width 0.15)
		(layer "In5.Cu")
		(net 23)
	)
	(segment
		(start 89.576442 117.125)
		(end 83.050212 123.65123)
		(width 0.15)
		(layer "In5.Cu")
		(net 23)
	)
	(segment
		(start 98.57501 116.774991)
		(end 98.225001 117.125)
		(width 0.15)
		(layer "In5.Cu")
		(net 23)
	)
	(segment
		(start 98.57501 116.774991)
		(end 100.67501 116.77499)
		(width 0.15)
		(layer "In5.Cu")
		(net 23)
	)
	(segment
		(start 88.4 170.7)
		(end 88.39 170.71)
		(width 0.15)
		(layer "In5.Cu")
		(net 23)
	)
	(segment
		(start 83.050212 155.650212)
		(end 84.97 157.57)
		(width 0.15)
		(layer "In5.Cu")
		(net 23)
	)
	(segment
		(start 100.775 116.675)
		(end 101.275 116.675)
		(width 0.15)
		(layer "In5.Cu")
		(net 23)
	)
	(segment
		(start 94.775 118.175)
		(end 95.275 117.675)
		(width 0.15)
		(layer "F.Cu")
		(net 24)
	)
	(via
		(at 101.685 164.345)
		(size 0.5)
		(drill 0.2)
		(layers "F.Cu" "B.Cu")
		(net 24)
	)
	(via blind
		(at 95.275 117.675)
		(size 0.5)
		(drill 0.2)
		(layers "F.Cu" "In2.Cu")
		(net 24)
	)
	(segment
		(start 101.69 177.345)
		(end 101.69 164.35)
		(width 0.15)
		(layer "B.Cu")
		(net 24)
	)
	(segment
		(start 87.68498 161.693538)
		(end 87.68498 122.216463)
		(width 0.15)
		(layer "In2.Cu")
		(net 24)
	)
	(segment
		(start 101.685 164.345)
		(end 101.685 164.945)
		(width 0.15)
		(layer "In2.Cu")
		(net 24)
	)
	(segment
		(start 92.236442 166.245)
		(end 87.68498 161.693538)
		(width 0.15)
		(layer "In2.Cu")
		(net 24)
	)
	(segment
		(start 100.385 166.245)
		(end 92.236442 166.245)
		(width 0.15)
		(layer "In2.Cu")
		(net 24)
	)
	(segment
		(start 101.685 164.945)
		(end 100.385 166.245)
		(width 0.15)
		(layer "In2.Cu")
		(net 24)
	)
	(segment
		(start 94.67503 118.27497)
		(end 95.275 117.675)
		(width 0.15)
		(layer "In2.Cu")
		(net 24)
	)
	(segment
		(start 90.726482 119.17496)
		(end 93.43504 119.17496)
		(width 0.15)
		(layer "In2.Cu")
		(net 24)
	)
	(segment
		(start 93.43504 119.17496)
		(end 94.33503 118.27497)
		(width 0.15)
		(layer "In2.Cu")
		(net 24)
	)
	(segment
		(start 87.68498 122.216463)
		(end 90.726482 119.17496)
		(width 0.15)
		(layer "In2.Cu")
		(net 24)
	)
	(segment
		(start 94.33503 118.27497)
		(end 94.67503 118.27497)
		(width 0.15)
		(layer "In2.Cu")
		(net 24)
	)
	(segment
		(start 99.199968 117.599968)
		(end 99.275 117.599968)
		(width 0.15)
		(layer "F.Cu")
		(net 25)
	)
	(segment
		(start 98.775 117.175)
		(end 99.199968 117.599968)
		(width 0.15)
		(layer "F.Cu")
		(net 25)
	)
	(via
		(at 89.35 168.5)
		(size 0.5)
		(drill 0.2)
		(layers "F.Cu" "B.Cu")
		(net 25)
	)
	(via blind
		(at 99.275 117.599968)
		(size 0.5)
		(drill 0.2)
		(layers "F.Cu" "In5.Cu")
		(net 25)
	)
	(segment
		(start 89.715 172.395)
		(end 89.715 177.32)
		(width 0.15)
		(layer "B.Cu")
		(net 25)
	)
	(segment
		(start 89.35 172.03)
		(end 89.715 172.395)
		(width 0.15)
		(layer "B.Cu")
		(net 25)
	)
	(segment
		(start 89.35 168.5)
		(end 89.35 172.03)
		(width 0.15)
		(layer "B.Cu")
		(net 25)
	)
	(segment
		(start 89.37 168.49)
		(end 89.37 161.262864)
		(width 0.15)
		(layer "In5.Cu")
		(net 25)
	)
	(segment
		(start 89.825 117.725)
		(end 98.796415 117.725)
		(width 0.15)
		(layer "In5.Cu")
		(net 25)
	)
	(segment
		(start 89.38 168.5)
		(end 89.37 168.49)
		(width 0.15)
		(layer "In5.Cu")
		(net 25)
	)
	(segment
		(start 98.921447 117.599968)
		(end 99.275 117.599968)
		(width 0.15)
		(layer "In5.Cu")
		(net 25)
	)
	(segment
		(start 89.37 161.262864)
		(end 83.650234 155.543098)
		(width 0.15)
		(layer "In5.Cu")
		(net 25)
	)
	(segment
		(start 83.650234 123.899766)
		(end 89.825 117.725)
		(width 0.15)
		(layer "In5.Cu")
		(net 25)
	)
	(segment
		(start 83.650234 155.543098)
		(end 83.650234 123.899766)
		(width 0.15)
		(layer "In5.Cu")
		(net 25)
	)
	(segment
		(start 98.796415 117.725)
		(end 98.921447 117.599968)
		(width 0.15)
		(layer "In5.Cu")
		(net 25)
	)
	(segment
		(start 89.35 168.5)
		(end 89.38 168.5)
		(width 0.15)
		(layer "In5.Cu")
		(net 25)
	)
	(segment
		(start 100.775 117.175)
		(end 101.275 117.675)
		(width 0.15)
		(layer "F.Cu")
		(net 26)
	)
	(via blind
		(at 101.275 117.675)
		(size 0.5)
		(drill 0.2)
		(layers "F.Cu" "In5.Cu")
		(net 26)
	)
	(via
		(at 88.87 167.95)
		(size 0.5)
		(drill 0.2)
		(layers "F.Cu" "B.Cu")
		(net 26)
	)
	(segment
		(start 89.1 172.46)
		(end 89.09 172.47)
		(width 0.15)
		(layer "B.Cu")
		(net 26)
	)
	(segment
		(start 88.86 172.16)
		(end 89.1 172.4)
		(width 0.15)
		(layer "B.Cu")
		(net 26)
	)
	(segment
		(start 88.87 167.95)
		(end 88.86 167.96)
		(width 0.15)
		(layer "B.Cu")
		(net 26)
	)
	(segment
		(start 89.09 172.47)
		(end 89.09 177.245)
		(width 0.15)
		(layer "B.Cu")
		(net 26)
	)
	(segment
		(start 89.1 172.4)
		(end 89.1 172.46)
		(width 0.15)
		(layer "B.Cu")
		(net 26)
	)
	(segment
		(start 88.86 167.96)
		(end 88.86 172.16)
		(width 0.15)
		(layer "B.Cu")
		(net 26)
	)
	(segment
		(start 89.700721 117.425)
		(end 98.525 117.425)
		(width 0.15)
		(layer "In5.Cu")
		(net 26)
	)
	(segment
		(start 98.874999 117.075001)
		(end 100.675001 117.075001)
		(width 0.15)
		(layer "In5.Cu")
		(net 26)
	)
	(segment
		(start 88.87 161.116432)
		(end 83.350223 155.596655)
		(width 0.15)
		(layer "In5.Cu")
		(net 26)
	)
	(segment
		(start 83.350223 123.775498)
		(end 89.700721 117.425)
		(width 0.15)
		(layer "In5.Cu")
		(net 26)
	)
	(segment
		(start 100.675001 117.075001)
		(end 101.275 117.675)
		(width 0.15)
		(layer "In5.Cu")
		(net 26)
	)
	(segment
		(start 88.87 167.95)
		(end 88.87 161.116432)
		(width 0.15)
		(layer "In5.Cu")
		(net 26)
	)
	(segment
		(start 83.350223 155.596655)
		(end 83.350223 123.775498)
		(width 0.15)
		(layer "In5.Cu")
		(net 26)
	)
	(segment
		(start 98.525 117.425)
		(end 98.874999 117.075001)
		(width 0.15)
		(layer "In5.Cu")
		(net 26)
	)
	(segment
		(start 100.775 118.175)
		(end 101.275 118.675)
		(width 0.15)
		(layer "F.Cu")
		(net 27)
	)
	(via
		(at 91.94 171.28)
		(size 0.5)
		(drill 0.2)
		(layers "F.Cu" "B.Cu")
		(net 27)
	)
	(via blind
		(at 101.275 118.675)
		(size 0.5)
		(drill 0.2)
		(layers "F.Cu" "In5.Cu")
		(net 27)
	)
	(segment
		(start 92.09 171.43)
		(end 92.09 177.345)
		(width 0.15)
		(layer "B.Cu")
		(net 27)
	)
	(segment
		(start 91.94 171.28)
		(end 92.09 171.43)
		(width 0.15)
		(layer "B.Cu")
		(net 27)
	)
	(segment
		(start 91.94 171.28)
		(end 91.86 171.2)
		(width 0.15)
		(layer "In5.Cu")
		(net 27)
	)
	(segment
		(start 84.850278 155.170278)
		(end 84.850278 124.499722)
		(width 0.15)
		(layer "In5.Cu")
		(net 27)
	)
	(segment
		(start 91.86 162.18)
		(end 84.850278 155.170278)
		(width 0.15)
		(layer "In5.Cu")
		(net 27)
	)
	(segment
		(start 92.475 119.175)
		(end 100.775 119.175)
		(width 0.15)
		(layer "In5.Cu")
		(net 27)
	)
	(segment
		(start 91.675 119.975)
		(end 92.475 119.175)
		(width 0.15)
		(layer "In5.Cu")
		(net 27)
	)
	(segment
		(start 91.86 171.2)
		(end 91.86 162.18)
		(width 0.15)
		(layer "In5.Cu")
		(net 27)
	)
	(segment
		(start 89.375 119.975)
		(end 91.675 119.975)
		(width 0.15)
		(layer "In5.Cu")
		(net 27)
	)
	(segment
		(start 100.775 119.175)
		(end 101.275 118.675)
		(width 0.15)
		(layer "In5.Cu")
		(net 27)
	)
	(segment
		(start 84.850278 124.499722)
		(end 89.375 119.975)
		(width 0.15)
		(layer "In5.Cu")
		(net 27)
	)
	(segment
		(start 97.775 118.175)
		(end 98.239117 118.639117)
		(width 0.15)
		(layer "F.Cu")
		(net 28)
	)
	(segment
		(start 98.239117 118.639117)
		(end 98.310883 118.639117)
		(width 0.15)
		(layer "F.Cu")
		(net 28)
	)
	(via blind
		(at 98.310883 118.639117)
		(size 0.5)
		(drill 0.2)
		(layers "F.Cu" "In2.Cu")
		(net 28)
	)
	(via
		(at 99.885 164.645)
		(size 0.5)
		(drill 0.2)
		(layers "F.Cu" "B.Cu")
		(net 28)
	)
	(segment
		(start 99.89 177.345)
		(end 99.89 164.65)
		(width 0.15)
		(layer "B.Cu")
		(net 28)
	)
	(segment
		(start 99.885 164.998553)
		(end 99.885 164.645)
		(width 0.15)
		(layer "In2.Cu")
		(net 28)
	)
	(segment
		(start 97.775 119.175)
		(end 94.655 119.175)
		(width 0.15)
		(layer "In2.Cu")
		(net 28)
	)
	(segment
		(start 91.175009 120.074991)
		(end 88.585011 122.664989)
		(width 0.15)
		(layer "In2.Cu")
		(net 28)
	)
	(segment
		(start 94.655 119.175)
		(end 93.755009 120.074991)
		(width 0.15)
		(layer "In2.Cu")
		(net 28)
	)
	(segment
		(start 92.660722 165.345)
		(end 99.538553 165.345)
		(width 0.15)
		(layer "In2.Cu")
		(net 28)
	)
	(segment
		(start 99.538553 165.345)
		(end 99.885 164.998553)
		(width 0.15)
		(layer "In2.Cu")
		(net 28)
	)
	(segment
		(start 98.310883 118.639117)
		(end 97.775 119.175)
		(width 0.15)
		(layer "In2.Cu")
		(net 28)
	)
	(segment
		(start 88.585011 122.664989)
		(end 88.585011 161.269289)
		(width 0.15)
		(layer "In2.Cu")
		(net 28)
	)
	(segment
		(start 88.585011 161.269289)
		(end 92.660722 165.345)
		(width 0.15)
		(layer "In2.Cu")
		(net 28)
	)
	(segment
		(start 93.755009 120.074991)
		(end 91.175009 120.074991)
		(width 0.15)
		(layer "In2.Cu")
		(net 28)
	)
	(segment
		(start 96.775 118.175)
		(end 97.275 118.675)
		(width 0.15)
		(layer "F.Cu")
		(net 29)
	)
	(via
		(at 100.485 164.345)
		(size 0.5)
		(drill 0.2)
		(layers "F.Cu" "B.Cu")
		(net 29)
	)
	(via blind
		(at 97.275 118.675)
		(size 0.5)
		(drill 0.2)
		(layers "F.Cu" "In2.Cu")
		(net 29)
	)
	(segment
		(start 100.49 177.345)
		(end 100.49 164.35)
		(width 0.15)
		(layer "B.Cu")
		(net 29)
	)
	(segment
		(start 96.475 118.87499)
		(end 94.53501 118.87499)
		(width 0.15)
		(layer "In2.Cu")
		(net 29)
	)
	(segment
		(start 100.485 164.345)
		(end 100.485 165.045)
		(width 0.15)
		(layer "In2.Cu")
		(net 29)
	)
	(segment
		(start 97.275 118.675)
		(end 96.67499 118.675)
		(width 0.15)
		(layer "In2.Cu")
		(net 29)
	)
	(segment
		(start 92.536444 165.645)
		(end 99.885 165.645)
		(width 0.15)
		(layer "In2.Cu")
		(net 29)
	)
	(segment
		(start 96.67499 118.675)
		(end 96.475 118.87499)
		(width 0.15)
		(layer "In2.Cu")
		(net 29)
	)
	(segment
		(start 93.63502 119.77498)
		(end 90.97502 119.77498)
		(width 0.15)
		(layer "In2.Cu")
		(net 29)
	)
	(segment
		(start 90.97502 119.77498)
		(end 88.285 122.465)
		(width 0.15)
		(layer "In2.Cu")
		(net 29)
	)
	(segment
		(start 100.485 165.045)
		(end 99.885 165.645)
		(width 0.15)
		(layer "In2.Cu")
		(net 29)
	)
	(segment
		(start 94.53501 118.87499)
		(end 93.63502 119.77498)
		(width 0.15)
		(layer "In2.Cu")
		(net 29)
	)
	(segment
		(start 88.285 161.393556)
		(end 92.536444 165.645)
		(width 0.15)
		(layer "In2.Cu")
		(net 29)
	)
	(segment
		(start 88.285 122.465)
		(end 88.285 161.393556)
		(width 0.15)
		(layer "In2.Cu")
		(net 29)
	)
	(segment
		(start 99.775 118.175)
		(end 100.275 118.675)
		(width 0.15)
		(layer "F.Cu")
		(net 30)
	)
	(via blind
		(at 100.275 118.675)
		(size 0.5)
		(drill 0.2)
		(layers "F.Cu" "In5.Cu")
		(net 30)
	)
	(via
		(at 91.4 170.55)
		(size 0.5)
		(drill 0.2)
		(layers "F.Cu" "B.Cu")
		(net 30)
	)
	(segment
		(start 91.49 170.64)
		(end 91.49 177.37)
		(width 0.15)
		(layer "B.Cu")
		(net 30)
	)
	(segment
		(start 91.4 170.55)
		(end 91.49 170.64)
		(width 0.15)
		(layer "B.Cu")
		(net 30)
	)
	(segment
		(start 92.512861 118.675)
		(end 91.512872 119.674989)
		(width 0.15)
		(layer "In5.Cu")
		(net 30)
	)
	(segment
		(start 91.4 170.55)
		(end 91.4 162.144278)
		(width 0.15)
		(layer "In5.Cu")
		(net 30)
	)
	(segment
		(start 100.275 118.675)
		(end 92.512861 118.675)
		(width 0.15)
		(layer "In5.Cu")
		(net 30)
	)
	(segment
		(start 89.250732 119.674989)
		(end 84.550267 124.375454)
		(width 0.15)
		(layer "In5.Cu")
		(net 30)
	)
	(segment
		(start 86.30499 157.049268)
		(end 91.4 162.144278)
		(width 0.15)
		(layer "In5.Cu")
		(net 30)
	)
	(segment
		(start 84.550267 155.300267)
		(end 86.3 157.05)
		(width 0.15)
		(layer "In5.Cu")
		(net 30)
	)
	(segment
		(start 91.512872 119.674989)
		(end 89.250732 119.674989)
		(width 0.15)
		(layer "In5.Cu")
		(net 30)
	)
	(segment
		(start 84.550267 124.375454)
		(end 84.550267 155.300267)
		(width 0.15)
		(layer "In5.Cu")
		(net 30)
	)
	(segment
		(start 98.775 115.175)
		(end 98.275 115.675)
		(width 0.15)
		(layer "F.Cu")
		(net 31)
	)
	(via
		(at 84.93 169.1)
		(size 0.5)
		(drill 0.2)
		(layers "F.Cu" "B.Cu")
		(net 31)
	)
	(via blind
		(at 98.275 115.675)
		(size 0.5)
		(drill 0.2)
		(layers "F.Cu" "In5.Cu")
		(net 31)
	)
	(segment
		(start 86.685 170.855)
		(end 84.93 169.1)
		(width 0.15)
		(layer "B.Cu")
		(net 31)
	)
	(segment
		(start 86.685 177.155)
		(end 86.685 170.855)
		(width 0.15)
		(layer "B.Cu")
		(net 31)
	)
	(segment
		(start 82.150179 157.625179)
		(end 82.150179 123.278426)
		(width 0.15)
		(layer "In5.Cu")
		(net 31)
	)
	(segment
		(start 97.775 116.175)
		(end 98.275 115.675)
		(width 0.15)
		(layer "In5.Cu")
		(net 31)
	)
	(segment
		(start 82.150179 123.278426)
		(end 89.853606 115.575)
		(width 0.15)
		(layer "In5.Cu")
		(net 31)
	)
	(segment
		(start 89.853606 115.575)
		(end 94.275 115.575)
		(width 0.15)
		(layer "In5.Cu")
		(net 31)
	)
	(segment
		(start 84.83 169)
		(end 84.83 159.505)
		(width 0.15)
		(layer "In5.Cu")
		(net 31)
	)
	(segment
		(start 84.83 159.505)
		(end 84.54 159.215)
		(width 0.15)
		(layer "In5.Cu")
		(net 31)
	)
	(segment
		(start 94.275 115.575)
		(end 94.875 116.175)
		(width 0.15)
		(layer "In5.Cu")
		(net 31)
	)
	(segment
		(start 94.875 116.175)
		(end 97.775 116.175)
		(width 0.15)
		(layer "In5.Cu")
		(net 31)
	)
	(segment
		(start 84.54 159.215)
		(end 83.74 159.215)
		(width 0.15)
		(layer "In5.Cu")
		(net 31)
	)
	(segment
		(start 83.74 159.215)
		(end 82.150179 157.625179)
		(width 0.15)
		(layer "In5.Cu")
		(net 31)
	)
	(segment
		(start 84.93 169.1)
		(end 84.83 169)
		(width 0.15)
		(layer "In5.Cu")
		(net 31)
	)
	(segment
		(start 98.775 116.175)
		(end 99.275 115.675)
		(width 0.15)
		(layer "F.Cu")
		(net 32)
	)
	(via blind
		(at 99.275 115.675)
		(size 0.5)
		(drill 0.2)
		(layers "F.Cu" "In5.Cu")
		(net 32)
	)
	(via
		(at 85.38 168.61)
		(size 0.5)
		(drill 0.2)
		(layers "F.Cu" "B.Cu")
		(net 32)
	)
	(segment
		(start 87.29 177.155)
		(end 87.29 170.52)
		(width 0.15)
		(layer "B.Cu")
		(net 32)
	)
	(segment
		(start 87.29 170.52)
		(end 85.38 168.61)
		(width 0.15)
		(layer "B.Cu")
		(net 32)
	)
	(segment
		(start 82.45019 157.47519)
		(end 82.45019 123.402694)
		(width 0.15)
		(layer "In5.Cu")
		(net 32)
	)
	(segment
		(start 85.11 159.335)
		(end 84.715 158.94)
		(width 0.15)
		(layer "In5.Cu")
		(net 32)
	)
	(segment
		(start 94.999278 116.475)
		(end 98.026444 116.475)
		(width 0.15)
		(layer "In5.Cu")
		(net 32)
	)
	(segment
		(start 94.150732 115.87501)
		(end 94.750731 116.475009)
		(width 0.15)
		(layer "In5.Cu")
		(net 32)
	)
	(segment
		(start 98.799999 116.150001)
		(end 98.351443 116.150001)
		(width 0.15)
		(layer "In5.Cu")
		(net 32)
	)
	(segment
		(start 98.026444 116.475)
		(end 98.351443 116.150001)
		(width 0.15)
		(layer "In5.Cu")
		(net 32)
	)
	(segment
		(start 99.275 115.675)
		(end 98.799999 116.150001)
		(width 0.15)
		(layer "In5.Cu")
		(net 32)
	)
	(segment
		(start 85.11 168.34)
		(end 85.11 159.335)
		(width 0.15)
		(layer "In5.Cu")
		(net 32)
	)
	(segment
		(start 82.45019 123.402694)
		(end 89.977874 115.87501)
		(width 0.15)
		(layer "In5.Cu")
		(net 32)
	)
	(segment
		(start 89.977874 115.87501)
		(end 94.150732 115.87501)
		(width 0.15)
		(layer "In5.Cu")
		(net 32)
	)
	(segment
		(start 83.915 158.94)
		(end 82.45019 157.47519)
		(width 0.15)
		(layer "In5.Cu")
		(net 32)
	)
	(segment
		(start 94.750731 116.475009)
		(end 94.999269 116.475009)
		(width 0.15)
		(layer "In5.Cu")
		(net 32)
	)
	(segment
		(start 94.999269 116.475009)
		(end 94.999278 116.475)
		(width 0.15)
		(layer "In5.Cu")
		(net 32)
	)
	(segment
		(start 84.715 158.94)
		(end 83.915 158.94)
		(width 0.15)
		(layer "In5.Cu")
		(net 32)
	)
	(segment
		(start 85.38 168.61)
		(end 85.11 168.34)
		(width 0.15)
		(layer "In5.Cu")
		(net 32)
	)
	(segment
		(start 105.775 110.175)
		(end 106.275 110.675)
		(width 0.15)
		(layer "F.Cu")
		(net 33)
	)
	(segment
		(start 77.49 177.445)
		(end 77.490001 173.289999)
		(width 0.15)
		(layer "F.Cu")
		(net 33)
	)
	(via blind
		(at 106.275 110.675)
		(size 0.5)
		(drill 0.2)
		(layers "F.Cu" "In5.Cu")
		(net 33)
	)
	(via blind
		(at 77.490001 173.289999)
		(size 0.5)
		(drill 0.2)
		(layers "F.Cu" "In5.Cu")
		(net 33)
	)
	(segment
		(start 90.410806 110.775009)
		(end 79.150069 122.035746)
		(width 0.15)
		(layer "In5.Cu")
		(net 33)
	)
	(segment
		(start 105.375 111.575)
		(end 97.417 111.575)
		(width 0.15)
		(layer "In5.Cu")
		(net 33)
	)
	(segment
		(start 105.375 111.575)
		(end 106.275 110.675)
		(width 0.15)
		(layer "In5.Cu")
		(net 33)
	)
	(segment
		(start 96.617009 110.775009)
		(end 90.410806 110.775009)
		(width 0.15)
		(layer "In5.Cu")
		(net 33)
	)
	(segment
		(start 81.315 161.296396)
		(end 81.315 169.465)
		(width 0.15)
		(layer "In5.Cu")
		(net 33)
	)
	(segment
		(start 79.150069 122.035746)
		(end 79.150069 159.131465)
		(width 0.15)
		(layer "In5.Cu")
		(net 33)
	)
	(segment
		(start 81.315 169.465)
		(end 77.490001 173.289999)
		(width 0.15)
		(layer "In5.Cu")
		(net 33)
	)
	(segment
		(start 97.417 111.575)
		(end 96.617009 110.775009)
		(width 0.15)
		(layer "In5.Cu")
		(net 33)
	)
	(segment
		(start 79.150069 159.131465)
		(end 81.315 161.296396)
		(width 0.15)
		(layer "In5.Cu")
		(net 33)
	)
	(segment
		(start 108.775 124.175)
		(end 109.275 124.675)
		(width 0.15)
		(layer "F.Cu")
		(net 34)
	)
	(via blind
		(at 109.275 124.675)
		(size 0.5)
		(drill 0.2)
		(layers "F.Cu" "In5.Cu")
		(net 34)
	)
	(via
		(at 112.274 168.275)
		(size 0.5)
		(drill 0.2)
		(layers "F.Cu" "B.Cu")
		(net 34)
	)
	(segment
		(start 112.29 177.345)
		(end 112.29 168.291)
		(width 0.15)
		(layer "B.Cu")
		(net 34)
	)
	(segment
		(start 112.29 168.291)
		(end 112.274 168.275)
		(width 0.15)
		(layer "B.Cu")
		(net 34)
	)
	(segment
		(start 112.274 164.975)
		(end 112.274 168.275)
		(width 0.15)
		(layer "In5.Cu")
		(net 34)
	)
	(segment
		(start 111.675001 123.076001)
		(end 110.774 122.175)
		(width 0.15)
		(layer "In5.Cu")
		(net 34)
	)
	(segment
		(start 112.274 164.975)
		(end 111.119 163.82)
		(width 0.15)
		(layer "In5.Cu")
		(net 34)
	)
	(segment
		(start 111.119 163.82)
		(end 111.119 128.823432)
		(width 0.15)
		(layer "In5.Cu")
		(net 34)
	)
	(segment
		(start 111.67402 128.268412)
		(end 111.67402 123.904982)
		(width 0.15)
		(layer "In5.Cu")
		(net 34)
	)
	(segment
		(start 111.675001 123.904001)
		(end 111.675001 123.076001)
		(width 0.15)
		(layer "In5.Cu")
		(net 34)
	)
	(segment
		(start 109.774 122.472998)
		(end 109.774 124.176)
		(width 0.15)
		(layer "In5.Cu")
		(net 34)
	)
	(segment
		(start 111.67402 123.904982)
		(end 111.675001 123.904001)
		(width 0.15)
		(layer "In5.Cu")
		(net 34)
	)
	(segment
		(start 110.774 122.175)
		(end 110.071998 122.175)
		(width 0.15)
		(layer "In5.Cu")
		(net 34)
	)
	(segment
		(start 109.774 124.176)
		(end 109.275 124.675)
		(width 0.15)
		(layer "In5.Cu")
		(net 34)
	)
	(segment
		(start 111.119 128.823432)
		(end 111.67402 128.268412)
		(width 0.15)
		(layer "In5.Cu")
		(net 34)
	)
	(segment
		(start 110.071998 122.175)
		(end 109.774 122.472998)
		(width 0.15)
		(layer "In5.Cu")
		(net 34)
	)
	(segment
		(start 94.775 114.175)
		(end 95.275 114.675)
		(width 0.15)
		(layer "F.Cu")
		(net 35)
	)
	(segment
		(start 80.615 170.465)
		(end 80.615 168.965)
		(width 0.15)
		(layer "F.Cu")
		(net 35)
	)
	(segment
		(start 78.69 177.445)
		(end 78.69 172.39)
		(width 0.15)
		(layer "F.Cu")
		(net 35)
	)
	(segment
		(start 78.69 172.39)
		(end 80.615 170.465)
		(width 0.15)
		(layer "F.Cu")
		(net 35)
	)
	(via blind
		(at 95.275 114.675)
		(size 0.5)
		(drill 0.2)
		(layers "F.Cu" "In2.Cu")
		(net 35)
	)
	(via blind
		(at 80.615 168.965)
		(size 0.5)
		(drill 0.2)
		(layers "F.Cu" "In2.Cu")
		(net 35)
	)
	(segment
		(start 80.775 168.155)
		(end 80.615 168.315)
		(width 0.15)
		(layer "In2.Cu")
		(net 35)
	)
	(segment
		(start 80.775 120.926444)
		(end 87.850722 113.850722)
		(width 0.15)
		(layer "In2.Cu")
		(net 35)
	)
	(segment
		(start 80.615 168.315)
		(end 80.615 168.965)
		(width 0.15)
		(layer "In2.Cu")
		(net 35)
	)
	(segment
		(start 88.77499 112.92501)
		(end 88.225 113.475)
		(width 0.15)
		(layer "In2.Cu")
		(net 35)
	)
	(segment
		(start 93.075 113.175)
		(end 94.875 113.175)
		(width 0.15)
		(layer "In2.Cu")
		(net 35)
	)
	(segment
		(start 93.075 113.175)
		(end 92.82501 112.92501)
		(width 0.15)
		(layer "In2.Cu")
		(net 35)
	)
	(segment
		(start 80.775 120.926444)
		(end 80.775 168.155)
		(width 0.15)
		(layer "In2.Cu")
		(net 35)
	)
	(segment
		(start 92.82501 112.92501)
		(end 88.77499 112.92501)
		(width 0.15)
		(layer "In2.Cu")
		(net 35)
	)
	(segment
		(start 94.875 113.175)
		(end 95.275 113.575)
		(width 0.15)
		(layer "In2.Cu")
		(net 35)
	)
	(segment
		(start 95.275 113.575)
		(end 95.275 114.675)
		(width 0.15)
		(layer "In2.Cu")
		(net 35)
	)
	(segment
		(start 87.850722 113.850722)
		(end 88.225 113.475)
		(width 0.15)
		(layer "In2.Cu")
		(net 35)
	)
	(segment
		(start 108.775 122.175)
		(end 109.275 122.675)
		(width 0.15)
		(layer "F.Cu")
		(net 36)
	)
	(via blind
		(at 109.275 122.675)
		(size 0.5)
		(drill 0.2)
		(layers "F.Cu" "In5.Cu")
		(net 36)
	)
	(via
		(at 112.874 168.275)
		(size 0.5)
		(drill 0.2)
		(layers "F.Cu" "B.Cu")
		(net 36)
	)
	(segment
		(start 112.89 168.291)
		(end 112.874 168.275)
		(width 0.15)
		(layer "B.Cu")
		(net 36)
	)
	(segment
		(start 112.89 177.345)
		(end 112.89 168.291)
		(width 0.15)
		(layer "B.Cu")
		(net 36)
	)
	(segment
		(start 111.97403 128.32197)
		(end 111.97403 122.87503)
		(width 0.15)
		(layer "In5.Cu")
		(net 36)
	)
	(segment
		(start 109.721456 121.874991)
		(end 109.275 122.321447)
		(width 0.15)
		(layer "In5.Cu")
		(net 36)
	)
	(segment
		(start 109.97399 121.87499)
		(end 110.97399 121.87499)
		(width 0.15)
		(layer "In5.Cu")
		(net 36)
	)
	(segment
		(start 109.97399 121.87499)
		(end 109.947729 121.874991)
		(width 0.15)
		(layer "In5.Cu")
		(net 36)
	)
	(segment
		(start 111.419 128.877)
		(end 111.97403 128.32197)
		(width 0.15)
		(layer "In5.Cu")
		(net 36)
	)
	(segment
		(start 109.275 122.321447)
		(end 109.275 122.675)
		(width 0.15)
		(layer "In5.Cu")
		(net 36)
	)
	(segment
		(start 112.874 168.275)
		(end 112.874 165.075)
		(width 0.15)
		(layer "In5.Cu")
		(net 36)
	)
	(segment
		(start 111.419 163.62)
		(end 111.419 128.877)
		(width 0.15)
		(layer "In5.Cu")
		(net 36)
	)
	(segment
		(start 112.874 165.075)
		(end 111.419 163.62)
		(width 0.15)
		(layer "In5.Cu")
		(net 36)
	)
	(segment
		(start 111.97403 122.87503)
		(end 110.97399 121.87499)
		(width 0.15)
		(layer "In5.Cu")
		(net 36)
	)
	(segment
		(start 109.947729 121.874991)
		(end 109.721456 121.874991)
		(width 0.15)
		(layer "In5.Cu")
		(net 36)
	)
	(segment
		(start 105.775 126.175)
		(end 106.275 126.675)
		(width 0.15)
		(layer "F.Cu")
		(net 37)
	)
	(via
		(at 104.223991 168.275)
		(size 0.5)
		(drill 0.2)
		(layers "F.Cu" "B.Cu")
		(net 37)
	)
	(via blind
		(at 106.275 126.675)
		(size 0.5)
		(drill 0.2)
		(layers "F.Cu" "In5.Cu")
		(net 37)
	)
	(segment
		(start 104.223991 168.624991)
		(end 104.223991 168.275)
		(width 0.15)
		(layer "B.Cu")
		(net 37)
	)
	(segment
		(start 106.89 177.345)
		(end 106.89 171.291)
		(width 0.15)
		(layer "B.Cu")
		(net 37)
	)
	(segment
		(start 106.89 171.291)
		(end 104.223991 168.624991)
		(width 0.15)
		(layer "B.Cu")
		(net 37)
	)
	(segment
		(start 104.223991 166.700731)
		(end 107.473959 163.450763)
		(width 0.15)
		(layer "In5.Cu")
		(net 37)
	)
	(segment
		(start 107.473959 163.450763)
		(end 107.473959 128.873959)
		(width 0.15)
		(layer "In5.Cu")
		(net 37)
	)
	(segment
		(start 106.275 127.675)
		(end 106.275 126.675)
		(width 0.15)
		(layer "In5.Cu")
		(net 37)
	)
	(segment
		(start 104.223991 168.275)
		(end 104.223991 166.700731)
		(width 0.15)
		(layer "In5.Cu")
		(net 37)
	)
	(segment
		(start 107.473959 128.873959)
		(end 106.275 127.675)
		(width 0.15)
		(layer "In5.Cu")
		(net 37)
	)
	(segment
		(start 105.775 125.175)
		(end 106.275 124.675)
		(width 0.15)
		(layer "F.Cu")
		(net 38)
	)
	(via blind
		(at 106.275 124.675)
		(size 0.5)
		(drill 0.2)
		(layers "F.Cu" "In5.Cu")
		(net 38)
	)
	(via
		(at 104.873994 168.275)
		(size 0.5)
		(drill 0.2)
		(layers "F.Cu" "B.Cu")
		(net 38)
	)
	(segment
		(start 107.49 177.445)
		(end 107.49 171.291)
		(width 0.15)
		(layer "B.Cu")
		(net 38)
	)
	(segment
		(start 104.873994 168.674994)
		(end 104.873994 168.275)
		(width 0.15)
		(layer "B.Cu")
		(net 38)
	)
	(segment
		(start 107.49 171.291)
		(end 104.873994 168.674994)
		(width 0.15)
		(layer "B.Cu")
		(net 38)
	)
	(segment
		(start 106.774 127.660917)
		(end 106.774 126.475)
		(width 0.15)
		(layer "In5.Cu")
		(net 38)
	)
	(segment
		(start 105.775 125.175)
		(end 106.275 124.675)
		(width 0.15)
		(layer "In5.Cu")
		(net 38)
	)
	(segment
		(start 104.874 166.475)
		(end 107.77397 163.57503)
		(width 0.15)
		(layer "In5.Cu")
		(net 38)
	)
	(segment
		(start 104.874 167.921441)
		(end 104.874 166.475)
		(width 0.15)
		(layer "In5.Cu")
		(net 38)
	)
	(segment
		(start 104.873994 167.921447)
		(end 104.874 167.921441)
		(width 0.15)
		(layer "In5.Cu")
		(net 38)
	)
	(segment
		(start 107.77397 128.660887)
		(end 106.774 127.660917)
		(width 0.15)
		(layer "In5.Cu")
		(net 38)
	)
	(segment
		(start 104.873994 168.275)
		(end 104.873994 167.921447)
		(width 0.15)
		(layer "In5.Cu")
		(net 38)
	)
	(segment
		(start 106.125 126.175)
		(end 106.474 126.175)
		(width 0.15)
		(layer "In5.Cu")
		(net 38)
	)
	(segment
		(start 106.125 126.175)
		(end 105.775 125.825)
		(width 0.15)
		(layer "In5.Cu")
		(net 38)
	)
	(segment
		(start 106.774 126.475)
		(end 106.474 126.175)
		(width 0.15)
		(layer "In5.Cu")
		(net 38)
	)
	(segment
		(start 107.77397 163.57503)
		(end 107.77397 128.660887)
		(width 0.15)
		(layer "In5.Cu")
		(net 38)
	)
	(segment
		(start 105.775 125.825)
		(end 105.775 125.175)
		(width 0.15)
		(layer "In5.Cu")
		(net 38)
	)
	(segment
		(start 79.29 177.445)
		(end 79.29 172.34)
		(width 0.15)
		(layer "F.Cu")
		(net 39)
	)
	(segment
		(start 93.775 114.155)
		(end 93.275 113.655)
		(width 0.15)
		(layer "F.Cu")
		(net 39)
	)
	(segment
		(start 81.115 170.515)
		(end 81.115 168.465)
		(width 0.15)
		(layer "F.Cu")
		(net 39)
	)
	(segment
		(start 79.29 172.34)
		(end 81.115 170.515)
		(width 0.15)
		(layer "F.Cu")
		(net 39)
	)
	(via blind
		(at 93.275 113.655)
		(size 0.5)
		(drill 0.2)
		(layers "F.Cu" "In2.Cu")
		(net 39)
	)
	(via blind
		(at 81.115 168.465)
		(size 0.5)
		(drill 0.2)
		(layers "F.Cu" "In2.Cu")
		(net 39)
	)
	(segment
		(start 92.441467 113.17502)
		(end 88.950702 113.17502)
		(width 0.15)
		(layer "In2.Cu")
		(net 39)
	)
	(segment
		(start 93.275 113.655)
		(end 92.921447 113.655)
		(width 0.15)
		(layer "In2.Cu")
		(net 39)
	)
	(segment
		(start 92.921447 113.655)
		(end 92.441467 113.17502)
		(width 0.15)
		(layer "In2.Cu")
		(net 39)
	)
	(segment
		(start 81.075 168.425)
		(end 81.115 168.465)
		(width 0.15)
		(layer "In2.Cu")
		(net 39)
	)
	(segment
		(start 88.950702 113.17502)
		(end 81.075 121.050722)
		(width 0.15)
		(layer "In2.Cu")
		(net 39)
	)
	(segment
		(start 81.075 121.050722)
		(end 81.075 168.425)
		(width 0.15)
		(layer "In2.Cu")
		(net 39)
	)
	(segment
		(start 76.89 177.445)
		(end 76.89 172.84)
		(width 0.15)
		(layer "F.Cu")
		(net 40)
	)
	(segment
		(start 106.775 110.175)
		(end 106.275 109.675)
		(width 0.15)
		(layer "F.Cu")
		(net 40)
	)
	(via blind
		(at 106.275 109.675)
		(size 0.5)
		(drill 0.2)
		(layers "F.Cu" "In5.Cu")
		(net 40)
	)
	(via blind
		(at 76.89 172.84)
		(size 0.5)
		(drill 0.2)
		(layers "F.Cu" "In5.Cu")
		(net 40)
	)
	(segment
		(start 106.275 109.675)
		(end 104.675022 111.274978)
		(width 0.15)
		(layer "In5.Cu")
		(net 40)
	)
	(segment
		(start 81.015 168.715)
		(end 76.89 172.84)
		(width 0.15)
		(layer "In5.Cu")
		(net 40)
	)
	(segment
		(start 78.850058 121.911478)
		(end 78.850058 159.255733)
		(width 0.15)
		(layer "In5.Cu")
		(net 40)
	)
	(segment
		(start 104.675022 111.274978)
		(end 97.516978 111.274978)
		(width 0.15)
		(layer "In5.Cu")
		(net 40)
	)
	(segment
		(start 78.850058 159.255733)
		(end 81.015 161.420675)
		(width 0.15)
		(layer "In5.Cu")
		(net 40)
	)
	(segment
		(start 90.286538 110.474998)
		(end 78.850058 121.911478)
		(width 0.15)
		(layer "In5.Cu")
		(net 40)
	)
	(segment
		(start 81.015 161.420675)
		(end 81.015 168.715)
		(width 0.15)
		(layer "In5.Cu")
		(net 40)
	)
	(segment
		(start 96.716998 110.474998)
		(end 90.286538 110.474998)
		(width 0.15)
		(layer "In5.Cu")
		(net 40)
	)
	(segment
		(start 97.516978 111.274978)
		(end 96.716998 110.474998)
		(width 0.15)
		(layer "In5.Cu")
		(net 40)
	)
	(segment
		(start 108.774 125.176)
		(end 108.274 125.676)
		(width 0.15)
		(layer "F.Cu")
		(net 41)
	)
	(via blind
		(at 108.274 125.676)
		(size 0.5)
		(drill 0.2)
		(layers "F.Cu" "In5.Cu")
		(net 41)
	)
	(via
		(at 106.174 168.275)
		(size 0.5)
		(drill 0.2)
		(layers "F.Cu" "B.Cu")
		(net 41)
	)
	(segment
		(start 108.69 171.391)
		(end 106.174 168.875)
		(width 0.15)
		(layer "B.Cu")
		(net 41)
	)
	(segment
		(start 108.69 177.445)
		(end 108.69 171.391)
		(width 0.15)
		(layer "B.Cu")
		(net 41)
	)
	(segment
		(start 106.174 168.875)
		(end 106.174 168.275)
		(width 0.15)
		(layer "B.Cu")
		(net 41)
	)
	(segment
		(start 106.174 168.275)
		(end 106.174 166.075)
		(width 0.15)
		(layer "In5.Cu")
		(net 41)
	)
	(segment
		(start 107.774 127.799278)
		(end 107.774 126.175)
		(width 0.15)
		(layer "In5.Cu")
		(net 41)
	)
	(segment
		(start 108.37399 163.87501)
		(end 108.37399 128.399268)
		(width 0.15)
		(layer "In5.Cu")
		(net 41)
	)
	(segment
		(start 107.774 126.175)
		(end 107.775 126.175)
		(width 0.15)
		(layer "In5.Cu")
		(net 41)
	)
	(segment
		(start 106.174 166.075)
		(end 108.37399 163.87501)
		(width 0.15)
		(layer "In5.Cu")
		(net 41)
	)
	(segment
		(start 107.775 126.175)
		(end 108.274 125.676)
		(width 0.15)
		(layer "In5.Cu")
		(net 41)
	)
	(segment
		(start 108.37399 128.399268)
		(end 107.774 127.799278)
		(width 0.15)
		(layer "In5.Cu")
		(net 41)
	)
	(segment
		(start 106.775 125.175)
		(end 107.275 125.675)
		(width 0.15)
		(layer "F.Cu")
		(net 42)
	)
	(via
		(at 105.523997 168.275)
		(size 0.5)
		(drill 0.2)
		(layers "F.Cu" "B.Cu")
		(net 42)
	)
	(via blind
		(at 107.275 125.675)
		(size 0.5)
		(drill 0.2)
		(layers "F.Cu" "In5.Cu")
		(net 42)
	)
	(segment
		(start 108.09 177.445)
		(end 108.09 171.291)
		(width 0.15)
		(layer "B.Cu")
		(net 42)
	)
	(segment
		(start 108.09 171.291)
		(end 105.523997 168.724997)
		(width 0.15)
		(layer "B.Cu")
		(net 42)
	)
	(segment
		(start 105.523997 168.724997)
		(end 105.523997 168.275)
		(width 0.15)
		(layer "B.Cu")
		(net 42)
	)
	(segment
		(start 105.523997 168.275)
		(end 105.523997 166.293923)
		(width 0.15)
		(layer "In5.Cu")
		(net 42)
	)
	(segment
		(start 108.07398 163.74394)
		(end 108.07398 128.523536)
		(width 0.15)
		(layer "In5.Cu")
		(net 42)
	)
	(segment
		(start 105.523997 166.293923)
		(end 108.07398 163.74394)
		(width 0.15)
		(layer "In5.Cu")
		(net 42)
	)
	(segment
		(start 108.07398 128.523536)
		(end 107.275 127.724556)
		(width 0.15)
		(layer "In5.Cu")
		(net 42)
	)
	(segment
		(start 107.275 127.724556)
		(end 107.275 125.675)
		(width 0.15)
		(layer "In5.Cu")
		(net 42)
	)
	(segment
		(start 107.775 122.175)
		(end 108.275 122.675)
		(width 0.15)
		(layer "F.Cu")
		(net 43)
	)
	(via
		(at 114.074 168.275)
		(size 0.5)
		(drill 0.2)
		(layers "F.Cu" "B.Cu")
		(net 43)
	)
	(via blind
		(at 108.275 122.675)
		(size 0.5)
		(drill 0.2)
		(layers "F.Cu" "In5.Cu")
		(net 43)
	)
	(segment
		(start 114.09 177.345)
		(end 114.09 168.291)
		(width 0.15)
		(layer "B.Cu")
		(net 43)
	)
	(segment
		(start 112.574 163.675)
		(end 112.574 157.322)
		(width 0.15)
		(layer "In5.Cu")
		(net 43)
	)
	(segment
		(start 108.275 122.249722)
		(end 108.275 122.321447)
		(width 0.15)
		(layer "In5.Cu")
		(net 43)
	)
	(segment
		(start 111.192577 121.245022)
		(end 109.2797 121.245022)
		(width 0.15)
		(layer "In5.Cu")
		(net 43)
	)
	(segment
		(start 114.074 165.175)
		(end 112.574 163.675)
		(width 0.15)
		(layer "In5.Cu")
		(net 43)
	)
	(segment
		(start 109.2797 121.245022)
		(end 108.275 122.249722)
		(width 0.15)
		(layer "In5.Cu")
		(net 43)
	)
	(segment
		(start 112.57405 123.27505)
		(end 112.57405 122.626495)
		(width 0.15)
		(layer "In5.Cu")
		(net 43)
	)
	(segment
		(start 112.57405 122.626495)
		(end 111.192577 121.245022)
		(width 0.15)
		(layer "In5.Cu")
		(net 43)
	)
	(segment
		(start 112.619 128.577)
		(end 112.619 128.477)
		(width 0.15)
		(layer "In5.Cu")
		(net 43)
	)
	(segment
		(start 112.574 157.322)
		(end 113.219 156.677)
		(width 0.15)
		(layer "In5.Cu")
		(net 43)
	)
	(segment
		(start 114.074 168.275)
		(end 114.074 165.175)
		(width 0.15)
		(layer "In5.Cu")
		(net 43)
	)
	(segment
		(start 112.619 128.477)
		(end 112.57405 123.27505)
		(width 0.15)
		(layer "In5.Cu")
		(net 43)
	)
	(segment
		(start 108.275 122.321447)
		(end 108.275 122.675)
		(width 0.15)
		(layer "In5.Cu")
		(net 43)
	)
	(segment
		(start 113.219 156.677)
		(end 113.219 129.177)
		(width 0.15)
		(layer "In5.Cu")
		(net 43)
	)
	(segment
		(start 113.219 129.177)
		(end 112.619 128.577)
		(width 0.15)
		(layer "In5.Cu")
		(net 43)
	)
	(segment
		(start 107.775 123.175)
		(end 108.275 123.675)
		(width 0.15)
		(layer "F.Cu")
		(net 44)
	)
	(via blind
		(at 108.275 123.675)
		(size 0.5)
		(drill 0.2)
		(layers "F.Cu" "In5.Cu")
		(net 44)
	)
	(via
		(at 113.474 168.275)
		(size 0.5)
		(drill 0.2)
		(layers "F.Cu" "B.Cu")
		(net 44)
	)
	(segment
		(start 113.49 177.345)
		(end 113.49 168.291)
		(width 0.15)
		(layer "B.Cu")
		(net 44)
	)
	(segment
		(start 112.27404 122.750763)
		(end 111.06831 121.545033)
		(width 0.15)
		(layer "In5.Cu")
		(net 44)
	)
	(segment
		(start 112.27404 128.73204)
		(end 112.919 129.377)
		(width 0.15)
		(layer "In5.Cu")
		(net 44)
	)
	(segment
		(start 112.919 156.477)
		(end 112.274 157.122)
		(width 0.15)
		(layer "In5.Cu")
		(net 44)
	)
	(segment
		(start 111.06831 121.545033)
		(end 109.403967 121.545033)
		(width 0.15)
		(layer "In5.Cu")
		(net 44)
	)
	(segment
		(start 112.27404 122.750763)
		(end 112.27404 128.73204)
		(width 0.15)
		(layer "In5.Cu")
		(net 44)
	)
	(segment
		(start 113.474 165.175)
		(end 113.474 168.275)
		(width 0.15)
		(layer "In5.Cu")
		(net 44)
	)
	(segment
		(start 108.774 122.175)
		(end 108.774 123.176)
		(width 0.15)
		(layer "In5.Cu")
		(net 44)
	)
	(segment
		(start 108.275 123.675)
		(end 108.774 123.176)
		(width 0.15)
		(layer "In5.Cu")
		(net 44)
	)
	(segment
		(start 109.403967 121.545033)
		(end 108.774 122.175)
		(width 0.15)
		(layer "In5.Cu")
		(net 44)
	)
	(segment
		(start 112.274 163.975)
		(end 113.474 165.175)
		(width 0.15)
		(layer "In5.Cu")
		(net 44)
	)
	(segment
		(start 112.274 157.122)
		(end 112.274 163.975)
		(width 0.15)
		(layer "In5.Cu")
		(net 44)
	)
	(segment
		(start 112.919 129.377)
		(end 112.919 156.477)
		(width 0.15)
		(layer "In5.Cu")
		(net 44)
	)
	(segment
		(start 92.775 118.175)
		(end 93.275 118.675)
		(width 0.15)
		(layer "F.Cu")
		(net 45)
	)
	(via blind
		(at 93.275 118.675)
		(size 0.5)
		(drill 0.2)
		(layers "F.Cu" "In2.Cu")
		(net 45)
	)
	(via
		(at 102.285 164.645)
		(size 0.5)
		(drill 0.2)
		(layers "F.Cu" "B.Cu")
		(net 45)
	)
	(segment
		(start 102.29 177.345)
		(end 102.29 164.65)
		(width 0.15)
		(layer "B.Cu")
		(net 45)
	)
	(segment
		(start 102.285 165.045)
		(end 100.785 166.545)
		(width 0.15)
		(layer "In2.Cu")
		(net 45)
	)
	(segment
		(start 90.97446 118.87446)
		(end 90.97495 118.87495)
		(width 0.15)
		(layer "In2.Cu")
		(net 45)
	)
	(segment
		(start 87.38497 161.817807)
		(end 87.384971 122.092194)
		(width 0.15)
		(layer "In2.Cu")
		(net 45)
	)
	(segment
		(start 87.384971 122.092194)
		(end 90.602705 118.87446)
		(width 0.15)
		(layer "In2.Cu")
		(net 45)
	)
	(segment
		(start 92.112163 166.545)
		(end 87.38497 161.817807)
		(width 0.15)
		(layer "In2.Cu")
		(net 45)
	)
	(segment
		(start 102.285 164.645)
		(end 102.285 165.045)
		(width 0.15)
		(layer "In2.Cu")
		(net 45)
	)
	(segment
		(start 90.602705 118.87446)
		(end 90.97446 118.87446)
		(width 0.15)
		(layer "In2.Cu")
		(net 45)
	)
	(segment
		(start 92.721497 118.87495)
		(end 92.921447 118.675)
		(width 0.15)
		(layer "In2.Cu")
		(net 45)
	)
	(segment
		(start 100.785 166.545)
		(end 92.112163 166.545)
		(width 0.15)
		(layer "In2.Cu")
		(net 45)
	)
	(segment
		(start 92.921447 118.675)
		(end 93.275 118.675)
		(width 0.15)
		(layer "In2.Cu")
		(net 45)
	)
	(segment
		(start 90.97495 118.87495)
		(end 92.721497 118.87495)
		(width 0.15)
		(layer "In2.Cu")
		(net 45)
	)
	(segment
		(start 92.775 117.175)
		(end 93.275 117.675)
		(width 0.15)
		(layer "F.Cu")
		(net 46)
	)
	(via blind
		(at 93.275 117.675)
		(size 0.5)
		(drill 0.2)
		(layers "F.Cu" "In2.Cu")
		(net 46)
	)
	(via
		(at 102.885 164.345)
		(size 0.5)
		(drill 0.2)
		(layers "F.Cu" "B.Cu")
		(net 46)
	)
	(segment
		(start 102.89 177.345)
		(end 102.89 164.35)
		(width 0.15)
		(layer "B.Cu")
		(net 46)
	)
	(segment
		(start 90.478437 118.57445)
		(end 92.37555 118.57445)
		(width 0.15)
		(layer "In2.Cu")
		(net 46)
	)
	(segment
		(start 92.37555 118.57445)
		(end 93.275 117.675)
		(width 0.15)
		(layer "In2.Cu")
		(net 46)
	)
	(segment
		(start 91.897634 166.845)
		(end 87.08496 162.032326)
		(width 0.15)
		(layer "In2.Cu")
		(net 46)
	)
	(segment
		(start 102.885 164.345)
		(end 102.885 165.045)
		(width 0.15)
		(layer "In2.Cu")
		(net 46)
	)
	(segment
		(start 87.084962 121.967925)
		(end 90.478437 118.57445)
		(width 0.15)
		(layer "In2.Cu")
		(net 46)
	)
	(segment
		(start 101.085 166.845)
		(end 91.897634 166.845)
		(width 0.15)
		(layer "In2.Cu")
		(net 46)
	)
	(segment
		(start 102.885 165.045)
		(end 101.085 166.845)
		(width 0.15)
		(layer "In2.Cu")
		(net 46)
	)
	(segment
		(start 87.08496 162.032326)
		(end 87.08496 124.66504)
		(width 0.15)
		(layer "In2.Cu")
		(net 46)
	)
	(segment
		(start 87.08496 124.66504)
		(end 87.084962 121.967925)
		(width 0.15)
		(layer "In2.Cu")
		(net 46)
	)
	(segment
		(start 78.765 167.3)
		(end 78.765 167.960406)
		(width 0.15)
		(layer "F.Cu")
		(net 47)
	)
	(segment
		(start 78.765 167.960406)
		(end 78.712703 168.012703)
		(width 0.15)
		(layer "F.Cu")
		(net 47)
	)
	(via
		(at 78.712703 168.012703)
		(size 0.5)
		(drill 0.2)
		(layers "F.Cu" "B.Cu")
		(net 47)
	)
	(segment
		(start 78.712703 169.562703)
		(end 79.275 170.125)
		(width 0.15)
		(layer "B.Cu")
		(net 47)
	)
	(segment
		(start 79.29 176.135)
		(end 79.29 177.345)
		(width 0.15)
		(layer "B.Cu")
		(net 47)
	)
	(segment
		(start 78.712703 168.012703)
		(end 78.712703 169.562703)
		(width 0.15)
		(layer "B.Cu")
		(net 47)
	)
	(segment
		(start 79.275 170.125)
		(end 79.275 176.12)
		(width 0.15)
		(layer "B.Cu")
		(net 47)
	)
	(segment
		(start 79.275 176.12)
		(end 79.29 176.135)
		(width 0.15)
		(layer "B.Cu")
		(net 47)
	)
	(segment
		(start 77.265 168.065)
		(end 76.915 168.415)
		(width 0.15)
		(layer "F.Cu")
		(net 48)
	)
	(segment
		(start 77.265 167.3)
		(end 77.265 168.065)
		(width 0.15)
		(layer "F.Cu")
		(net 48)
	)
	(segment
		(start 76.915 168.415)
		(end 76.915 168.915002)
		(width 0.15)
		(layer "F.Cu")
		(net 48)
	)
	(via
		(at 76.915 168.915002)
		(size 0.5)
		(drill 0.2)
		(layers "F.Cu" "B.Cu")
		(net 48)
	)
	(segment
		(start 77.49 170.39)
		(end 76.915 169.815)
		(width 0.15)
		(layer "B.Cu")
		(net 48)
	)
	(segment
		(start 76.915 169.815)
		(end 76.915 168.915002)
		(width 0.15)
		(layer "B.Cu")
		(net 48)
	)
	(segment
		(start 77.49 177.345)
		(end 77.49 170.39)
		(width 0.15)
		(layer "B.Cu")
		(net 48)
	)
	(segment
		(start 76.765 168.015004)
		(end 76.365 168.415004)
		(width 0.15)
		(layer "F.Cu")
		(net 49)
	)
	(segment
		(start 76.765 167.3)
		(end 76.765 168.015004)
		(width 0.15)
		(layer "F.Cu")
		(net 49)
	)
	(via
		(at 76.365 168.415004)
		(size 0.5)
		(drill 0.2)
		(layers "F.Cu" "B.Cu")
		(net 49)
	)
	(segment
		(start 76.89 170.44)
		(end 76.365 169.915)
		(width 0.15)
		(layer "B.Cu")
		(net 49)
	)
	(segment
		(start 76.365 169.915)
		(end 76.365 168.415004)
		(width 0.15)
		(layer "B.Cu")
		(net 49)
	)
	(segment
		(start 76.89 177.345)
		(end 76.89 170.44)
		(width 0.15)
		(layer "B.Cu")
		(net 49)
	)
	(segment
		(start 79.265 167.3)
		(end 79.265 168.817841)
		(width 0.15)
		(layer "F.Cu")
		(net 50)
	)
	(via
		(at 79.265 168.817841)
		(size 0.5)
		(drill 0.2)
		(layers "F.Cu" "B.Cu")
		(net 50)
	)
	(segment
		(start 79.265 169.49142)
		(end 79.265 168.817841)
		(width 0.15)
		(layer "B.Cu")
		(net 50)
	)
	(segment
		(start 79.89 177.345)
		(end 79.89 170.11642)
		(width 0.15)
		(layer "B.Cu")
		(net 50)
	)
	(segment
		(start 79.89 170.11642)
		(end 79.265 169.49142)
		(width 0.15)
		(layer "B.Cu")
		(net 50)
	)
	(segment
		(start 78.265 167.3)
		(end 78.265 169.015)
		(width 0.15)
		(layer "F.Cu")
		(net 51)
	)
	(via
		(at 78.265 169.015)
		(size 0.5)
		(drill 0.2)
		(layers "F.Cu" "B.Cu")
		(net 51)
	)
	(segment
		(start 78.69 177.345)
		(end 78.69 170.19)
		(width 0.15)
		(layer "B.Cu")
		(net 51)
	)
	(segment
		(start 78.69 170.19)
		(end 78.265 169.765)
		(width 0.15)
		(layer "B.Cu")
		(net 51)
	)
	(segment
		(start 78.265 169.765)
		(end 78.265 169.015)
		(width 0.15)
		(layer "B.Cu")
		(net 51)
	)
	(segment
		(start 77.765 167.3)
		(end 77.765 168.365)
		(width 0.15)
		(layer "F.Cu")
		(net 52)
	)
	(segment
		(start 77.765 168.365)
		(end 77.565 168.565)
		(width 0.15)
		(layer "F.Cu")
		(net 52)
	)
	(via
		(at 77.565 168.565)
		(size 0.5)
		(drill 0.2)
		(layers "F.Cu" "B.Cu")
		(net 52)
	)
	(segment
		(start 77.565 169.765)
		(end 77.565 168.565)
		(width 0.15)
		(layer "B.Cu")
		(net 52)
	)
	(segment
		(start 78.09 170.29)
		(end 77.565 169.765)
		(width 0.15)
		(layer "B.Cu")
		(net 52)
	)
	(segment
		(start 78.09 177.345)
		(end 78.09 170.29)
		(width 0.15)
		(layer "B.Cu")
		(net 52)
	)
	(segment
		(start 80.2 166.365)
		(end 80.2 168.05)
		(width 0.15)
		(layer "F.Cu")
		(net 53)
	)
	(via
		(at 80.2 168.05)
		(size 0.5)
		(drill 0.2)
		(layers "F.Cu" "B.Cu")
		(net 53)
	)
	(segment
		(start 81.09 168.94)
		(end 80.2 168.05)
		(width 0.15)
		(layer "B.Cu")
		(net 53)
	)
	(segment
		(start 81.09 177.345)
		(end 81.09 168.94)
		(width 0.15)
		(layer "B.Cu")
		(net 53)
	)
	(segment
		(start 79.765 167.3)
		(end 79.765 168.515)
		(width 0.15)
		(layer "F.Cu")
		(net 54)
	)
	(segment
		(start 79.765 168.515)
		(end 79.965 168.715)
		(width 0.15)
		(layer "F.Cu")
		(net 54)
	)
	(via
		(at 79.965 168.715)
		(size 0.5)
		(drill 0.2)
		(layers "F.Cu" "B.Cu")
		(net 54)
	)
	(segment
		(start 79.965 169.54)
		(end 79.965 168.715)
		(width 0.15)
		(layer "B.Cu")
		(net 54)
	)
	(segment
		(start 80.49 170.065)
		(end 79.965 169.54)
		(width 0.15)
		(layer "B.Cu")
		(net 54)
	)
	(segment
		(start 80.49 177.345)
		(end 80.49 170.065)
		(width 0.15)
		(layer "B.Cu")
		(net 54)
	)
	(segment
		(start 73.58 104.97)
		(end 67.05 104.97)
		(width 0.5)
		(layer "F.Cu")
		(net 55)
	)
	(segment
		(start 82.365 170.465)
		(end 82.365 168.465002)
		(width 0.15)
		(layer "F.Cu")
		(net 55)
	)
	(segment
		(start 81.09 177.345)
		(end 81.09 171.74)
		(width 0.15)
		(layer "F.Cu")
		(net 55)
	)
	(segment
		(start 75.285 106.675)
		(end 73.58 104.97)
		(width 0.5)
		(layer "F.Cu")
		(net 55)
	)
	(segment
		(start 67.05 104.97)
		(end 65.13 103.05)
		(width 0.5)
		(layer "F.Cu")
		(net 55)
	)
	(segment
		(start 75.285 106.675)
		(end 77.99 109.38)
		(width 0.15)
		(layer "F.Cu")
		(net 55)
	)
	(segment
		(start 77.99 124.879296)
		(end 79.060705 125.950001)
		(width 0.15)
		(layer "F.Cu")
		(net 55)
	)
	(segment
		(start 82.19 124.13)
		(end 82.19 125.138228)
		(width 0.15)
		(layer "F.Cu")
		(net 55)
	)
	(segment
		(start 82.19 125.138228)
		(end 82.4154 125.363628)
		(width 0.15)
		(layer "F.Cu")
		(net 55)
	)
	(segment
		(start 81.09 171.74)
		(end 82.365 170.465)
		(width 0.15)
		(layer "F.Cu")
		(net 55)
	)
	(segment
		(start 79.060705 125.950001)
		(end 81.829027 125.950001)
		(width 0.15)
		(layer "F.Cu")
		(net 55)
	)
	(segment
		(start 77.99 109.38)
		(end 77.99 124.879296)
		(width 0.15)
		(layer "F.Cu")
		(net 55)
	)
	(segment
		(start 81.829027 125.950001)
		(end 82.4154 125.363628)
		(width 0.15)
		(layer "F.Cu")
		(net 55)
	)
	(via blind
		(at 82.4154 125.363628)
		(size 0.5)
		(drill 0.2)
		(layers "F.Cu" "In2.Cu")
		(net 55)
	)
	(via blind
		(at 82.365 168.465002)
		(size 0.5)
		(drill 0.2)
		(layers "F.Cu" "In2.Cu")
		(net 55)
	)
	(segment
		(start 81.815 127.665)
		(end 81.815 167.915002)
		(width 0.15)
		(layer "In2.Cu")
		(net 55)
	)
	(segment
		(start 82.4154 125.363628)
		(end 82.4154 127.0646)
		(width 0.15)
		(layer "In2.Cu")
		(net 55)
	)
	(segment
		(start 81.815 167.915002)
		(end 82.365 168.465002)
		(width 0.15)
		(layer "In2.Cu")
		(net 55)
	)
	(segment
		(start 82.4154 127.0646)
		(end 81.815 127.665)
		(width 0.15)
		(layer "In2.Cu")
		(net 55)
	)
	(segment
		(start 79.232136 126.475)
		(end 81.675 126.475)
		(width 0.15)
		(layer "F.Cu")
		(net 56)
	)
	(segment
		(start 74.445 108.375)
		(end 75.375 108.375)
		(width 0.15)
		(layer "F.Cu")
		(net 56)
	)
	(segment
		(start 81.865 170.465)
		(end 81.865 168.965)
		(width 0.15)
		(layer "F.Cu")
		(net 56)
	)
	(segment
		(start 81.19 124.13)
		(end 81.19 124.99)
		(width 0.15)
		(layer "F.Cu")
		(net 56)
	)
	(segment
		(start 80.49 177.345)
		(end 80.49 171.84)
		(width 0.15)
		(layer "F.Cu")
		(net 56)
	)
	(segment
		(start 72.745 106.675)
		(end 74.445 108.375)
		(width 0.15)
		(layer "F.Cu")
		(net 56)
	)
	(segment
		(start 77.74 110.74)
		(end 77.74 124.982864)
		(width 0.15)
		(layer "F.Cu")
		(net 56)
	)
	(segment
		(start 81.19 124.99)
		(end 81.675 125.475)
		(width 0.15)
		(layer "F.Cu")
		(net 56)
	)
	(segment
		(start 75.375 108.375)
		(end 77.74 110.74)
		(width 0.15)
		(layer "F.Cu")
		(net 56)
	)
	(segment
		(start 80.49 171.84)
		(end 81.865 170.465)
		(width 0.15)
		(layer "F.Cu")
		(net 56)
	)
	(segment
		(start 77.74 124.982864)
		(end 79.232136 126.475)
		(width 0.15)
		(layer "F.Cu")
		(net 56)
	)
	(via blind
		(at 81.865 168.965)
		(size 0.5)
		(drill 0.2)
		(layers "F.Cu" "In2.Cu")
		(net 56)
	)
	(via blind
		(at 81.675 126.475)
		(size 0.5)
		(drill 0.2)
		(layers "F.Cu" "In2.Cu")
		(net 56)
	)
	(via blind
		(at 81.675 125.475)
		(size 0.5)
		(drill 0.2)
		(layers "F.Cu" "In2.Cu")
		(net 56)
	)
	(segment
		(start 72.745 103.055)
		(end 72.75 103.05)
		(width 0.5)
		(layer "B.Cu")
		(net 56)
	)
	(segment
		(start 72.745 106.675)
		(end 72.745 103.055)
		(width 0.5)
		(layer "B.Cu")
		(net 56)
	)
	(segment
		(start 81.675 126.675)
		(end 81.675 126.475)
		(width 0.15)
		(layer "In2.Cu")
		(net 56)
	)
	(segment
		(start 81.675 126.675)
		(end 81.675 125.475)
		(width 0.15)
		(layer "In2.Cu")
		(net 56)
	)
	(segment
		(start 81.675 126.675)
		(end 81.564993 126.785007)
		(width 0.15)
		(layer "In2.Cu")
		(net 56)
	)
	(segment
		(start 81.564993 168.664993)
		(end 81.865 168.965)
		(width 0.15)
		(layer "In2.Cu")
		(net 56)
	)
	(segment
		(start 81.564993 126.785007)
		(end 81.564993 168.664993)
		(width 0.15)
		(layer "In2.Cu")
		(net 56)
	)
	(segment
		(start 81.69 171.69)
		(end 82.915 170.465)
		(width 0.15)
		(layer "F.Cu")
		(net 57)
	)
	(segment
		(start 77.24 125.19)
		(end 77.24 110.965)
		(width 0.15)
		(layer "F.Cu")
		(net 57)
	)
	(segment
		(start 83.175 125.375)
		(end 83.175 124.145)
		(width 0.15)
		(layer "F.Cu")
		(net 57)
	)
	(segment
		(start 75.34 109.065)
		(end 68.64 109.065)
		(width 0.15)
		(layer "F.Cu")
		(net 57)
	)
	(segment
		(start 67.665 108.09)
		(end 67.665 106.675)
		(width 0.15)
		(layer "F.Cu")
		(net 57)
	)
	(segment
		(start 79.725 127.675)
		(end 77.24 125.19)
		(width 0.15)
		(layer "F.Cu")
		(net 57)
	)
	(segment
		(start 68.64 109.065)
		(end 67.665 108.09)
		(width 0.15)
		(layer "F.Cu")
		(net 57)
	)
	(segment
		(start 81.69 177.345)
		(end 81.69 171.69)
		(width 0.15)
		(layer "F.Cu")
		(net 57)
	)
	(segment
		(start 77.24 110.965)
		(end 75.34 109.065)
		(width 0.15)
		(layer "F.Cu")
		(net 57)
	)
	(segment
		(start 82.875 127.675)
		(end 79.725 127.675)
		(width 0.15)
		(layer "F.Cu")
		(net 57)
	)
	(segment
		(start 83.175 124.145)
		(end 83.19 124.13)
		(width 0.15)
		(layer "F.Cu")
		(net 57)
	)
	(segment
		(start 82.915 170.465)
		(end 82.915 168.965)
		(width 0.15)
		(layer "F.Cu")
		(net 57)
	)
	(via blind
		(at 82.875 127.675)
		(size 0.5)
		(drill 0.2)
		(layers "F.Cu" "In2.Cu")
		(net 57)
	)
	(via blind
		(at 82.915 168.965)
		(size 0.5)
		(drill 0.2)
		(layers "F.Cu" "In2.Cu")
		(net 57)
	)
	(via blind
		(at 83.175 125.375)
		(size 0.5)
		(drill 0.2)
		(layers "F.Cu" "In2.Cu")
		(net 57)
	)
	(segment
		(start 67.67 103.05)
		(end 67.67 106.67)
		(width 0.5)
		(layer "B.Cu")
		(net 57)
	)
	(segment
		(start 67.67 106.67)
		(end 67.665 106.675)
		(width 0.5)
		(layer "B.Cu")
		(net 57)
	)
	(segment
		(start 82.875 127.675)
		(end 82.065 128.485)
		(width 0.15)
		(layer "In2.Cu")
		(net 57)
	)
	(segment
		(start 82.915 168.335998)
		(end 82.915 168.965)
		(width 0.15)
		(layer "In2.Cu")
		(net 57)
	)
	(segment
		(start 82.065 128.485)
		(end 82.065 167.485998)
		(width 0.15)
		(layer "In2.Cu")
		(net 57)
	)
	(segment
		(start 82.875 127.675)
		(end 83.175 127.375)
		(width 0.15)
		(layer "In2.Cu")
		(net 57)
	)
	(segment
		(start 82.065 167.485998)
		(end 82.915 168.335998)
		(width 0.15)
		(layer "In2.Cu")
		(net 57)
	)
	(segment
		(start 83.175 127.375)
		(end 83.175 125.375)
		(width 0.15)
		(layer "In2.Cu")
		(net 57)
	)
	(segment
		(start 77.49 110.861432)
		(end 75.343568 108.715)
		(width 0.15)
		(layer "F.Cu")
		(net 58)
	)
	(segment
		(start 82.29 176.17)
		(end 82.295 176.165)
		(width 0.15)
		(layer "F.Cu")
		(net 58)
	)
	(segment
		(start 82.599999 126.950001)
		(end 79.353569 126.950001)
		(width 0.15)
		(layer "F.Cu")
		(net 58)
	)
	(segment
		(start 82.29 174.48)
		(end 82.29 171.69)
		(width 0.15)
		(layer "F.Cu")
		(net 58)
	)
	(segment
		(start 82.655 175.735)
		(end 82.655 174.845)
		(width 0.15)
		(layer "F.Cu")
		(net 58)
	)
	(segment
		(start 82.29 171.69)
		(end 83.515 170.465)
		(width 0.15)
		(layer "F.Cu")
		(net 58)
	)
	(segment
		(start 72.245 108.715)
		(end 70.205 106.675)
		(width 0.15)
		(layer "F.Cu")
		(net 58)
	)
	(segment
		(start 77.49 125.086432)
		(end 77.49 110.861432)
		(width 0.15)
		(layer "F.Cu")
		(net 58)
	)
	(segment
		(start 79.353569 126.950001)
		(end 77.49 125.086432)
		(width 0.15)
		(layer "F.Cu")
		(net 58)
	)
	(segment
		(start 84.175 124.145)
		(end 84.19 124.13)
		(width 0.15)
		(layer "F.Cu")
		(net 58)
	)
	(segment
		(start 82.29 177.345)
		(end 82.29 176.17)
		(width 0.15)
		(layer "F.Cu")
		(net 58)
	)
	(segment
		(start 84.175 125.375)
		(end 84.175 124.145)
		(width 0.15)
		(layer "F.Cu")
		(net 58)
	)
	(segment
		(start 82.29 177.155)
		(end 82.29 176.1)
		(width 0.15)
		(layer "F.Cu")
		(net 58)
	)
	(segment
		(start 83.515 170.465)
		(end 83.515 168.465)
		(width 0.15)
		(layer "F.Cu")
		(net 58)
	)
	(segment
		(start 75.343568 108.715)
		(end 72.245 108.715)
		(width 0.15)
		(layer "F.Cu")
		(net 58)
	)
	(segment
		(start 84.175 125.375)
		(end 82.599999 126.950001)
		(width 0.15)
		(layer "F.Cu")
		(net 58)
	)
	(segment
		(start 82.29 176.1)
		(end 82.655 175.735)
		(width 0.15)
		(layer "F.Cu")
		(net 58)
	)
	(segment
		(start 82.655 174.845)
		(end 82.29 174.48)
		(width 0.15)
		(layer "F.Cu")
		(net 58)
	)
	(via blind
		(at 84.175 125.375)
		(size 0.5)
		(drill 0.2)
		(layers "F.Cu" "In2.Cu")
		(net 58)
	)
	(via blind
		(at 83.515 168.465)
		(size 0.5)
		(drill 0.2)
		(layers "F.Cu" "In2.Cu")
		(net 58)
	)
	(segment
		(start 70.21 103.05)
		(end 70.21 106.67)
		(width 0.5)
		(layer "B.Cu")
		(net 58)
	)
	(segment
		(start 70.21 106.67)
		(end 70.205 106.675)
		(width 0.5)
		(layer "B.Cu")
		(net 58)
	)
	(segment
		(start 82.315 167.265)
		(end 83.515 168.465)
		(width 0.15)
		(layer "In2.Cu")
		(net 58)
	)
	(segment
		(start 84.175 125.375)
		(end 84.175 127.375)
		(width 0.15)
		(layer "In2.Cu")
		(net 58)
	)
	(segment
		(start 82.315 129.235)
		(end 82.315 167.265)
		(width 0.15)
		(layer "In2.Cu")
		(net 58)
	)
	(segment
		(start 84.175 127.375)
		(end 82.315 129.235)
		(width 0.15)
		(layer "In2.Cu")
		(net 58)
	)
	(segment
		(start 75.09 174.76)
		(end 75.095 174.755)
		(width 0.2)
		(layer "F.Cu")
		(net 59)
	)
	(segment
		(start 74.49 175.26)
		(end 74.495 175.255)
		(width 0.2)
		(layer "F.Cu")
		(net 59)
	)
	(segment
		(start 74.49 177.345)
		(end 74.49 175.26)
		(width 0.2)
		(layer "F.Cu")
		(net 59)
	)
	(segment
		(start 75.09 177.345)
		(end 75.09 174.76)
		(width 0.2)
		(layer "F.Cu")
		(net 59)
	)
	(via
		(at 93.155 63.55)
		(size 0.5)
		(drill 0.2)
		(layers "F.Cu" "B.Cu")
		(net 59)
	)
	(via
		(at 92.455 63.55)
		(size 0.5)
		(drill 0.2)
		(layers "F.Cu" "B.Cu")
		(net 59)
	)
	(via
		(at 92.455 64.24)
		(size 0.5)
		(drill 0.2)
		(layers "F.Cu" "B.Cu")
		(net 59)
	)
	(via
		(at 93.155 64.24)
		(size 0.5)
		(drill 0.2)
		(layers "F.Cu" "B.Cu")
		(net 59)
	)
	(via
		(at 92.455 64.93)
		(size 0.5)
		(drill 0.2)
		(layers "F.Cu" "B.Cu")
		(net 59)
	)
	(via
		(at 93.155 64.93)
		(size 0.5)
		(drill 0.2)
		(layers "F.Cu" "B.Cu")
		(net 59)
	)
	(via
		(at 92.445 71.045)
		(size 0.5)
		(drill 0.2)
		(layers "F.Cu" "B.Cu")
		(net 59)
	)
	(via
		(at 93.145 71.045)
		(size 0.5)
		(drill 0.2)
		(layers "F.Cu" "B.Cu")
		(net 59)
	)
	(via
		(at 93.145 72.445)
		(size 0.5)
		(drill 0.2)
		(layers "F.Cu" "B.Cu")
		(net 59)
	)
	(via
		(at 92.445 72.445)
		(size 0.5)
		(drill 0.2)
		(layers "F.Cu" "B.Cu")
		(net 59)
	)
	(via
		(at 92.445 71.745)
		(size 0.5)
		(drill 0.2)
		(layers "F.Cu" "B.Cu")
		(net 59)
	)
	(via
		(at 93.145 71.745)
		(size 0.5)
		(drill 0.2)
		(layers "F.Cu" "B.Cu")
		(net 59)
	)
	(via
		(at 74.495 175.255)
		(size 0.5)
		(drill 0.2)
		(layers "F.Cu" "B.Cu")
		(net 59)
	)
	(via
		(at 75.095 174.755)
		(size 0.5)
		(drill 0.2)
		(layers "F.Cu" "B.Cu")
		(net 59)
	)
	(segment
		(start 74.49 177.345)
		(end 74.49 175.26)
		(width 0.2)
		(layer "B.Cu")
		(net 59)
	)
	(segment
		(start 74.49 175.26)
		(end 74.495 175.255)
		(width 0.2)
		(layer "B.Cu")
		(net 59)
	)
	(segment
		(start 75.09 174.76)
		(end 75.095 174.755)
		(width 0.2)
		(layer "B.Cu")
		(net 59)
	)
	(segment
		(start 75.09 177.345)
		(end 75.09 174.76)
		(width 0.2)
		(layer "B.Cu")
		(net 59)
	)
	(segment
		(start 90.52 73.915)
		(end 90.52 73.25)
		(width 0.25)
		(layer "F.Cu")
		(net 60)
	)
	(segment
		(start 90.52 73.25)
		(end 90.37 73.1)
		(width 0.25)
		(layer "F.Cu")
		(net 60)
	)
	(segment
		(start 91.52 73.915)
		(end 90.52 73.915)
		(width 0.25)
		(layer "F.Cu")
		(net 60)
	)
	(segment
		(start 81 71.4)
		(end 81.35 71.05)
		(width 0.5)
		(layer "F.Cu")
		(net 60)
	)
	(segment
		(start 81.35 71.05)
		(end 82.5 71.05)
		(width 0.5)
		(layer "F.Cu")
		(net 60)
	)
	(segment
		(start 81 71.4)
		(end 79.925 71.4)
		(width 0.5)
		(layer "F.Cu")
		(net 60)
	)
	(via
		(at 90.37 73.1)
		(size 0.5)
		(drill 0.2)
		(layers "F.Cu" "B.Cu")
		(net 60)
	)
	(via
		(at 85.45 71.35)
		(size 0.5)
		(drill 0.2)
		(layers "F.Cu" "B.Cu")
		(net 60)
	)
	(segment
		(start 85.45 71.35)
		(end 88.62 71.35)
		(width 0.25)
		(layer "B.Cu")
		(net 60)
	)
	(segment
		(start 88.62 71.35)
		(end 90.37 73.1)
		(width 0.25)
		(layer "B.Cu")
		(net 60)
	)
	(segment
		(start 84.64 163.265)
		(end 84.24 163.265)
		(width 0.15)
		(layer "F.Cu")
		(net 61)
	)
	(segment
		(start 100.75 113.175)
		(end 100.275 112.7)
		(width 0.1)
		(layer "F.Cu")
		(net 61)
	)
	(segment
		(start 85.39 164.83)
		(end 85.39 164.015)
		(width 0.15)
		(layer "F.Cu")
		(net 61)
	)
	(segment
		(start 85.39 164.015)
		(end 84.64 163.265)
		(width 0.15)
		(layer "F.Cu")
		(net 61)
	)
	(segment
		(start 100.775 113.175)
		(end 100.75 113.175)
		(width 0.1)
		(layer "F.Cu")
		(net 61)
	)
	(via blind
		(at 100.275 112.7)
		(size 0.5)
		(drill 0.2)
		(layers "F.Cu" "In5.Cu")
		(net 61)
	)
	(via
		(at 84.24 163.265)
		(size 0.5)
		(drill 0.2)
		(layers "F.Cu" "B.Cu")
		(net 61)
	)
	(segment
		(start 79.45008 159.007197)
		(end 83.707883 163.265)
		(width 0.15)
		(layer "In5.Cu")
		(net 61)
	)
	(segment
		(start 99.45 111.875)
		(end 100.275 112.7)
		(width 0.15)
		(layer "In5.Cu")
		(net 61)
	)
	(segment
		(start 97.217 111.875)
		(end 99.45 111.875)
		(width 0.15)
		(layer "In5.Cu")
		(net 61)
	)
	(segment
		(start 79.45008 159.007197)
		(end 79.45008 122.160014)
		(width 0.15)
		(layer "In5.Cu")
		(net 61)
	)
	(segment
		(start 90.535074 111.07502)
		(end 96.41702 111.07502)
		(width 0.15)
		(layer "In5.Cu")
		(net 61)
	)
	(segment
		(start 79.45008 122.160014)
		(end 90.535074 111.07502)
		(width 0.15)
		(layer "In5.Cu")
		(net 61)
	)
	(segment
		(start 96.41702 111.07502)
		(end 97.217 111.875)
		(width 0.15)
		(layer "In5.Cu")
		(net 61)
	)
	(segment
		(start 83.707883 163.265)
		(end 84.24 163.265)
		(width 0.15)
		(layer "In5.Cu")
		(net 61)
	)
	(segment
		(start 84.49 162.665)
		(end 83.715 162.665)
		(width 0.15)
		(layer "F.Cu")
		(net 62)
	)
	(segment
		(start 85.89 164.83)
		(end 85.89 164.065)
		(width 0.15)
		(layer "F.Cu")
		(net 62)
	)
	(segment
		(start 99.775 113.125)
		(end 99.325 112.675)
		(width 0.1)
		(layer "F.Cu")
		(net 62)
	)
	(segment
		(start 85.89 164.065)
		(end 84.49 162.665)
		(width 0.15)
		(layer "F.Cu")
		(net 62)
	)
	(segment
		(start 99.775 113.175)
		(end 99.775 113.125)
		(width 0.1)
		(layer "F.Cu")
		(net 62)
	)
	(via
		(at 83.715 162.665)
		(size 0.5)
		(drill 0.2)
		(layers "F.Cu" "B.Cu")
		(net 62)
	)
	(via blind
		(at 99.325 112.675)
		(size 0.5)
		(drill 0.2)
		(layers "F.Cu" "In5.Cu")
		(net 62)
	)
	(segment
		(start 98.849999 112.199999)
		(end 99.325 112.675)
		(width 0.15)
		(layer "In5.Cu")
		(net 62)
	)
	(segment
		(start 92.965 111.615)
		(end 95.239279 111.615)
		(width 0.15)
		(layer "In5.Cu")
		(net 62)
	)
	(segment
		(start 92.305019 112.274981)
		(end 92.965 111.615)
		(width 0.15)
		(layer "In5.Cu")
		(net 62)
	)
	(segment
		(start 79.750091 122.284282)
		(end 89.759394 112.274981)
		(width 0.15)
		(layer "In5.Cu")
		(net 62)
	)
	(segment
		(start 89.759394 112.274981)
		(end 92.305019 112.274981)
		(width 0.15)
		(layer "In5.Cu")
		(net 62)
	)
	(segment
		(start 95.824278 112.199999)
		(end 98.849999 112.199999)
		(width 0.15)
		(layer "In5.Cu")
		(net 62)
	)
	(segment
		(start 95.239279 111.615)
		(end 95.824278 112.199999)
		(width 0.15)
		(layer "In5.Cu")
		(net 62)
	)
	(segment
		(start 83.715 162.665)
		(end 83.532162 162.665)
		(width 0.15)
		(layer "In5.Cu")
		(net 62)
	)
	(segment
		(start 83.532162 162.665)
		(end 79.750091 158.882929)
		(width 0.15)
		(layer "In5.Cu")
		(net 62)
	)
	(segment
		(start 79.750091 158.882929)
		(end 79.750091 122.284282)
		(width 0.15)
		(layer "In5.Cu")
		(net 62)
	)
	(segment
		(start 86.39 164.09)
		(end 84.54 162.24)
		(width 0.15)
		(layer "F.Cu")
		(net 63)
	)
	(segment
		(start 86.39 164.83)
		(end 86.39 164.09)
		(width 0.15)
		(layer "F.Cu")
		(net 63)
	)
	(segment
		(start 84.54 162.24)
		(end 84.24 162.24)
		(width 0.15)
		(layer "F.Cu")
		(net 63)
	)
	(segment
		(start 97.775 113.175)
		(end 97.275 112.675)
		(width 0.15)
		(layer "F.Cu")
		(net 63)
	)
	(via
		(at 84.24 162.24)
		(size 0.5)
		(drill 0.2)
		(layers "F.Cu" "B.Cu")
		(net 63)
	)
	(via blind
		(at 97.275 112.675)
		(size 0.5)
		(drill 0.2)
		(layers "F.Cu" "In5.Cu")
		(net 63)
	)
	(segment
		(start 80.050102 158.758661)
		(end 80.050102 122.40855)
		(width 0.15)
		(layer "In5.Cu")
		(net 63)
	)
	(segment
		(start 92.40501 112.57499)
		(end 93.065 111.915)
		(width 0.15)
		(layer "In5.Cu")
		(net 63)
	)
	(segment
		(start 83.531441 162.24)
		(end 80.050102 158.758661)
		(width 0.15)
		(layer "In5.Cu")
		(net 63)
	)
	(segment
		(start 93.065 111.915)
		(end 95.115 111.915)
		(width 0.15)
		(layer "In5.Cu")
		(net 63)
	)
	(segment
		(start 95.875 112.675)
		(end 97.275 112.675)
		(width 0.15)
		(layer "In5.Cu")
		(net 63)
	)
	(segment
		(start 80.050102 122.40855)
		(end 89.883663 112.57499)
		(width 0.15)
		(layer "In5.Cu")
		(net 63)
	)
	(segment
		(start 95.115 111.915)
		(end 95.875 112.675)
		(width 0.15)
		(layer "In5.Cu")
		(net 63)
	)
	(segment
		(start 89.883663 112.57499)
		(end 92.40501 112.57499)
		(width 0.15)
		(layer "In5.Cu")
		(net 63)
	)
	(segment
		(start 84.24 162.24)
		(end 83.531441 162.24)
		(width 0.15)
		(layer "In5.Cu")
		(net 63)
	)
	(segment
		(start 86.89 164.19)
		(end 84.515 161.815)
		(width 0.15)
		(layer "F.Cu")
		(net 64)
	)
	(segment
		(start 101.775 114.175)
		(end 102.275 113.675)
		(width 0.15)
		(layer "F.Cu")
		(net 64)
	)
	(segment
		(start 86.89 164.83)
		(end 86.89 164.19)
		(width 0.15)
		(layer "F.Cu")
		(net 64)
	)
	(segment
		(start 83.715 161.815)
		(end 84.515 161.815)
		(width 0.15)
		(layer "F.Cu")
		(net 64)
	)
	(via blind
		(at 102.275 113.675)
		(size 0.5)
		(drill 0.2)
		(layers "F.Cu" "In5.Cu")
		(net 64)
	)
	(via
		(at 83.715 161.815)
		(size 0.5)
		(drill 0.2)
		(layers "F.Cu" "B.Cu")
		(net 64)
	)
	(segment
		(start 83.715 161.815)
		(end 83.53072 161.815)
		(width 0.15)
		(layer "In5.Cu")
		(net 64)
	)
	(segment
		(start 95.924978 113.174978)
		(end 99.823536 113.174978)
		(width 0.15)
		(layer "In5.Cu")
		(net 64)
	)
	(segment
		(start 94.965 112.215)
		(end 95.924978 113.174978)
		(width 0.15)
		(layer "In5.Cu")
		(net 64)
	)
	(segment
		(start 99.823536 113.174978)
		(end 99.823558 113.175)
		(width 0.15)
		(layer "In5.Cu")
		(net 64)
	)
	(segment
		(start 80.350113 122.532818)
		(end 90.007931 112.875)
		(width 0.15)
		(layer "In5.Cu")
		(net 64)
	)
	(segment
		(start 80.350113 158.634393)
		(end 80.350113 122.532818)
		(width 0.15)
		(layer "In5.Cu")
		(net 64)
	)
	(segment
		(start 101.775 113.175)
		(end 102.275 113.675)
		(width 0.15)
		(layer "In5.Cu")
		(net 64)
	)
	(segment
		(start 83.53072 161.815)
		(end 80.350113 158.634393)
		(width 0.15)
		(layer "In5.Cu")
		(net 64)
	)
	(segment
		(start 90.007931 112.875)
		(end 92.505 112.875)
		(width 0.15)
		(layer "In5.Cu")
		(net 64)
	)
	(segment
		(start 92.505 112.875)
		(end 93.165 112.215)
		(width 0.15)
		(layer "In5.Cu")
		(net 64)
	)
	(segment
		(start 99.823558 113.175)
		(end 101.775 113.175)
		(width 0.15)
		(layer "In5.Cu")
		(net 64)
	)
	(segment
		(start 93.165 112.215)
		(end 94.965 112.215)
		(width 0.15)
		(layer "In5.Cu")
		(net 64)
	)
	(segment
		(start 99.775 114.175)
		(end 100.275 113.675)
		(width 0.15)
		(layer "F.Cu")
		(net 65)
	)
	(segment
		(start 84.515 161.365)
		(end 84.24 161.365)
		(width 0.15)
		(layer "F.Cu")
		(net 65)
	)
	(segment
		(start 87.39 164.24)
		(end 84.515 161.365)
		(width 0.15)
		(layer "F.Cu")
		(net 65)
	)
	(segment
		(start 87.39 164.83)
		(end 87.39 164.24)
		(width 0.15)
		(layer "F.Cu")
		(net 65)
	)
	(via blind
		(at 100.275 113.675)
		(size 0.5)
		(drill 0.2)
		(layers "F.Cu" "In5.Cu")
		(net 65)
	)
	(via
		(at 84.24 161.365)
		(size 0.5)
		(drill 0.2)
		(layers "F.Cu" "B.Cu")
		(net 65)
	)
	(segment
		(start 84.24 161.365)
		(end 83.504999 161.365)
		(width 0.15)
		(layer "In5.Cu")
		(net 65)
	)
	(segment
		(start 83.504999 161.365)
		(end 80.650124 158.510125)
		(width 0.15)
		(layer "In5.Cu")
		(net 65)
	)
	(segment
		(start 90.13221 113.175)
		(end 95.475 113.175)
		(width 0.15)
		(layer "In5.Cu")
		(net 65)
	)
	(segment
		(start 99.899279 113.675)
		(end 100.275 113.675)
		(width 0.15)
		(layer "In5.Cu")
		(net 65)
	)
	(segment
		(start 99.699268 113.474989)
		(end 99.899279 113.675)
		(width 0.15)
		(layer "In5.Cu")
		(net 65)
	)
	(segment
		(start 80.650124 158.510125)
		(end 80.650124 122.657086)
		(width 0.15)
		(layer "In5.Cu")
		(net 65)
	)
	(segment
		(start 95.774989 113.474989)
		(end 99.699268 113.474989)
		(width 0.15)
		(layer "In5.Cu")
		(net 65)
	)
	(segment
		(start 80.650124 122.657086)
		(end 90.13221 113.175)
		(width 0.15)
		(layer "In5.Cu")
		(net 65)
	)
	(segment
		(start 95.475 113.175)
		(end 95.774989 113.474989)
		(width 0.15)
		(layer "In5.Cu")
		(net 65)
	)
	(segment
		(start 84.565 160.94)
		(end 83.715 160.94)
		(width 0.15)
		(layer "F.Cu")
		(net 66)
	)
	(segment
		(start 87.89 164.83)
		(end 87.89 164.265)
		(width 0.15)
		(layer "F.Cu")
		(net 66)
	)
	(segment
		(start 101.775 115.175)
		(end 102.275 114.675)
		(width 0.15)
		(layer "F.Cu")
		(net 66)
	)
	(segment
		(start 87.89 164.265)
		(end 84.565 160.94)
		(width 0.15)
		(layer "F.Cu")
		(net 66)
	)
	(via blind
		(at 102.275 114.675)
		(size 0.5)
		(drill 0.2)
		(layers "F.Cu" "In5.Cu")
		(net 66)
	)
	(via
		(at 83.715 160.94)
		(size 0.5)
		(drill 0.2)
		(layers "F.Cu" "B.Cu")
		(net 66)
	)
	(segment
		(start 80.950135 122.781354)
		(end 89.465745 114.265745)
		(width 0.15)
		(layer "In5.Cu")
		(net 66)
	)
	(segment
		(start 83.504278 160.94)
		(end 80.950135 158.385857)
		(width 0.15)
		(layer "In5.Cu")
		(net 66)
	)
	(segment
		(start 83.715 160.94)
		(end 83.504278 160.94)
		(width 0.15)
		(layer "In5.Cu")
		(net 66)
	)
	(segment
		(start 97.575 113.775)
		(end 99.575 113.775)
		(width 0.15)
		(layer "In5.Cu")
		(net 66)
	)
	(segment
		(start 99.975 114.175)
		(end 99.57501 113.77501)
		(width 0.15)
		(layer "In5.Cu")
		(net 66)
	)
	(segment
		(start 89.465745 114.265745)
		(end 97.084255 114.265745)
		(width 0.15)
		(layer "In5.Cu")
		(net 66)
	)
	(segment
		(start 80.950135 158.385857)
		(end 80.950135 122.781354)
		(width 0.15)
		(layer "In5.Cu")
		(net 66)
	)
	(segment
		(start 97.084255 114.265745)
		(end 97.575 113.775)
		(width 0.15)
		(layer "In5.Cu")
		(net 66)
	)
	(segment
		(start 101.775 114.175)
		(end 99.975 114.175)
		(width 0.15)
		(layer "In5.Cu")
		(net 66)
	)
	(segment
		(start 102.275 114.675)
		(end 101.775 114.175)
		(width 0.15)
		(layer "In5.Cu")
		(net 66)
	)
	(segment
		(start 99.775 115.175)
		(end 100.275 114.675)
		(width 0.15)
		(layer "F.Cu")
		(net 67)
	)
	(segment
		(start 84.64 160.515)
		(end 88.39 164.265)
		(width 0.15)
		(layer "F.Cu")
		(net 67)
	)
	(segment
		(start 88.39 164.265)
		(end 88.39 164.815)
		(width 0.15)
		(layer "F.Cu")
		(net 67)
	)
	(segment
		(start 84.24 160.515)
		(end 84.64 160.515)
		(width 0.15)
		(layer "F.Cu")
		(net 67)
	)
	(via blind
		(at 100.275 114.675)
		(size 0.5)
		(drill 0.2)
		(layers "F.Cu" "In5.Cu")
		(net 67)
	)
	(via
		(at 84.24 160.515)
		(size 0.5)
		(drill 0.2)
		(layers "F.Cu" "B.Cu")
		(net 67)
	)
	(segment
		(start 83.503557 160.515)
		(end 84.24 160.515)
		(width 0.15)
		(layer "In5.Cu")
		(net 67)
	)
	(segment
		(start 99.921447 114.675)
		(end 100.275 114.675)
		(width 0.15)
		(layer "In5.Cu")
		(net 67)
	)
	(segment
		(start 81.250146 158.261589)
		(end 83.503557 160.515)
		(width 0.15)
		(layer "In5.Cu")
		(net 67)
	)
	(segment
		(start 81.250148 158.26159)
		(end 81.250147 122.905622)
		(width 0.15)
		(layer "In5.Cu")
		(net 67)
	)
	(segment
		(start 97.675 114.175)
		(end 99.421447 114.175)
		(width 0.15)
		(layer "In5.Cu")
		(net 67)
	)
	(segment
		(start 81.250146 122.905622)
		(end 81.250146 158.261589)
		(width 0.15)
		(layer "In5.Cu")
		(net 67)
	)
	(segment
		(start 97.275021 114.574979)
		(end 97.675 114.175)
		(width 0.15)
		(layer "In5.Cu")
		(net 67)
	)
	(segment
		(start 89.580789 114.57498)
		(end 97.275021 114.574979)
		(width 0.15)
		(layer "In5.Cu")
		(net 67)
	)
	(segment
		(start 99.421447 114.175)
		(end 99.921447 114.675)
		(width 0.15)
		(layer "In5.Cu")
		(net 67)
	)
	(segment
		(start 81.250147 122.905622)
		(end 89.580789 114.57498)
		(width 0.15)
		(layer "In5.Cu")
		(net 67)
	)
	(segment
		(start 100.775 115.175)
		(end 101.275 114.675)
		(width 0.15)
		(layer "F.Cu")
		(net 68)
	)
	(segment
		(start 88.825 164.25)
		(end 84.665 160.09)
		(width 0.15)
		(layer "F.Cu")
		(net 68)
	)
	(segment
		(start 83.715 160.09)
		(end 84.665 160.09)
		(width 0.15)
		(layer "F.Cu")
		(net 68)
	)
	(segment
		(start 88.825 165.765)
		(end 88.825 164.25)
		(width 0.15)
		(layer "F.Cu")
		(net 68)
	)
	(via blind
		(at 101.275 114.675)
		(size 0.5)
		(drill 0.2)
		(layers "F.Cu" "In5.Cu")
		(net 68)
	)
	(via
		(at 83.715 160.09)
		(size 0.5)
		(drill 0.2)
		(layers "F.Cu" "B.Cu")
		(net 68)
	)
	(segment
		(start 100.775 115.175)
		(end 101.275 114.675)
		(width 0.15)
		(layer "In5.Cu")
		(net 68)
	)
	(segment
		(start 83.64 160.09)
		(end 81.550157 158.000157)
		(width 0.15)
		(layer "In5.Cu")
		(net 68)
	)
	(segment
		(start 89.705058 114.874989)
		(end 97.674989 114.874989)
		(width 0.15)
		(layer "In5.Cu")
		(net 68)
	)
	(segment
		(start 97.975 115.175)
		(end 100.775 115.175)
		(width 0.15)
		(layer "In5.Cu")
		(net 68)
	)
	(segment
		(start 83.715 160.09)
		(end 83.64 160.09)
		(width 0.15)
		(layer "In5.Cu")
		(net 68)
	)
	(segment
		(start 81.550157 158.000157)
		(end 81.550157 123.02989)
		(width 0.15)
		(layer "In5.Cu")
		(net 68)
	)
	(segment
		(start 81.550157 123.02989)
		(end 89.705058 114.874989)
		(width 0.15)
		(layer "In5.Cu")
		(net 68)
	)
	(segment
		(start 97.674989 114.874989)
		(end 97.975 115.175)
		(width 0.15)
		(layer "In5.Cu")
		(net 68)
	)
	(segment
		(start 90.495 162.365)
		(end 87.44 162.365)
		(width 0.15)
		(layer "F.Cu")
		(net 69)
	)
	(segment
		(start 87.44 162.365)
		(end 84.74 159.665)
		(width 0.15)
		(layer "F.Cu")
		(net 69)
	)
	(segment
		(start 96.775 116.175)
		(end 97.275 115.675)
		(width 0.15)
		(layer "F.Cu")
		(net 69)
	)
	(segment
		(start 84.74 159.665)
		(end 84.24 159.665)
		(width 0.15)
		(layer "F.Cu")
		(net 69)
	)
	(via
		(at 84.24 159.665)
		(size 0.5)
		(drill 0.2)
		(layers "F.Cu" "B.Cu")
		(net 69)
	)
	(via blind
		(at 97.275 115.675)
		(size 0.5)
		(drill 0.2)
		(layers "F.Cu" "In5.Cu")
		(net 69)
	)
	(segment
		(start 83.69 159.665)
		(end 81.850168 157.825168)
		(width 0.15)
		(layer "In5.Cu")
		(net 69)
	)
	(segment
		(start 84.24 159.665)
		(end 83.69 159.665)
		(width 0.15)
		(layer "In5.Cu")
		(net 69)
	)
	(segment
		(start 81.850168 157.825168)
		(end 81.850168 123.154158)
		(width 0.15)
		(layer "In5.Cu")
		(net 69)
	)
	(segment
		(start 96.775 115.175)
		(end 97.275 115.675)
		(width 0.15)
		(layer "In5.Cu")
		(net 69)
	)
	(segment
		(start 89.829326 115.175)
		(end 96.775 115.175)
		(width 0.15)
		(layer "In5.Cu")
		(net 69)
	)
	(segment
		(start 81.850168 123.154158)
		(end 89.829326 115.175)
		(width 0.15)
		(layer "In5.Cu")
		(net 69)
	)
	(segment
		(start 92.715 177.07)
		(end 92.715 175.17)
		(width 0.2)
		(layer "F.Cu")
		(net 70)
	)
	(segment
		(start 72.052 161.013002)
		(end 72.050002 161.015)
		(width 0.15)
		(layer "F.Cu")
		(net 70)
	)
	(segment
		(start 72.052 158.73122)
		(end 72.052 161.013002)
		(width 0.15)
		(layer "F.Cu")
		(net 70)
	)
	(via blind
		(at 92.715 175.17)
		(size 0.5)
		(drill 0.2)
		(layers "F.Cu" "In2.Cu")
		(net 70)
	)
	(via
		(at 72.050002 161.015)
		(size 0.5)
		(drill 0.2)
		(layers "F.Cu" "B.Cu")
		(net 70)
	)
	(segment
		(start 87.94 173.65)
		(end 85.455067 171.165067)
		(width 0.15)
		(layer "In2.Cu")
		(net 70)
	)
	(segment
		(start 75.994069 171.165067)
		(end 72.050002 167.221)
		(width 0.15)
		(layer "In2.Cu")
		(net 70)
	)
	(segment
		(start 92.715 175.17)
		(end 91.195 173.65)
		(width 0.15)
		(layer "In2.Cu")
		(net 70)
	)
	(segment
		(start 91.195 173.65)
		(end 87.94 173.65)
		(width 0.15)
		(layer "In2.Cu")
		(net 70)
	)
	(segment
		(start 72.050002 167.221)
		(end 72.050002 161.015)
		(width 0.15)
		(layer "In2.Cu")
		(net 70)
	)
	(segment
		(start 85.455067 171.165067)
		(end 75.994069 171.165067)
		(width 0.15)
		(layer "In2.Cu")
		(net 70)
	)
	(segment
		(start 72.54 158.47822)
		(end 72.54 159.86)
		(width 0.15)
		(layer "F.Cu")
		(net 71)
	)
	(segment
		(start 72.572 158.44622)
		(end 72.54 158.47822)
		(width 0.15)
		(layer "F.Cu")
		(net 71)
	)
	(segment
		(start 93.315 177.095)
		(end 93.315 175.495)
		(width 0.2)
		(layer "F.Cu")
		(net 71)
	)
	(via blind
		(at 93.315 175.495)
		(size 0.5)
		(drill 0.2)
		(layers "F.Cu" "In2.Cu")
		(net 71)
	)
	(via
		(at 72.54 160.015)
		(size 0.5)
		(drill 0.2)
		(layers "F.Cu" "B.Cu")
		(net 71)
	)
	(segment
		(start 76.097626 170.915056)
		(end 72.55 167.36743)
		(width 0.15)
		(layer "In2.Cu")
		(net 71)
	)
	(segment
		(start 93.315 175.495)
		(end 93.315 174.470721)
		(width 0.15)
		(layer "In2.Cu")
		(net 71)
	)
	(segment
		(start 93.315 174.470721)
		(end 92.194268 173.349989)
		(width 0.15)
		(layer "In2.Cu")
		(net 71)
	)
	(segment
		(start 72.55 167.36743)
		(end 72.55 159.87)
		(width 0.15)
		(layer "In2.Cu")
		(net 71)
	)
	(segment
		(start 85.629334 170.915056)
		(end 76.097626 170.915056)
		(width 0.15)
		(layer "In2.Cu")
		(net 71)
	)
	(segment
		(start 92.194268 173.349989)
		(end 88.064267 173.349989)
		(width 0.15)
		(layer "In2.Cu")
		(net 71)
	)
	(segment
		(start 88.064267 173.349989)
		(end 85.629334 170.915056)
		(width 0.15)
		(layer "In2.Cu")
		(net 71)
	)
	(segment
		(start 73.077 160.448)
		(end 73.065 160.46)
		(width 0.15)
		(layer "F.Cu")
		(net 72)
	)
	(segment
		(start 73.077 158.45122)
		(end 73.077 160.448)
		(width 0.15)
		(layer "F.Cu")
		(net 72)
	)
	(segment
		(start 93.915 177.095)
		(end 93.915 175.195)
		(width 0.2)
		(layer "F.Cu")
		(net 72)
	)
	(via blind
		(at 93.915 175.195)
		(size 0.5)
		(drill 0.2)
		(layers "F.Cu" "In2.Cu")
		(net 72)
	)
	(via
		(at 73.065 160.46)
		(size 0.5)
		(drill 0.2)
		(layers "F.Cu" "B.Cu")
		(net 72)
	)
	(segment
		(start 92.318536 173.049978)
		(end 88.188534 173.049978)
		(width 0.15)
		(layer "In2.Cu")
		(net 72)
	)
	(segment
		(start 76.201183 170.665045)
		(end 73.065 167.528862)
		(width 0.15)
		(layer "In2.Cu")
		(net 72)
	)
	(segment
		(start 88.188534 173.049978)
		(end 85.803601 170.665045)
		(width 0.15)
		(layer "In2.Cu")
		(net 72)
	)
	(segment
		(start 93.915 174.646442)
		(end 92.318536 173.049978)
		(width 0.15)
		(layer "In2.Cu")
		(net 72)
	)
	(segment
		(start 85.803601 170.665045)
		(end 76.201183 170.665045)
		(width 0.15)
		(layer "In2.Cu")
		(net 72)
	)
	(segment
		(start 73.065 167.528862)
		(end 73.065 160.46)
		(width 0.15)
		(layer "In2.Cu")
		(net 72)
	)
	(segment
		(start 93.915 175.195)
		(end 93.915 174.646442)
		(width 0.15)
		(layer "In2.Cu")
		(net 72)
	)
	(segment
		(start 94.49 177.12)
		(end 94.49 175.52)
		(width 0.2)
		(layer "F.Cu")
		(net 73)
	)
	(segment
		(start 73.577 158.45122)
		(end 73.577 159.848)
		(width 0.15)
		(layer "F.Cu")
		(net 73)
	)
	(via blind
		(at 94.49 175.52)
		(size 0.5)
		(drill 0.2)
		(layers "F.Cu" "In2.Cu")
		(net 73)
	)
	(via
		(at 73.577 159.848)
		(size 0.5)
		(drill 0.2)
		(layers "F.Cu" "B.Cu")
		(net 73)
	)
	(segment
		(start 94.49 175.52)
		(end 94.49 174.797163)
		(width 0.15)
		(layer "In2.Cu")
		(net 73)
	)
	(segment
		(start 94.49 174.797163)
		(end 92.442804 172.749967)
		(width 0.15)
		(layer "In2.Cu")
		(net 73)
	)
	(segment
		(start 92.442804 172.749967)
		(end 88.312801 172.749967)
		(width 0.15)
		(layer "In2.Cu")
		(net 73)
	)
	(segment
		(start 88.312801 172.749967)
		(end 85.977868 170.415034)
		(width 0.15)
		(layer "In2.Cu")
		(net 73)
	)
	(segment
		(start 76.330755 170.415034)
		(end 73.575 167.659279)
		(width 0.15)
		(layer "In2.Cu")
		(net 73)
	)
	(segment
		(start 73.575 159.85)
		(end 73.577 159.848)
		(width 0.15)
		(layer "In2.Cu")
		(net 73)
	)
	(segment
		(start 73.575 167.659279)
		(end 73.575 159.85)
		(width 0.15)
		(layer "In2.Cu")
		(net 73)
	)
	(segment
		(start 85.977868 170.415034)
		(end 76.330755 170.415034)
		(width 0.15)
		(layer "In2.Cu")
		(net 73)
	)
	(segment
		(start 95.09 177.12)
		(end 95.09 175.22)
		(width 0.2)
		(layer "F.Cu")
		(net 74)
	)
	(segment
		(start 74.072 158.44622)
		(end 74.072 160.442)
		(width 0.15)
		(layer "F.Cu")
		(net 74)
	)
	(segment
		(start 74.072 160.442)
		(end 74.09 160.46)
		(width 0.15)
		(layer "F.Cu")
		(net 74)
	)
	(via
		(at 74.09 160.46)
		(size 0.5)
		(drill 0.2)
		(layers "F.Cu" "B.Cu")
		(net 74)
	)
	(via blind
		(at 95.09 175.22)
		(size 0.5)
		(drill 0.2)
		(layers "F.Cu" "In2.Cu")
		(net 74)
	)
	(segment
		(start 92.673509 172.449956)
		(end 88.437068 172.449956)
		(width 0.15)
		(layer "In2.Cu")
		(net 74)
	)
	(segment
		(start 86.152135 170.165023)
		(end 76.505023 170.165023)
		(width 0.15)
		(layer "In2.Cu")
		(net 74)
	)
	(segment
		(start 74.075 167.735)
		(end 74.09 160.46)
		(width 0.15)
		(layer "In2.Cu")
		(net 74)
	)
	(segment
		(start 76.505023 170.165023)
		(end 74.075 167.735)
		(width 0.15)
		(layer "In2.Cu")
		(net 74)
	)
	(segment
		(start 95.09 175.22)
		(end 95.09 174.866447)
		(width 0.15)
		(layer "In2.Cu")
		(net 74)
	)
	(segment
		(start 95.09 174.866447)
		(end 92.673509 172.449956)
		(width 0.15)
		(layer "In2.Cu")
		(net 74)
	)
	(segment
		(start 88.437068 172.449956)
		(end 86.152135 170.165023)
		(width 0.15)
		(layer "In2.Cu")
		(net 74)
	)
	(segment
		(start 74.577 158.45122)
		(end 74.577 159.798)
		(width 0.15)
		(layer "F.Cu")
		(net 75)
	)
	(segment
		(start 95.665 177.17)
		(end 95.665 175.57)
		(width 0.2)
		(layer "F.Cu")
		(net 75)
	)
	(via blind
		(at 95.665 175.57)
		(size 0.5)
		(drill 0.2)
		(layers "F.Cu" "In2.Cu")
		(net 75)
	)
	(via
		(at 74.577 159.798)
		(size 0.5)
		(drill 0.2)
		(layers "F.Cu" "B.Cu")
		(net 75)
	)
	(segment
		(start 88.561335 172.149945)
		(end 86.326402 169.915012)
		(width 0.15)
		(layer "In2.Cu")
		(net 75)
	)
	(segment
		(start 76.755012 169.915012)
		(end 74.577 167.737)
		(width 0.15)
		(layer "In2.Cu")
		(net 75)
	)
	(segment
		(start 95.665 174.525)
		(end 93.299945 172.159945)
		(width 0.15)
		(layer "In2.Cu")
		(net 75)
	)
	(segment
		(start 92.69134 172.149945)
		(end 88.561335 172.149945)
		(width 0.15)
		(layer "In2.Cu")
		(net 75)
	)
	(segment
		(start 74.577 167.737)
		(end 74.577 159.798)
		(width 0.15)
		(layer "In2.Cu")
		(net 75)
	)
	(segment
		(start 95.665 175.57)
		(end 95.665 174.525)
		(width 0.15)
		(layer "In2.Cu")
		(net 75)
	)
	(segment
		(start 92.70134 172.159945)
		(end 92.69134 172.149945)
		(width 0.15)
		(layer "In2.Cu")
		(net 75)
	)
	(segment
		(start 93.299945 172.159945)
		(end 92.70134 172.159945)
		(width 0.15)
		(layer "In2.Cu")
		(net 75)
	)
	(segment
		(start 86.326402 169.915012)
		(end 76.755012 169.915012)
		(width 0.15)
		(layer "In2.Cu")
		(net 75)
	)
	(segment
		(start 91.775 118.175)
		(end 92.275 117.675)
		(width 0.15)
		(layer "F.Cu")
		(net 76)
	)
	(segment
		(start 96.49 173.101)
		(end 96.89 172.701)
		(width 0.2)
		(layer "F.Cu")
		(net 76)
	)
	(segment
		(start 96.89 177.155)
		(end 96.89 174.771)
		(width 0.2)
		(layer "F.Cu")
		(net 76)
	)
	(segment
		(start 96.49 174.371)
		(end 96.49 173.101)
		(width 0.2)
		(layer "F.Cu")
		(net 76)
	)
	(segment
		(start 96.89 172.701)
		(end 96.89 167.745)
		(width 0.2)
		(layer "F.Cu")
		(net 76)
	)
	(segment
		(start 96.89 174.771)
		(end 96.49 174.371)
		(width 0.2)
		(layer "F.Cu")
		(net 76)
	)
	(via blind
		(at 96.89 167.745)
		(size 0.5)
		(drill 0.2)
		(layers "F.Cu" "In2.Cu")
		(net 76)
	)
	(via blind
		(at 92.275 117.675)
		(size 0.5)
		(drill 0.2)
		(layers "F.Cu" "In2.Cu")
		(net 76)
	)
	(segment
		(start 96.89 167.745)
		(end 92.373356 167.745)
		(width 0.15)
		(layer "In2.Cu")
		(net 76)
	)
	(segment
		(start 86.78495 162.156594)
		(end 86.78495 121.76505)
		(width 0.15)
		(layer "In2.Cu")
		(net 76)
	)
	(segment
		(start 91.67556 118.27444)
		(end 92.275 117.675)
		(width 0.15)
		(layer "In2.Cu")
		(net 76)
	)
	(segment
		(start 92.373356 167.745)
		(end 86.78495 162.156594)
		(width 0.15)
		(layer "In2.Cu")
		(net 76)
	)
	(segment
		(start 90.27556 118.27444)
		(end 91.67556 118.27444)
		(width 0.15)
		(layer "In2.Cu")
		(net 76)
	)
	(segment
		(start 86.78495 121.76505)
		(end 90.27556 118.27444)
		(width 0.15)
		(layer "In2.Cu")
		(net 76)
	)
	(segment
		(start 96.998 173.355)
		(end 97.49 172.863)
		(width 0.2)
		(layer "F.Cu")
		(net 77)
	)
	(segment
		(start 97.49 174.609)
		(end 96.998 174.117)
		(width 0.2)
		(layer "F.Cu")
		(net 77)
	)
	(segment
		(start 97.49 177.155)
		(end 97.49 174.609)
		(width 0.2)
		(layer "F.Cu")
		(net 77)
	)
	(segment
		(start 97.49 172.863)
		(end 97.49 167.345)
		(width 0.2)
		(layer "F.Cu")
		(net 77)
	)
	(segment
		(start 96.998 174.117)
		(end 96.998 173.355)
		(width 0.2)
		(layer "F.Cu")
		(net 77)
	)
	(segment
		(start 90.775 117.175)
		(end 90.099979 117.850021)
		(width 0.15)
		(layer "F.Cu")
		(net 77)
	)
	(segment
		(start 90.099979 117.850021)
		(end 89.575 117.850021)
		(width 0.15)
		(layer "F.Cu")
		(net 77)
	)
	(via blind
		(at 97.49 167.345)
		(size 0.5)
		(drill 0.2)
		(layers "F.Cu" "In2.Cu")
		(net 77)
	)
	(via blind
		(at 89.575 117.850021)
		(size 0.5)
		(drill 0.2)
		(layers "F.Cu" "In2.Cu")
		(net 77)
	)
	(segment
		(start 89.575 118.328553)
		(end 89.575 117.850021)
		(width 0.15)
		(layer "In2.Cu")
		(net 77)
	)
	(segment
		(start 86.48494 162.280862)
		(end 86.48494 121.418613)
		(width 0.15)
		(layer "In2.Cu")
		(net 77)
	)
	(segment
		(start 97.49 167.944001)
		(end 97.214 168.220001)
		(width 0.15)
		(layer "In2.Cu")
		(net 77)
	)
	(segment
		(start 92.424079 168.220001)
		(end 86.48494 162.280862)
		(width 0.15)
		(layer "In2.Cu")
		(net 77)
	)
	(segment
		(start 97.49 167.345)
		(end 97.49 167.944001)
		(width 0.15)
		(layer "In2.Cu")
		(net 77)
	)
	(segment
		(start 86.48494 121.418613)
		(end 89.575 118.328553)
		(width 0.15)
		(layer "In2.Cu")
		(net 77)
	)
	(segment
		(start 97.214 168.220001)
		(end 92.424079 168.220001)
		(width 0.15)
		(layer "In2.Cu")
		(net 77)
	)
	(segment
		(start 90.525001 118.424999)
		(end 89.319907 118.424999)
		(width 0.15)
		(layer "F.Cu")
		(net 78)
	)
	(segment
		(start 98.09 167.745)
		(end 98.09 177.345)
		(width 0.2)
		(layer "F.Cu")
		(net 78)
	)
	(segment
		(start 90.775 118.175)
		(end 90.525001 118.424999)
		(width 0.15)
		(layer "F.Cu")
		(net 78)
	)
	(segment
		(start 89.319907 118.424999)
		(end 89.071914 118.177006)
		(width 0.15)
		(layer "F.Cu")
		(net 78)
	)
	(via blind
		(at 89.071914 118.177006)
		(size 0.5)
		(drill 0.2)
		(layers "F.Cu" "In2.Cu")
		(net 78)
	)
	(via blind
		(at 98.09 167.745)
		(size 0.5)
		(drill 0.2)
		(layers "F.Cu" "In2.Cu")
		(net 78)
	)
	(segment
		(start 92.29981 168.52001)
		(end 86.18493 162.40513)
		(width 0.15)
		(layer "In2.Cu")
		(net 78)
	)
	(segment
		(start 86.18493 162.40513)
		(end 86.18493 121.06399)
		(width 0.15)
		(layer "In2.Cu")
		(net 78)
	)
	(segment
		(start 86.18493 121.06399)
		(end 89.071914 118.177006)
		(width 0.15)
		(layer "In2.Cu")
		(net 78)
	)
	(segment
		(start 98.09 167.745)
		(end 98.09 168.24)
		(width 0.15)
		(layer "In2.Cu")
		(net 78)
	)
	(segment
		(start 98.09 168.24)
		(end 97.80999 168.52001)
		(width 0.15)
		(layer "In2.Cu")
		(net 78)
	)
	(segment
		(start 97.80999 168.52001)
		(end 92.29981 168.52001)
		(width 0.15)
		(layer "In2.Cu")
		(net 78)
	)
	(segment
		(start 98.69 177.345)
		(end 98.69 168.24)
		(width 0.2)
		(layer "F.Cu")
		(net 79)
	)
	(segment
		(start 93.775 117.175)
		(end 94.275 117.675)
		(width 0.15)
		(layer "F.Cu")
		(net 79)
	)
	(via blind
		(at 94.275 117.675)
		(size 0.5)
		(drill 0.2)
		(layers "F.Cu" "In2.Cu")
		(net 79)
	)
	(via blind
		(at 98.69 168.24)
		(size 0.5)
		(drill 0.2)
		(layers "F.Cu" "In2.Cu")
		(net 79)
	)
	(segment
		(start 85.88492 120.66508)
		(end 85.88492 162.529398)
		(width 0.15)
		(layer "In2.Cu")
		(net 79)
	)
	(segment
		(start 93.775 117.175)
		(end 94.275 117.675)
		(width 0.15)
		(layer "In2.Cu")
		(net 79)
	)
	(segment
		(start 98.109981 168.820019)
		(end 98.69 168.24)
		(width 0.15)
		(layer "In2.Cu")
		(net 79)
	)
	(segment
		(start 89.124989 117.425011)
		(end 85.88492 120.66508)
		(width 0.15)
		(layer "In2.Cu")
		(net 79)
	)
	(segment
		(start 92.175541 168.820019)
		(end 98.109981 168.820019)
		(width 0.15)
		(layer "In2.Cu")
		(net 79)
	)
	(segment
		(start 92.145998 117.175)
		(end 93.775 117.175)
		(width 0.15)
		(layer "In2.Cu")
		(net 79)
	)
	(segment
		(start 92.145998 117.175)
		(end 91.895987 117.425011)
		(width 0.15)
		(layer "In2.Cu")
		(net 79)
	)
	(segment
		(start 85.88492 162.529398)
		(end 92.175541 168.820019)
		(width 0.15)
		(layer "In2.Cu")
		(net 79)
	)
	(segment
		(start 91.895987 117.425011)
		(end 89.124989 117.425011)
		(width 0.15)
		(layer "In2.Cu")
		(net 79)
	)
	(segment
		(start 99.734001 174.111499)
		(end 99.734001 173.360501)
		(width 0.2)
		(layer "F.Cu")
		(net 80)
	)
	(segment
		(start 99.29 174.5555)
		(end 99.734001 174.111499)
		(width 0.2)
		(layer "F.Cu")
		(net 80)
	)
	(segment
		(start 99.29 177.155)
		(end 99.29 174.5555)
		(width 0.2)
		(layer "F.Cu")
		(net 80)
	)
	(segment
		(start 94.775 117.175)
		(end 94.275 116.675)
		(width 0.15)
		(layer "F.Cu")
		(net 80)
	)
	(segment
		(start 99.29 172.9165)
		(end 99.29 168.615)
		(width 0.2)
		(layer "F.Cu")
		(net 80)
	)
	(segment
		(start 99.734001 173.360501)
		(end 99.29 172.9165)
		(width 0.2)
		(layer "F.Cu")
		(net 80)
	)
	(via blind
		(at 94.275 116.675)
		(size 0.5)
		(drill 0.2)
		(layers "F.Cu" "In2.Cu")
		(net 80)
	)
	(via blind
		(at 99.29 168.615)
		(size 0.5)
		(drill 0.2)
		(layers "F.Cu" "In2.Cu")
		(net 80)
	)
	(segment
		(start 91.675 117.175)
		(end 88.899278 117.175)
		(width 0.15)
		(layer "In2.Cu")
		(net 80)
	)
	(segment
		(start 98.784974 169.120026)
		(end 99.29 168.615)
		(width 0.15)
		(layer "In2.Cu")
		(net 80)
	)
	(segment
		(start 94.275 116.675)
		(end 92.175 116.675)
		(width 0.15)
		(layer "In2.Cu")
		(net 80)
	)
	(segment
		(start 85.584911 162.653667)
		(end 92.05127 169.120026)
		(width 0.15)
		(layer "In2.Cu")
		(net 80)
	)
	(segment
		(start 92.05127 169.120026)
		(end 98.784974 169.120026)
		(width 0.15)
		(layer "In2.Cu")
		(net 80)
	)
	(segment
		(start 92.175 116.675)
		(end 91.675 117.175)
		(width 0.15)
		(layer "In2.Cu")
		(net 80)
	)
	(segment
		(start 85.584911 120.489367)
		(end 85.584911 162.653667)
		(width 0.15)
		(layer "In2.Cu")
		(net 80)
	)
	(segment
		(start 88.899278 117.175)
		(end 85.584911 120.489367)
		(width 0.15)
		(layer "In2.Cu")
		(net 80)
	)
	(segment
		(start 99.89 174.654)
		(end 100.3 174.244)
		(width 0.2)
		(layer "F.Cu")
		(net 81)
	)
	(segment
		(start 92.775 116.175)
		(end 92.275 115.675)
		(width 0.15)
		(layer "F.Cu")
		(net 81)
	)
	(segment
		(start 99.89 177.155)
		(end 99.89 174.654)
		(width 0.2)
		(layer "F.Cu")
		(net 81)
	)
	(segment
		(start 100.3 173.101)
		(end 99.89 172.691)
		(width 0.2)
		(layer "F.Cu")
		(net 81)
	)
	(segment
		(start 99.89 172.691)
		(end 99.89 169.07)
		(width 0.2)
		(layer "F.Cu")
		(net 81)
	)
	(segment
		(start 100.3 174.244)
		(end 100.3 173.101)
		(width 0.2)
		(layer "F.Cu")
		(net 81)
	)
	(via blind
		(at 92.275 115.675)
		(size 0.5)
		(drill 0.2)
		(layers "F.Cu" "In2.Cu")
		(net 81)
	)
	(via blind
		(at 99.89 169.07)
		(size 0.5)
		(drill 0.2)
		(layers "F.Cu" "In2.Cu")
		(net 81)
	)
	(segment
		(start 85.2849 120.3651)
		(end 85.2849 162.777934)
		(width 0.15)
		(layer "In2.Cu")
		(net 81)
	)
	(segment
		(start 92.275 115.675)
		(end 91.775 116.175)
		(width 0.15)
		(layer "In2.Cu")
		(net 81)
	)
	(segment
		(start 85.2849 162.777934)
		(end 91.927003 169.420037)
		(width 0.15)
		(layer "In2.Cu")
		(net 81)
	)
	(segment
		(start 89.475 116.175)
		(end 85.2849 120.3651)
		(width 0.15)
		(layer "In2.Cu")
		(net 81)
	)
	(segment
		(start 91.775 116.175)
		(end 89.475 116.175)
		(width 0.15)
		(layer "In2.Cu")
		(net 81)
	)
	(segment
		(start 99.539963 169.420037)
		(end 99.89 169.07)
		(width 0.15)
		(layer "In2.Cu")
		(net 81)
	)
	(segment
		(start 91.927003 169.420037)
		(end 99.539963 169.420037)
		(width 0.15)
		(layer "In2.Cu")
		(net 81)
	)
	(segment
		(start 100.49 172.402)
		(end 100.49 169.515)
		(width 0.2)
		(layer "F.Cu")
		(net 82)
	)
	(segment
		(start 100.49 177.155)
		(end 100.49 174.816)
		(width 0.2)
		(layer "F.Cu")
		(net 82)
	)
	(segment
		(start 100.935 172.847)
		(end 100.49 172.402)
		(width 0.2)
		(layer "F.Cu")
		(net 82)
	)
	(segment
		(start 100.935 174.371)
		(end 100.935 172.847)
		(width 0.2)
		(layer "F.Cu")
		(net 82)
	)
	(segment
		(start 100.49 174.816)
		(end 100.935 174.371)
		(width 0.2)
		(layer "F.Cu")
		(net 82)
	)
	(segment
		(start 90.775 116.175)
		(end 88.775 116.175)
		(width 0.15)
		(layer "F.Cu")
		(net 82)
	)
	(via blind
		(at 88.775 116.175)
		(size 0.5)
		(drill 0.2)
		(layers "F.Cu" "In2.Cu")
		(net 82)
	)
	(via blind
		(at 100.49 169.515)
		(size 0.5)
		(drill 0.2)
		(layers "F.Cu" "In2.Cu")
		(net 82)
	)
	(segment
		(start 100.240001 169.764999)
		(end 100.49 169.515)
		(width 0.15)
		(layer "In2.Cu")
		(net 82)
	)
	(segment
		(start 84.98489 119.96511)
		(end 84.98489 162.902202)
		(width 0.15)
		(layer "In2.Cu")
		(net 82)
	)
	(segment
		(start 84.98489 162.902202)
		(end 91.847687 169.764999)
		(width 0.15)
		(layer "In2.Cu")
		(net 82)
	)
	(segment
		(start 88.775 116.175)
		(end 84.98489 119.96511)
		(width 0.15)
		(layer "In2.Cu")
		(net 82)
	)
	(segment
		(start 91.847687 169.764999)
		(end 100.240001 169.764999)
		(width 0.15)
		(layer "In2.Cu")
		(net 82)
	)
	(segment
		(start 101.57 174.625)
		(end 101.57 172.339)
		(width 0.2)
		(layer "F.Cu")
		(net 83)
	)
	(segment
		(start 91.775 116.175)
		(end 91.275 115.675)
		(width 0.15)
		(layer "F.Cu")
		(net 83)
	)
	(segment
		(start 101.09 177.155)
		(end 101.09 175.105)
		(width 0.2)
		(layer "F.Cu")
		(net 83)
	)
	(segment
		(start 101.57 172.339)
		(end 101.09 171.859)
		(width 0.2)
		(layer "F.Cu")
		(net 83)
	)
	(segment
		(start 101.09 171.859)
		(end 101.09 170.065)
		(width 0.2)
		(layer "F.Cu")
		(net 83)
	)
	(segment
		(start 101.09 175.105)
		(end 101.57 174.625)
		(width 0.2)
		(layer "F.Cu")
		(net 83)
	)
	(via blind
		(at 101.09 170.065)
		(size 0.5)
		(drill 0.2)
		(layers "F.Cu" "In2.Cu")
		(net 83)
	)
	(via blind
		(at 91.275 115.675)
		(size 0.5)
		(drill 0.2)
		(layers "F.Cu" "In2.Cu")
		(net 83)
	)
	(segment
		(start 88.599278 115.675)
		(end 84.68488 119.589398)
		(width 0.15)
		(layer "In2.Cu")
		(net 83)
	)
	(segment
		(start 91.72341 170.065)
		(end 101.09 170.065)
		(width 0.15)
		(layer "In2.Cu")
		(net 83)
	)
	(segment
		(start 84.68488 163.02647)
		(end 91.72341 170.065)
		(width 0.15)
		(layer "In2.Cu")
		(net 83)
	)
	(segment
		(start 84.68488 119.589398)
		(end 84.68488 163.02647)
		(width 0.15)
		(layer "In2.Cu")
		(net 83)
	)
	(segment
		(start 91.275 115.675)
		(end 88.599278 115.675)
		(width 0.15)
		(layer "In2.Cu")
		(net 83)
	)
	(segment
		(start 102.29 177.345)
		(end 102.29 166.88)
		(width 0.2)
		(layer "F.Cu")
		(net 84)
	)
	(segment
		(start 102.29 166.88)
		(end 104.055 165.115)
		(width 0.2)
		(layer "F.Cu")
		(net 84)
	)
	(segment
		(start 104.055 165.115)
		(end 104.055 164.055)
		(width 0.2)
		(layer "F.Cu")
		(net 84)
	)
	(segment
		(start 102.89 166.88)
		(end 105.705 164.065)
		(width 0.2)
		(layer "F.Cu")
		(net 85)
	)
	(segment
		(start 102.89 177.345)
		(end 102.89 166.88)
		(width 0.2)
		(layer "F.Cu")
		(net 85)
	)
	(segment
		(start 106.89 177.345)
		(end 106.89 168.291)
		(width 0.15)
		(layer "F.Cu")
		(net 86)
	)
	(segment
		(start 107.775 126.175)
		(end 108.275 126.675)
		(width 0.15)
		(layer "F.Cu")
		(net 86)
	)
	(via blind
		(at 106.924013 168.275)
		(size 0.5)
		(drill 0.2)
		(layers "F.Cu" "In5.Cu")
		(net 86)
	)
	(via blind
		(at 108.275 126.675)
		(size 0.5)
		(drill 0.2)
		(layers "F.Cu" "In5.Cu")
		(net 86)
	)
	(segment
		(start 108.674 164.075)
		(end 108.674 128.275)
		(width 0.15)
		(layer "In5.Cu")
		(net 86)
	)
	(segment
		(start 106.924013 165.824987)
		(end 108.674 164.075)
		(width 0.15)
		(layer "In5.Cu")
		(net 86)
	)
	(segment
		(start 108.275 127.876)
		(end 108.275 126.675)
		(width 0.15)
		(layer "In5.Cu")
		(net 86)
	)
	(segment
		(start 106.924013 168.275)
		(end 106.924013 165.824987)
		(width 0.15)
		(layer "In5.Cu")
		(net 86)
	)
	(segment
		(start 108.674 128.275)
		(end 108.275 127.876)
		(width 0.15)
		(layer "In5.Cu")
		(net 86)
	)
	(segment
		(start 109.374 167.16)
		(end 108.189 167.16)
		(width 0.15)
		(layer "F.Cu")
		(net 87)
	)
	(segment
		(start 107.49 177.345)
		(end 107.49 168.291)
		(width 0.15)
		(layer "F.Cu")
		(net 87)
	)
	(segment
		(start 108.775 126.175)
		(end 109.275 126.675)
		(width 0.15)
		(layer "F.Cu")
		(net 87)
	)
	(segment
		(start 107.574026 167.774974)
		(end 107.574026 168.275)
		(width 0.15)
		(layer "F.Cu")
		(net 87)
	)
	(segment
		(start 108.189 167.16)
		(end 107.574026 167.774974)
		(width 0.15)
		(layer "F.Cu")
		(net 87)
	)
	(via blind
		(at 109.275 126.675)
		(size 0.5)
		(drill 0.2)
		(layers "F.Cu" "In5.Cu")
		(net 87)
	)
	(via blind
		(at 107.574026 168.275)
		(size 0.5)
		(drill 0.2)
		(layers "F.Cu" "In5.Cu")
		(net 87)
	)
	(segment
		(start 108.774 127.950011)
		(end 108.774 127.175)
		(width 0.15)
		(layer "In5.Cu")
		(net 87)
	)
	(segment
		(start 108.974 128.150011)
		(end 108.774 127.950011)
		(width 0.15)
		(layer "In5.Cu")
		(net 87)
	)
	(segment
		(start 107.574026 165.599252)
		(end 107.574026 168.275)
		(width 0.15)
		(layer "In5.Cu")
		(net 87)
	)
	(segment
		(start 108.974 164.175)
		(end 108.974 128.150011)
		(width 0.15)
		(layer "In5.Cu")
		(net 87)
	)
	(segment
		(start 108.775 127.175)
		(end 109.275 126.675)
		(width 0.15)
		(layer "In5.Cu")
		(net 87)
	)
	(segment
		(start 107.574026 165.599252)
		(end 108.97399 164.199288)
		(width 0.15)
		(layer "In5.Cu")
		(net 87)
	)
	(segment
		(start 108.774 127.175)
		(end 108.775 127.175)
		(width 0.15)
		(layer "In5.Cu")
		(net 87)
	)
	(segment
		(start 108.09 177.345)
		(end 108.09 168.291)
		(width 0.15)
		(layer "F.Cu")
		(net 88)
	)
	(segment
		(start 108.775 127.175)
		(end 109.275 127.675)
		(width 0.15)
		(layer "F.Cu")
		(net 88)
	)
	(via blind
		(at 108.224039 168.275)
		(size 0.5)
		(drill 0.2)
		(layers "F.Cu" "In5.Cu")
		(net 88)
	)
	(via blind
		(at 109.275 127.675)
		(size 0.5)
		(drill 0.2)
		(layers "F.Cu" "In5.Cu")
		(net 88)
	)
	(segment
		(start 108.224039 165.424961)
		(end 108.224039 168.275)
		(width 0.15)
		(layer "In5.Cu")
		(net 88)
	)
	(segment
		(start 109.274 164.375)
		(end 108.224039 165.424961)
		(width 0.15)
		(layer "In5.Cu")
		(net 88)
	)
	(segment
		(start 109.275 127.675)
		(end 109.274 127.676)
		(width 0.15)
		(layer "In5.Cu")
		(net 88)
	)
	(segment
		(start 109.274 127.676)
		(end 109.274 164.375)
		(width 0.15)
		(layer "In5.Cu")
		(net 88)
	)
	(segment
		(start 107.775 124.175)
		(end 108.275 124.675)
		(width 0.15)
		(layer "F.Cu")
		(net 89)
	)
	(segment
		(start 108.69 177.345)
		(end 108.69 168.459052)
		(width 0.15)
		(layer "F.Cu")
		(net 89)
	)
	(segment
		(start 108.69 168.459052)
		(end 108.874052 168.275)
		(width 0.15)
		(layer "F.Cu")
		(net 89)
	)
	(via blind
		(at 108.275 124.675)
		(size 0.5)
		(drill 0.2)
		(layers "F.Cu" "In5.Cu")
		(net 89)
	)
	(via blind
		(at 108.874052 168.275)
		(size 0.5)
		(drill 0.2)
		(layers "F.Cu" "In5.Cu")
		(net 89)
	)
	(segment
		(start 109.574 128.375)
		(end 109.774 128.175)
		(width 0.15)
		(layer "In5.Cu")
		(net 89)
	)
	(segment
		(start 109.574 164.575)
		(end 108.874 165.275)
		(width 0.15)
		(layer "In5.Cu")
		(net 89)
	)
	(segment
		(start 109.574 164.575)
		(end 109.574 128.375)
		(width 0.15)
		(layer "In5.Cu")
		(net 89)
	)
	(segment
		(start 109.774 128.175)
		(end 109.774 126.174)
		(width 0.15)
		(layer "In5.Cu")
		(net 89)
	)
	(segment
		(start 108.874 168.274948)
		(end 108.874052 168.275)
		(width 0.15)
		(layer "In5.Cu")
		(net 89)
	)
	(segment
		(start 108.874 165.275)
		(end 108.874 168.274948)
		(width 0.15)
		(layer "In5.Cu")
		(net 89)
	)
	(segment
		(start 109.774 126.174)
		(end 108.275 124.675)
		(width 0.15)
		(layer "In5.Cu")
		(net 89)
	)
	(segment
		(start 109.89 177.345)
		(end 109.89 168.291)
		(width 0.15)
		(layer "F.Cu")
		(net 90)
	)
	(segment
		(start 109.775 125.175)
		(end 110.275 125.675)
		(width 0.15)
		(layer "F.Cu")
		(net 90)
	)
	(via blind
		(at 109.874 168.275)
		(size 0.5)
		(drill 0.2)
		(layers "F.Cu" "In5.Cu")
		(net 90)
	)
	(via blind
		(at 110.275 125.675)
		(size 0.5)
		(drill 0.2)
		(layers "F.Cu" "In5.Cu")
		(net 90)
	)
	(segment
		(start 109.624001 165.415985)
		(end 109.624001 168.025001)
		(width 0.15)
		(layer "In5.Cu")
		(net 90)
	)
	(segment
		(start 109.874 128.499278)
		(end 110.275 128.098278)
		(width 0.15)
		(layer "In5.Cu")
		(net 90)
	)
	(segment
		(start 110.275 128.098278)
		(end 110.275 125.675)
		(width 0.15)
		(layer "In5.Cu")
		(net 90)
	)
	(segment
		(start 109.874 165.165986)
		(end 109.874 128.499278)
		(width 0.15)
		(layer "In5.Cu")
		(net 90)
	)
	(segment
		(start 109.874 165.165986)
		(end 109.624001 165.415985)
		(width 0.15)
		(layer "In5.Cu")
		(net 90)
	)
	(segment
		(start 109.624001 168.025001)
		(end 109.874 168.275)
		(width 0.15)
		(layer "In5.Cu")
		(net 90)
	)
	(segment
		(start 110.474 166.19)
		(end 110.154 166.19)
		(width 0.15)
		(layer "F.Cu")
		(net 91)
	)
	(segment
		(start 110.09399 166.12999)
		(end 110.09399 165.575)
		(width 0.15)
		(layer "F.Cu")
		(net 91)
	)
	(segment
		(start 109.775 124.175)
		(end 110.275 124.675)
		(width 0.15)
		(layer "F.Cu")
		(net 91)
	)
	(segment
		(start 109.374 166.19)
		(end 110.474 166.19)
		(width 0.15)
		(layer "F.Cu")
		(net 91)
	)
	(segment
		(start 110.154 166.19)
		(end 110.09399 166.12999)
		(width 0.15)
		(layer "F.Cu")
		(net 91)
	)
	(via blind
		(at 110.09399 165.575)
		(size 0.5)
		(drill 0.2)
		(layers "F.Cu" "In5.Cu")
		(net 91)
	)
	(via blind
		(at 110.275 124.675)
		(size 0.5)
		(drill 0.2)
		(layers "F.Cu" "In5.Cu")
		(net 91)
	)
	(segment
		(start 110.774 128.023556)
		(end 110.19399 128.603566)
		(width 0.15)
		(layer "In5.Cu")
		(net 91)
	)
	(segment
		(start 110.774 125.174)
		(end 110.275 124.675)
		(width 0.15)
		(layer "In5.Cu")
		(net 91)
	)
	(segment
		(start 110.19399 128.603566)
		(end 110.19399 165.475)
		(width 0.15)
		(layer "In5.Cu")
		(net 91)
	)
	(segment
		(start 110.774 125.174)
		(end 110.774 128.023556)
		(width 0.15)
		(layer "In5.Cu")
		(net 91)
	)
	(segment
		(start 110.19399 165.475)
		(end 110.09399 165.575)
		(width 0.15)
		(layer "In5.Cu")
		(net 91)
	)
	(segment
		(start 109.775 123.175)
		(end 110.275 123.675)
		(width 0.15)
		(layer "F.Cu")
		(net 92)
	)
	(segment
		(start 111.09 177.345)
		(end 111.09 168.291026)
		(width 0.15)
		(layer "F.Cu")
		(net 92)
	)
	(segment
		(start 111.09 168.291026)
		(end 111.073974 168.275)
		(width 0.15)
		(layer "F.Cu")
		(net 92)
	)
	(via blind
		(at 110.275 123.675)
		(size 0.5)
		(drill 0.2)
		(layers "F.Cu" "In5.Cu")
		(net 92)
	)
	(via blind
		(at 111.073974 168.275)
		(size 0.5)
		(drill 0.2)
		(layers "F.Cu" "In5.Cu")
		(net 92)
	)
	(segment
		(start 111.073974 168.275)
		(end 110.519 167.720026)
		(width 0.15)
		(layer "In5.Cu")
		(net 92)
	)
	(segment
		(start 110.519 167.720026)
		(end 110.519 128.677)
		(width 0.15)
		(layer "In5.Cu")
		(net 92)
	)
	(segment
		(start 110.519 128.677)
		(end 111.074 128.122)
		(width 0.15)
		(layer "In5.Cu")
		(net 92)
	)
	(segment
		(start 111.074 128.122)
		(end 111.074 124.827553)
		(width 0.15)
		(layer "In5.Cu")
		(net 92)
	)
	(segment
		(start 111.074 124.827553)
		(end 110.275 124.028553)
		(width 0.15)
		(layer "In5.Cu")
		(net 92)
	)
	(segment
		(start 110.275 124.028553)
		(end 110.275 123.675)
		(width 0.15)
		(layer "In5.Cu")
		(net 92)
	)
	(segment
		(start 111.69 168.591)
		(end 111.69 168.291013)
		(width 0.15)
		(layer "F.Cu")
		(net 93)
	)
	(segment
		(start 111.69 168.291013)
		(end 111.673987 168.275)
		(width 0.15)
		(layer "F.Cu")
		(net 93)
	)
	(segment
		(start 109.775 122.175)
		(end 110.275 122.675)
		(width 0.15)
		(layer "F.Cu")
		(net 93)
	)
	(segment
		(start 111.69 177.345)
		(end 111.69 168.591)
		(width 0.15)
		(layer "F.Cu")
		(net 93)
	)
	(segment
		(start 111.69 168.591)
		(end 111.69 168.410986)
		(width 0.15)
		(layer "F.Cu")
		(net 93)
	)
	(via blind
		(at 111.673987 168.275)
		(size 0.5)
		(drill 0.2)
		(layers "F.Cu" "In5.Cu")
		(net 93)
	)
	(via blind
		(at 110.275 122.675)
		(size 0.5)
		(drill 0.2)
		(layers "F.Cu" "In5.Cu")
		(net 93)
	)
	(segment
		(start 111.673987 167.921447)
		(end 111.673987 168.275)
		(width 0.15)
		(layer "In5.Cu")
		(net 93)
	)
	(segment
		(start 110.819 167.06646)
		(end 111.673987 167.921447)
		(width 0.15)
		(layer "In5.Cu")
		(net 93)
	)
	(segment
		(start 110.725 124.075)
		(end 111.37401 124.72401)
		(width 0.15)
		(layer "In5.Cu")
		(net 93)
	)
	(segment
		(start 111.37401 124.72401)
		(end 111.37401 128.214854)
		(width 0.15)
		(layer "In5.Cu")
		(net 93)
	)
	(segment
		(start 110.725 123.125)
		(end 110.725 124.075)
		(width 0.15)
		(layer "In5.Cu")
		(net 93)
	)
	(segment
		(start 110.819 128.769864)
		(end 110.819 167.06646)
		(width 0.15)
		(layer "In5.Cu")
		(net 93)
	)
	(segment
		(start 111.37401 128.214854)
		(end 110.819 128.769864)
		(width 0.15)
		(layer "In5.Cu")
		(net 93)
	)
	(segment
		(start 110.275 122.675)
		(end 110.725 123.125)
		(width 0.15)
		(layer "In5.Cu")
		(net 93)
	)
	(segment
		(start 106.775 126.175)
		(end 106.275 125.675)
		(width 0.15)
		(layer "F.Cu")
		(net 94)
	)
	(segment
		(start 112.89 177.345)
		(end 112.89 171.055)
		(width 0.15)
		(layer "F.Cu")
		(net 94)
	)
	(segment
		(start 114.7 169.245)
		(end 114.7 168.267143)
		(width 0.15)
		(layer "F.Cu")
		(net 94)
	)
	(segment
		(start 114.7 168.267143)
		(end 114.723257 168.243886)
		(width 0.15)
		(layer "F.Cu")
		(net 94)
	)
	(segment
		(start 112.89 171.055)
		(end 114.7 169.245)
		(width 0.15)
		(layer "F.Cu")
		(net 94)
	)
	(via blind
		(at 106.275 125.675)
		(size 0.5)
		(drill 0.2)
		(layers "F.Cu" "In5.Cu")
		(net 94)
	)
	(via blind
		(at 114.723257 168.243886)
		(size 0.5)
		(drill 0.2)
		(layers "F.Cu" "In5.Cu")
		(net 94)
	)
	(segment
		(start 113.519001 129.123433)
		(end 113.519 156.877)
		(width 0.15)
		(layer "In5.Cu")
		(net 94)
	)
	(segment
		(start 112.87406 128.478492)
		(end 113.519001 129.123433)
		(width 0.15)
		(layer "In5.Cu")
		(net 94)
	)
	(segment
		(start 112.87406 163.510911)
		(end 114.723257 165.360108)
		(width 0.15)
		(layer "In5.Cu")
		(net 94)
	)
	(segment
		(start 107.225 123.825)
		(end 106.775 124.275)
		(width 0.2)
		(layer "In5.Cu")
		(net 94)
	)
	(segment
		(start 108.725 119.725)
		(end 110.935917 119.725)
		(width 0.15)
		(layer "In5.Cu")
		(net 94)
	)
	(segment
		(start 106.775 124.275)
		(end 106.775 125.175)
		(width 0.2)
		(layer "In5.Cu")
		(net 94)
	)
	(segment
		(start 113.519 156.877)
		(end 112.87406 157.52194)
		(width 0.15)
		(layer "In5.Cu")
		(net 94)
	)
	(segment
		(start 106.775 125.175)
		(end 106.275 125.675)
		(width 0.2)
		(layer "In5.Cu")
		(net 94)
	)
	(segment
		(start 107.575 123.475)
		(end 107.575 120.875)
		(width 0.15)
		(layer "In5.Cu")
		(net 94)
	)
	(segment
		(start 112.87406 157.52194)
		(end 112.87406 163.510911)
		(width 0.15)
		(layer "In5.Cu")
		(net 94)
	)
	(segment
		(start 110.935917 119.725)
		(end 112.87406 121.663143)
		(width 0.15)
		(layer "In5.Cu")
		(net 94)
	)
	(segment
		(start 107.225 123.825)
		(end 107.575 123.475)
		(width 0.15)
		(layer "In5.Cu")
		(net 94)
	)
	(segment
		(start 114.723257 165.360108)
		(end 114.723257 168.243886)
		(width 0.15)
		(layer "In5.Cu")
		(net 94)
	)
	(segment
		(start 107.575 120.875)
		(end 108.725 119.725)
		(width 0.15)
		(layer "In5.Cu")
		(net 94)
	)
	(segment
		(start 112.87406 121.663143)
		(end 112.87406 128.478492)
		(width 0.15)
		(layer "In5.Cu")
		(net 94)
	)
	(segment
		(start 113.49 170.955)
		(end 115.2 169.245)
		(width 0.15)
		(layer "F.Cu")
		(net 95)
	)
	(segment
		(start 113.49 177.345)
		(end 113.49 170.955)
		(width 0.15)
		(layer "F.Cu")
		(net 95)
	)
	(segment
		(start 106.775 124.175)
		(end 106.275 123.675)
		(width 0.15)
		(layer "F.Cu")
		(net 95)
	)
	(segment
		(start 115.2 169.245)
		(end 115.2 168.745)
		(width 0.15)
		(layer "F.Cu")
		(net 95)
	)
	(via blind
		(at 106.275 123.675)
		(size 0.5)
		(drill 0.2)
		(layers "F.Cu" "In5.Cu")
		(net 95)
	)
	(via blind
		(at 115.2 168.745)
		(size 0.5)
		(drill 0.2)
		(layers "F.Cu" "In5.Cu")
		(net 95)
	)
	(segment
		(start 107.275 120.821432)
		(end 107.275 122.675)
		(width 0.15)
		(layer "In5.Cu")
		(net 95)
	)
	(segment
		(start 113.819 129.069864)
		(end 113.17407 128.424934)
		(width 0.15)
		(layer "In5.Cu")
		(net 95)
	)
	(segment
		(start 115.2 168.745)
		(end 115.2 165.345)
		(width 0.15)
		(layer "In5.Cu")
		(net 95)
	)
	(segment
		(start 108.621443 119.474989)
		(end 107.275 120.821432)
		(width 0.15)
		(layer "In5.Cu")
		(net 95)
	)
	(segment
		(start 113.819 157.077)
		(end 113.819 129.069864)
		(width 0.15)
		(layer "In5.Cu")
		(net 95)
	)
	(segment
		(start 111.039474 119.474989)
		(end 108.621443 119.474989)
		(width 0.15)
		(layer "In5.Cu")
		(net 95)
	)
	(segment
		(start 113.17407 128.424934)
		(end 113.17407 121.609585)
		(width 0.15)
		(layer "In5.Cu")
		(net 95)
	)
	(segment
		(start 113.17407 121.609585)
		(end 111.039474 119.474989)
		(width 0.15)
		(layer "In5.Cu")
		(net 95)
	)
	(segment
		(start 113.17407 157.72193)
		(end 113.819 157.077)
		(width 0.15)
		(layer "In5.Cu")
		(net 95)
	)
	(segment
		(start 106.275 123.675)
		(end 107.275 122.675)
		(width 0.15)
		(layer "In5.Cu")
		(net 95)
	)
	(segment
		(start 113.17407 163.31907)
		(end 113.17407 157.72193)
		(width 0.15)
		(layer "In5.Cu")
		(net 95)
	)
	(segment
		(start 115.2 165.345)
		(end 113.17407 163.31907)
		(width 0.15)
		(layer "In5.Cu")
		(net 95)
	)
	(segment
		(start 114.69 177.345)
		(end 114.69 174.060004)
		(width 0.15)
		(layer "F.Cu")
		(net 96)
	)
	(segment
		(start 69.572 155.909042)
		(end 69.565521 155.915521)
		(width 0.15)
		(layer "F.Cu")
		(net 96)
	)
	(segment
		(start 69.572 154.35712)
		(end 69.572 155.909042)
		(width 0.15)
		(layer "F.Cu")
		(net 96)
	)
	(via
		(at 69.565521 155.915521)
		(size 0.5)
		(drill 0.2)
		(layers "F.Cu" "B.Cu")
		(net 96)
	)
	(via
		(at 75.065 167.36)
		(size 0.5)
		(drill 0.2)
		(layers "F.Cu" "B.Cu")
		(net 96)
	)
	(via
		(at 114.69 174.060004)
		(size 0.5)
		(drill 0.2)
		(layers "F.Cu" "B.Cu")
		(net 96)
	)
	(segment
		(start 75.065 167.36)
		(end 75.365 167.66)
		(width 0.15)
		(layer "In2.Cu")
		(net 96)
	)
	(segment
		(start 112.48993 171.859934)
		(end 114.69 174.060004)
		(width 0.15)
		(layer "In2.Cu")
		(net 96)
	)
	(segment
		(start 75.365 167.66)
		(end 75.365 168.115)
		(width 0.15)
		(layer "In2.Cu")
		(net 96)
	)
	(segment
		(start 88.686932 171.849934)
		(end 92.815608 171.849934)
		(width 0.15)
		(layer "In2.Cu")
		(net 96)
	)
	(segment
		(start 75.365 168.115)
		(end 76.915001 169.665001)
		(width 0.15)
		(layer "In2.Cu")
		(net 96)
	)
	(segment
		(start 92.825608 171.859934)
		(end 112.48993 171.859934)
		(width 0.15)
		(layer "In2.Cu")
		(net 96)
	)
	(segment
		(start 76.915001 169.665001)
		(end 86.501999 169.665001)
		(width 0.15)
		(layer "In2.Cu")
		(net 96)
	)
	(segment
		(start 92.815608 171.849934)
		(end 92.825608 171.859934)
		(width 0.15)
		(layer "In2.Cu")
		(net 96)
	)
	(segment
		(start 86.501999 169.665001)
		(end 88.686932 171.849934)
		(width 0.15)
		(layer "In2.Cu")
		(net 96)
	)
	(segment
		(start 69.565521 155.915521)
		(end 69.565521 157.864479)
		(width 0.15)
		(layer "In5.Cu")
		(net 96)
	)
	(segment
		(start 69.565521 157.864479)
		(end 69.164999 158.265001)
		(width 0.15)
		(layer "In5.Cu")
		(net 96)
	)
	(segment
		(start 73.06 167.36)
		(end 75.065 167.36)
		(width 0.15)
		(layer "In5.Cu")
		(net 96)
	)
	(segment
		(start 69.164999 163.464999)
		(end 73.06 167.36)
		(width 0.15)
		(layer "In5.Cu")
		(net 96)
	)
	(segment
		(start 69.164999 158.265001)
		(end 69.164999 163.464999)
		(width 0.15)
		(layer "In5.Cu")
		(net 96)
	)
	(segment
		(start 119.59 177.345)
		(end 119.59 175.745)
		(width 0.2)
		(layer "F.Cu")
		(net 97)
	)
	(segment
		(start 104.775 127.175)
		(end 105.275 126.675)
		(width 0.15)
		(layer "F.Cu")
		(net 97)
	)
	(via blind
		(at 119.59 175.745)
		(size 0.5)
		(drill 0.2)
		(layers "F.Cu" "In2.Cu")
		(net 97)
	)
	(via blind
		(at 105.275 126.675)
		(size 0.5)
		(drill 0.2)
		(layers "F.Cu" "In2.Cu")
		(net 97)
	)
	(segment
		(start 119.59 169.79)
		(end 118.7 168.9)
		(width 0.15)
		(layer "In2.Cu")
		(net 97)
	)
	(segment
		(start 105.275 126.675)
		(end 104.875 127.075)
		(width 0.1)
		(layer "In2.Cu")
		(net 97)
	)
	(segment
		(start 105.175 131.075)
		(end 105.175 131.275)
		(width 0.1)
		(layer "In2.Cu")
		(net 97)
	)
	(segment
		(start 118.7 168.9)
		(end 116.199 168.9)
		(width 0.15)
		(layer "In2.Cu")
		(net 97)
	)
	(segment
		(start 104.875 127.075)
		(end 104.875 130.775)
		(width 0.1)
		(layer "In2.Cu")
		(net 97)
	)
	(segment
		(start 119.59 175.745)
		(end 119.59 169.79)
		(width 0.15)
		(layer "In2.Cu")
		(net 97)
	)
	(segment
		(start 109.875 146.275)
		(end 105.175 141.575)
		(width 0.15)
		(layer "In2.Cu")
		(net 97)
	)
	(segment
		(start 109.875 162.576)
		(end 109.875 146.275)
		(width 0.15)
		(layer "In2.Cu")
		(net 97)
	)
	(segment
		(start 104.875 130.775)
		(end 105.175 131.075)
		(width 0.1)
		(layer "In2.Cu")
		(net 97)
	)
	(segment
		(start 105.175 141.575)
		(end 105.175 131.24999)
		(width 0.15)
		(layer "In2.Cu")
		(net 97)
	)
	(segment
		(start 116.199 168.9)
		(end 109.875 162.576)
		(width 0.15)
		(layer "In2.Cu")
		(net 97)
	)
	(segment
		(start 120.19 177.345)
		(end 120.19 175.445)
		(width 0.2)
		(layer "F.Cu")
		(net 98)
	)
	(segment
		(start 104.775 129.175)
		(end 105.275 129.675)
		(width 0.15)
		(layer "F.Cu")
		(net 98)
	)
	(via blind
		(at 120.19 175.445)
		(size 0.5)
		(drill 0.2)
		(layers "F.Cu" "In2.Cu")
		(net 98)
	)
	(via blind
		(at 105.275 129.675)
		(size 0.5)
		(drill 0.2)
		(layers "F.Cu" "In2.Cu")
		(net 98)
	)
	(segment
		(start 110.175 162.376)
		(end 110.175 146.075)
		(width 0.15)
		(layer "In2.Cu")
		(net 98)
	)
	(segment
		(start 105.524999 129.924999)
		(end 105.275 129.675)
		(width 0.15)
		(layer "In2.Cu")
		(net 98)
	)
	(segment
		(start 120.19 169.79)
		(end 118.95001 168.55001)
		(width 0.15)
		(layer "In2.Cu")
		(net 98)
	)
	(segment
		(start 110.175 146.075)
		(end 105.524999 141.424999)
		(width 0.15)
		(layer "In2.Cu")
		(net 98)
	)
	(segment
		(start 105.524999 141.424999)
		(end 105.524999 129.924999)
		(width 0.15)
		(layer "In2.Cu")
		(net 98)
	)
	(segment
		(start 116.34901 168.55001)
		(end 110.175 162.376)
		(width 0.15)
		(layer "In2.Cu")
		(net 98)
	)
	(segment
		(start 118.95001 168.55001)
		(end 116.34901 168.55001)
		(width 0.15)
		(layer "In2.Cu")
		(net 98)
	)
	(segment
		(start 120.19 175.445)
		(end 120.19 169.79)
		(width 0.15)
		(layer "In2.Cu")
		(net 98)
	)
	(segment
		(start 120.79 177.345)
		(end 120.79 175.745)
		(width 0.2)
		(layer "F.Cu")
		(net 99)
	)
	(segment
		(start 104.775 128.175)
		(end 105.275 128.675)
		(width 0.15)
		(layer "F.Cu")
		(net 99)
	)
	(via blind
		(at 105.275 128.675)
		(size 0.5)
		(drill 0.2)
		(layers "F.Cu" "In2.Cu")
		(net 99)
	)
	(via blind
		(at 120.79 175.745)
		(size 0.5)
		(drill 0.2)
		(layers "F.Cu" "In2.Cu")
		(net 99)
	)
	(segment
		(start 110.475 145.875)
		(end 105.824989 141.224989)
		(width 0.15)
		(layer "In2.Cu")
		(net 99)
	)
	(segment
		(start 105.824989 141.224989)
		(end 105.824989 129.524989)
		(width 0.15)
		(layer "In2.Cu")
		(net 99)
	)
	(segment
		(start 105.515 128.915)
		(end 105.275 128.675)
		(width 0.15)
		(layer "In2.Cu")
		(net 99)
	)
	(segment
		(start 105.824989 129.524989)
		(end 105.515 129.215)
		(width 0.15)
		(layer "In2.Cu")
		(net 99)
	)
	(segment
		(start 116.449 168.2)
		(end 110.475 162.226)
		(width 0.15)
		(layer "In2.Cu")
		(net 99)
	)
	(segment
		(start 120.79 169.69)
		(end 119.3 168.2)
		(width 0.15)
		(layer "In2.Cu")
		(net 99)
	)
	(segment
		(start 119.3 168.2)
		(end 116.449 168.2)
		(width 0.15)
		(layer "In2.Cu")
		(net 99)
	)
	(segment
		(start 110.475 162.226)
		(end 110.475 145.875)
		(width 0.15)
		(layer "In2.Cu")
		(net 99)
	)
	(segment
		(start 105.515 129.215)
		(end 105.515 128.915)
		(width 0.15)
		(layer "In2.Cu")
		(net 99)
	)
	(segment
		(start 120.79 175.745)
		(end 120.79 169.69)
		(width 0.15)
		(layer "In2.Cu")
		(net 99)
	)
	(segment
		(start 105.775 127.175)
		(end 105.275 127.675)
		(width 0.15)
		(layer "F.Cu")
		(net 100)
	)
	(segment
		(start 121.39 177.345)
		(end 121.39 175.445)
		(width 0.2)
		(layer "F.Cu")
		(net 100)
	)
	(via blind
		(at 105.275 127.675)
		(size 0.5)
		(drill 0.2)
		(layers "F.Cu" "In2.Cu")
		(net 100)
	)
	(via blind
		(at 121.39 175.445)
		(size 0.5)
		(drill 0.2)
		(layers "F.Cu" "In2.Cu")
		(net 100)
	)
	(segment
		(start 116.499 167.8)
		(end 110.774 162.075)
		(width 0.15)
		(layer "In2.Cu")
		(net 100)
	)
	(segment
		(start 106.075 129.121434)
		(end 106.075 141.005352)
		(width 0.15)
		(layer "In2.Cu")
		(net 100)
	)
	(segment
		(start 121.39 175.445)
		(end 121.39 169.69)
		(width 0.15)
		(layer "In2.Cu")
		(net 100)
	)
	(segment
		(start 110.774 161.975)
		(end 110.77501 161.97601)
		(width 0.15)
		(layer "In2.Cu")
		(net 100)
	)
	(segment
		(start 121.39 169.69)
		(end 119.5 167.8)
		(width 0.15)
		(layer "In2.Cu")
		(net 100)
	)
	(segment
		(start 105.700001 128.100001)
		(end 105.700001 128.746435)
		(width 0.15)
		(layer "In2.Cu")
		(net 100)
	)
	(segment
		(start 119.5 167.8)
		(end 116.499 167.8)
		(width 0.15)
		(layer "In2.Cu")
		(net 100)
	)
	(segment
		(start 110.774 162.075)
		(end 110.774 161.975)
		(width 0.15)
		(layer "In2.Cu")
		(net 100)
	)
	(segment
		(start 105.700001 128.746435)
		(end 106.075 129.121434)
		(width 0.15)
		(layer "In2.Cu")
		(net 100)
	)
	(segment
		(start 110.775 145.705352)
		(end 110.775 162.075)
		(width 0.15)
		(layer "In2.Cu")
		(net 100)
	)
	(segment
		(start 105.275 127.675)
		(end 105.700001 128.100001)
		(width 0.15)
		(layer "In2.Cu")
		(net 100)
	)
	(segment
		(start 106.075 141.005352)
		(end 110.775 145.705352)
		(width 0.15)
		(layer "In2.Cu")
		(net 100)
	)
	(segment
		(start 105.775 128.175)
		(end 106.275 127.675)
		(width 0.15)
		(layer "F.Cu")
		(net 101)
	)
	(segment
		(start 121.99 177.345)
		(end 121.99 175.745)
		(width 0.2)
		(layer "F.Cu")
		(net 101)
	)
	(via blind
		(at 106.275 127.675)
		(size 0.5)
		(drill 0.2)
		(layers "F.Cu" "In2.Cu")
		(net 101)
	)
	(via blind
		(at 121.99 175.745)
		(size 0.5)
		(drill 0.2)
		(layers "F.Cu" "In2.Cu")
		(net 101)
	)
	(segment
		(start 106.775 129.055)
		(end 106.775 128.175)
		(width 0.15)
		(layer "In2.Cu")
		(net 101)
	)
	(segment
		(start 106.275 127.675)
		(end 106.775 128.175)
		(width 0.15)
		(layer "In2.Cu")
		(net 101)
	)
	(segment
		(start 121.99 169.64)
		(end 119.625 167.275)
		(width 0.15)
		(layer "In2.Cu")
		(net 101)
	)
	(segment
		(start 106.32501 140.82501)
		(end 106.32501 129.50499)
		(width 0.15)
		(layer "In2.Cu")
		(net 101)
	)
	(segment
		(start 106.32501 129.50499)
		(end 106.775 129.055)
		(width 0.15)
		(layer "In2.Cu")
		(net 101)
	)
	(segment
		(start 121.99 175.745)
		(end 121.99 169.64)
		(width 0.15)
		(layer "In2.Cu")
		(net 101)
	)
	(segment
		(start 116.400784 167.275)
		(end 111.075 161.949216)
		(width 0.15)
		(layer "In2.Cu")
		(net 101)
	)
	(segment
		(start 119.625 167.275)
		(end 116.400784 167.275)
		(width 0.15)
		(layer "In2.Cu")
		(net 101)
	)
	(segment
		(start 111.075 145.575)
		(end 106.32501 140.82501)
		(width 0.15)
		(layer "In2.Cu")
		(net 101)
	)
	(segment
		(start 111.075 161.949216)
		(end 111.075 145.575)
		(width 0.15)
		(layer "In2.Cu")
		(net 101)
	)
	(segment
		(start 106.075 130.175)
		(end 106.75001 130.85001)
		(width 0.15)
		(layer "F.Cu")
		(net 102)
	)
	(segment
		(start 105.775 130.175)
		(end 106.075 130.175)
		(width 0.15)
		(layer "F.Cu")
		(net 102)
	)
	(segment
		(start 106.75001 130.85001)
		(end 106.75001 131.475)
		(width 0.15)
		(layer "F.Cu")
		(net 102)
	)
	(segment
		(start 122.59 177.345)
		(end 122.59 175.445)
		(width 0.2)
		(layer "F.Cu")
		(net 102)
	)
	(via blind
		(at 122.59 175.445)
		(size 0.5)
		(drill 0.2)
		(layers "F.Cu" "In2.Cu")
		(net 102)
	)
	(via blind
		(at 106.75001 131.475)
		(size 0.5)
		(drill 0.2)
		(layers "F.Cu" "In2.Cu")
		(net 102)
	)
	(segment
		(start 122.59 169.69)
		(end 122.59 175.445)
		(width 0.15)
		(layer "In2.Cu")
		(net 102)
	)
	(segment
		(start 116.573989 166.974989)
		(end 119.874989 166.974989)
		(width 0.15)
		(layer "In2.Cu")
		(net 102)
	)
	(segment
		(start 111.375 161.776)
		(end 116.573989 166.974989)
		(width 0.15)
		(layer "In2.Cu")
		(net 102)
	)
	(segment
		(start 119.874989 166.974989)
		(end 122.59 169.69)
		(width 0.15)
		(layer "In2.Cu")
		(net 102)
	)
	(segment
		(start 106.75001 131.475)
		(end 106.75001 140.807146)
		(width 0.15)
		(layer "In2.Cu")
		(net 102)
	)
	(segment
		(start 111.375 145.432136)
		(end 111.375 161.776)
		(width 0.15)
		(layer "In2.Cu")
		(net 102)
	)
	(segment
		(start 106.75001 140.807146)
		(end 111.375 145.432136)
		(width 0.15)
		(layer "In2.Cu")
		(net 102)
	)
	(segment
		(start 68.742 96.569)
		(end 68.739 96.572)
		(width 0.15)
		(layer "F.Cu")
		(net 103)
	)
	(segment
		(start 68.742 94.906857)
		(end 68.742 96.569)
		(width 0.15)
		(layer "F.Cu")
		(net 103)
	)
	(segment
		(start 123.925 114.535)
		(end 123.925 113.81)
		(width 0.15)
		(layer "F.Cu")
		(net 105)
	)
	(segment
		(start 123.875 107.975)
		(end 123.775 107.975)
		(width 0.15)
		(layer "F.Cu")
		(net 105)
	)
	(segment
		(start 123.925 108.025)
		(end 123.875 107.975)
		(width 0.15)
		(layer "F.Cu")
		(net 105)
	)
	(segment
		(start 124.165 114.775)
		(end 123.925 114.535)
		(width 0.15)
		(layer "F.Cu")
		(net 105)
	)
	(segment
		(start 123.925 108.94)
		(end 123.925 108.025)
		(width 0.15)
		(layer "F.Cu")
		(net 105)
	)
	(via
		(at 124.165 114.775)
		(size 0.5)
		(drill 0.2)
		(layers "F.Cu" "B.Cu")
		(net 105)
	)
	(via
		(at 123.775 107.975)
		(size 0.5)
		(drill 0.2)
		(layers "F.Cu" "B.Cu")
		(net 105)
	)
	(segment
		(start 123.875 113.96)
		(end 122.82 113.96)
		(width 0.2)
		(layer "B.Cu")
		(net 105)
	)
	(segment
		(start 124.065 108.265)
		(end 124.065 108.915)
		(width 0.15)
		(layer "B.Cu")
		(net 105)
	)
	(segment
		(start 123.875 114.485)
		(end 124.165 114.775)
		(width 0.15)
		(layer "B.Cu")
		(net 105)
	)
	(segment
		(start 123.775 107.975)
		(end 124.065 108.265)
		(width 0.15)
		(layer "B.Cu")
		(net 105)
	)
	(segment
		(start 123.875 113.96)
		(end 123.875 114.485)
		(width 0.15)
		(layer "B.Cu")
		(net 105)
	)
	(segment
		(start 123.465 114.075)
		(end 124.165 114.775)
		(width 0.2)
		(layer "In5.Cu")
		(net 105)
	)
	(segment
		(start 123.465 108.285)
		(end 123.465 114.075)
		(width 0.2)
		(layer "In5.Cu")
		(net 105)
	)
	(segment
		(start 123.775 107.975)
		(end 123.465 108.285)
		(width 0.2)
		(layer "In5.Cu")
		(net 105)
	)
	(segment
		(start 82.765 63.585)
		(end 82.765 61.935)
		(width 0.15)
		(layer "F.Cu")
		(net 106)
	)
	(segment
		(start 81.75 63.64)
		(end 82.71 63.64)
		(width 0.15)
		(layer "F.Cu")
		(net 106)
	)
	(segment
		(start 82.71 63.64)
		(end 82.765 63.585)
		(width 0.15)
		(layer "F.Cu")
		(net 106)
	)
	(segment
		(start 76.125 63.59)
		(end 77.64 63.59)
		(width 0.15)
		(layer "F.Cu")
		(net 107)
	)
	(segment
		(start 77.64 63.59)
		(end 77.725 63.675)
		(width 0.15)
		(layer "F.Cu")
		(net 107)
	)
	(segment
		(start 76.01 63.425)
		(end 76.125 63.54)
		(width 0.15)
		(layer "F.Cu")
		(net 107)
	)
	(segment
		(start 76.01 62.525)
		(end 76.01 63.425)
		(width 0.15)
		(layer "F.Cu")
		(net 107)
	)
	(segment
		(start 123.725 125.04)
		(end 123.725 124.150497)
		(width 0.15)
		(layer "F.Cu")
		(net 108)
	)
	(segment
		(start 123.725 130.625)
		(end 123.725 129.91)
		(width 0.15)
		(layer "F.Cu")
		(net 108)
	)
	(segment
		(start 123.725 124.150497)
		(end 123.675565 124.101062)
		(width 0.15)
		(layer "F.Cu")
		(net 108)
	)
	(segment
		(start 123.965 130.865)
		(end 123.725 130.625)
		(width 0.15)
		(layer "F.Cu")
		(net 108)
	)
	(via
		(at 123.965 130.865)
		(size 0.5)
		(drill 0.2)
		(layers "F.Cu" "B.Cu")
		(net 108)
	)
	(via
		(at 123.675565 124.101062)
		(size 0.5)
		(drill 0.2)
		(layers "F.Cu" "B.Cu")
		(net 108)
	)
	(segment
		(start 123.355 130.15)
		(end 123.355 130.505)
		(width 0.2)
		(layer "B.Cu")
		(net 108)
	)
	(segment
		(start 124.115 130.865)
		(end 124.365 130.615)
		(width 0.2)
		(layer "B.Cu")
		(net 108)
	)
	(segment
		(start 124.365 130.615)
		(end 124.365 130.115)
		(width 0.2)
		(layer "B.Cu")
		(net 108)
	)
	(segment
		(start 124 124.915)
		(end 124 124.425497)
		(width 0.15)
		(layer "B.Cu")
		(net 108)
	)
	(segment
		(start 123.355 130.505)
		(end 123.715 130.865)
		(width 0.2)
		(layer "B.Cu")
		(net 108)
	)
	(segment
		(start 123.965 130.865)
		(end 124.115 130.865)
		(width 0.2)
		(layer "B.Cu")
		(net 108)
	)
	(segment
		(start 124 124.425497)
		(end 123.675565 124.101062)
		(width 0.15)
		(layer "B.Cu")
		(net 108)
	)
	(segment
		(start 123.715 130.865)
		(end 123.965 130.865)
		(width 0.2)
		(layer "B.Cu")
		(net 108)
	)
	(segment
		(start 123.675565 124.101062)
		(end 123.675565 124.504435)
		(width 0.2)
		(layer "In5.Cu")
		(net 108)
	)
	(segment
		(start 123.515 124.665)
		(end 123.515 130.415)
		(width 0.2)
		(layer "In5.Cu")
		(net 108)
	)
	(segment
		(start 123.515 130.415)
		(end 123.965 130.865)
		(width 0.2)
		(layer "In5.Cu")
		(net 108)
	)
	(segment
		(start 123.675565 124.504435)
		(end 123.515 124.665)
		(width 0.2)
		(layer "In5.Cu")
		(net 108)
	)
	(segment
		(start 105.074 148.76)
		(end 106.074 148.76)
		(width 0.15)
		(layer "B.Cu")
		(net 109)
	)
	(segment
		(start 106.074 148.76)
		(end 107.074 148.76)
		(width 0.15)
		(layer "B.Cu")
		(net 109)
	)
	(segment
		(start 81.75 66.04)
		(end 81.755 66.045)
		(width 0.15)
		(layer "F.Cu")
		(net 110)
	)
	(segment
		(start 81.755 67.139)
		(end 81.766 67.15)
		(width 0.15)
		(layer "F.Cu")
		(net 110)
	)
	(segment
		(start 81.755 66.045)
		(end 81.755 67.139)
		(width 0.15)
		(layer "F.Cu")
		(net 110)
	)
	(segment
		(start 75.04 62.525)
		(end 75.04 63.525)
		(width 0.15)
		(layer "F.Cu")
		(net 111)
	)
	(segment
		(start 138.575 158.625)
		(end 138.575 160.32)
		(width 0.15)
		(layer "F.Cu")
		(net 112)
	)
	(segment
		(start 89.51 104.375)
		(end 89.545 104.41)
		(width 0.25)
		(layer "F.Cu")
		(net 113)
	)
	(segment
		(start 87.67 104.375)
		(end 89.51 104.375)
		(width 0.25)
		(layer "F.Cu")
		(net 113)
	)
	(segment
		(start 89.545 104.41)
		(end 90.545 104.41)
		(width 0.25)
		(layer "F.Cu")
		(net 113)
	)
	(segment
		(start 90.545 104.41)
		(end 91.545 104.41)
		(width 0.25)
		(layer "F.Cu")
		(net 113)
	)
	(segment
		(start 136.85 90.8875)
		(end 136.85 90.1125)
		(width 0.1)
		(layer "F.Cu")
		(net 115)
	)
	(via
		(at 136.85 90.1125)
		(size 0.5)
		(drill 0.2)
		(layers "F.Cu" "B.Cu")
		(net 115)
	)
	(segment
		(start 136.85 89.3975)
		(end 137.85 89.3975)
		(width 0.1)
		(layer "B.Cu")
		(net 115)
	)
	(segment
		(start 138.865 89.4125)
		(end 137.865 89.4125)
		(width 0.1)
		(layer "B.Cu")
		(net 115)
	)
	(segment
		(start 136.85 89.3975)
		(end 136.85 90.1125)
		(width 0.1)
		(layer "B.Cu")
		(net 115)
	)
	(segment
		(start 137.865 89.4125)
		(end 137.85 89.3975)
		(width 0.1)
		(layer "B.Cu")
		(net 115)
	)
	(segment
		(start 131.45 89.1975)
		(end 132.45 89.1975)
		(width 0.2)
		(layer "F.Cu")
		(net 116)
	)
	(segment
		(start 132.85 89.1975)
		(end 134.17 89.1975)
		(width 0.1)
		(layer "F.Cu")
		(net 116)
	)
	(segment
		(start 134.35 89.3775)
		(end 134.17 89.1975)
		(width 0.1)
		(layer "F.Cu")
		(net 116)
	)
	(segment
		(start 133.45 89.1975)
		(end 132.45 89.1975)
		(width 0.2)
		(layer "F.Cu")
		(net 116)
	)
	(segment
		(start 134.35 90.8875)
		(end 134.35 89.3775)
		(width 0.1)
		(layer "F.Cu")
		(net 116)
	)
	(segment
		(start 131.85 89.1975)
		(end 132.85 89.1975)
		(width 0.1)
		(layer "F.Cu")
		(net 116)
	)
	(segment
		(start 90.545 97.06)
		(end 91.545 97.06)
		(width 0.25)
		(layer "F.Cu")
		(net 117)
	)
	(segment
		(start 87.67 97.025)
		(end 89.51 97.025)
		(width 0.25)
		(layer "F.Cu")
		(net 117)
	)
	(segment
		(start 89.51 97.025)
		(end 89.545 97.06)
		(width 0.25)
		(layer "F.Cu")
		(net 117)
	)
	(segment
		(start 89.545 97.06)
		(end 90.545 97.06)
		(width 0.25)
		(layer "F.Cu")
		(net 117)
	)
	(segment
		(start 123 157.2)
		(end 123 156.325)
		(width 0.1)
		(layer "F.Cu")
		(net 118)
	)
	(segment
		(start 122.99 158.92)
		(end 122.99 159.273553)
		(width 0.15)
		(layer "F.Cu")
		(net 118)
	)
	(segment
		(start 141.275 160.175)
		(end 142.575 160.175)
		(width 0.15)
		(layer "F.Cu")
		(net 118)
	)
	(segment
		(start 125.091447 161.375)
		(end 140.075 161.375)
		(width 0.15)
		(layer "F.Cu")
		(net 118)
	)
	(segment
		(start 123 156.325)
		(end 123.54 155.785)
		(width 0.1)
		(layer "F.Cu")
		(net 118)
	)
	(segment
		(start 122.99 159.273553)
		(end 125.091447 161.375)
		(width 0.15)
		(layer "F.Cu")
		(net 118)
	)
	(segment
		(start 140.075 161.375)
		(end 141.275 160.175)
		(width 0.15)
		(layer "F.Cu")
		(net 118)
	)
	(segment
		(start 123.54 155.785)
		(end 123.54 154.695)
		(width 0.1)
		(layer "F.Cu")
		(net 118)
	)
	(segment
		(start 122.99 157.21)
		(end 123 157.2)
		(width 0.15)
		(layer "F.Cu")
		(net 118)
	)
	(segment
		(start 122.99 158.92)
		(end 122.99 157.21)
		(width 0.15)
		(layer "F.Cu")
		(net 118)
	)
	(via
		(at 122.99 158.92)
		(size 0.5)
		(drill 0.2)
		(layers "F.Cu" "B.Cu")
		(net 118)
	)
	(segment
		(start 122.67 159.24)
		(end 122.99 158.92)
		(width 0.15)
		(layer "B.Cu")
		(net 118)
	)
	(segment
		(start 128 177.335)
		(end 128 174.8)
		(width 0.15)
		(layer "B.Cu")
		(net 118)
	)
	(segment
		(start 122.67 169.47)
		(end 122.67 159.24)
		(width 0.15)
		(layer "B.Cu")
		(net 118)
	)
	(segment
		(start 128 174.8)
		(end 122.67 169.47)
		(width 0.15)
		(layer "B.Cu")
		(net 118)
	)
	(segment
		(start 69.795696 117.125896)
		(end 67.545696 117.125896)
		(width 0.25)
		(layer "F.Cu")
		(net 119)
	)
	(segment
		(start 67.1407 116.7209)
		(end 67.1407 114.961)
		(width 0.25)
		(layer "F.Cu")
		(net 119)
	)
	(segment
		(start 67.545696 117.125896)
		(end 67.1407 116.7209)
		(width 0.25)
		(layer "F.Cu")
		(net 119)
	)
	(segment
		(start 69.755696 126.675896)
		(end 67.505696 126.675896)
		(width 0.25)
		(layer "F.Cu")
		(net 119)
	)
	(segment
		(start 67.1007 126.2709)
		(end 67.1007 124.511)
		(width 0.25)
		(layer "F.Cu")
		(net 119)
	)
	(segment
		(start 67.505696 126.675896)
		(end 67.1007 126.2709)
		(width 0.25)
		(layer "F.Cu")
		(net 119)
	)
	(segment
		(start 77.572 150.972)
		(end 76.775 150.175)
		(width 0.15)
		(layer "F.Cu")
		(net 119)
	)
	(segment
		(start 77.572 154.34712)
		(end 77.572 150.972)
		(width 0.15)
		(layer "F.Cu")
		(net 119)
	)
	(via
		(at 69.795696 117.125896)
		(size 0.5)
		(drill 0.2)
		(layers "F.Cu" "B.Cu")
		(net 119)
	)
	(via
		(at 69.755696 126.675896)
		(size 0.5)
		(drill 0.2)
		(layers "F.Cu" "B.Cu")
		(net 119)
	)
	(via blind
		(at 76.775 150.175)
		(size 0.5)
		(drill 0.2)
		(layers "F.Cu" "In2.Cu")
		(net 119)
	)
	(segment
		(start 69.7957 117.1259)
		(end 70.8107 117.1259)
		(width 0.25)
		(layer "B.Cu")
		(net 119)
	)
	(segment
		(start 69.7557 126.6759)
		(end 70.7707 126.6759)
		(width 0.25)
		(layer "B.Cu")
		(net 119)
	)
	(segment
		(start 69.795696 117.125896)
		(end 73.815896 117.125896)
		(width 0.15)
		(layer "In2.Cu")
		(net 119)
	)
	(segment
		(start 75.924989 149.324989)
		(end 76.775 150.175)
		(width 0.15)
		(layer "In2.Cu")
		(net 119)
	)
	(segment
		(start 75.924989 119.234989)
		(end 75.924989 149.324989)
		(width 0.15)
		(layer "In2.Cu")
		(net 119)
	)
	(segment
		(start 73.815896 117.125896)
		(end 75.924989 119.234989)
		(width 0.15)
		(layer "In2.Cu")
		(net 119)
	)
	(segment
		(start 71.015 125.945)
		(end 71.015 117.475)
		(width 0.15)
		(layer "In5.Cu")
		(net 119)
	)
	(segment
		(start 71.015 117.475)
		(end 70.665896 117.125896)
		(width 0.15)
		(layer "In5.Cu")
		(net 119)
	)
	(segment
		(start 70.665896 117.125896)
		(end 69.795696 117.125896)
		(width 0.15)
		(layer "In5.Cu")
		(net 119)
	)
	(segment
		(start 70.310004 126.649996)
		(end 71.015 125.945)
		(width 0.15)
		(layer "In5.Cu")
		(net 119)
	)
	(segment
		(start 69.774996 126.649996)
		(end 70.310004 126.649996)
		(width 0.15)
		(layer "In5.Cu")
		(net 119)
	)
	(segment
		(start 75.085 154.44678)
		(end 75.085 153.065)
		(width 0.15)
		(layer "F.Cu")
		(net 120)
	)
	(segment
		(start 68.3707 125.523)
		(end 68.3707 124.511)
		(width 0.25)
		(layer "F.Cu")
		(net 120)
	)
	(segment
		(start 68.523588 125.675888)
		(end 68.3707 125.523)
		(width 0.25)
		(layer "F.Cu")
		(net 120)
	)
	(segment
		(start 69.755688 125.675888)
		(end 68.523588 125.675888)
		(width 0.25)
		(layer "F.Cu")
		(net 120)
	)
	(via blind
		(at 75.085 153.065)
		(size 0.5)
		(drill 0.2)
		(layers "F.Cu" "In2.Cu")
		(net 120)
	)
	(via
		(at 69.755688 125.675888)
		(size 0.5)
		(drill 0.2)
		(layers "F.Cu" "B.Cu")
		(net 120)
	)
	(segment
		(start 69.7557 125.6759)
		(end 70.7707 125.6759)
		(width 0.25)
		(layer "B.Cu")
		(net 120)
	)
	(segment
		(start 75.085 151.355)
		(end 74.665 150.935)
		(width 0.15)
		(layer "In2.Cu")
		(net 120)
	)
	(segment
		(start 72.075888 125.675888)
		(end 69.755688 125.675888)
		(width 0.15)
		(layer "In2.Cu")
		(net 120)
	)
	(segment
		(start 74.665 150.935)
		(end 74.665 128.265)
		(width 0.15)
		(layer "In2.Cu")
		(net 120)
	)
	(segment
		(start 74.665 128.265)
		(end 72.075888 125.675888)
		(width 0.15)
		(layer "In2.Cu")
		(net 120)
	)
	(segment
		(start 75.085 153.065)
		(end 75.085 151.355)
		(width 0.15)
		(layer "In2.Cu")
		(net 120)
	)
	(segment
		(start 73.598 154.19378)
		(end 73.598 152.507)
		(width 0.15)
		(layer "F.Cu")
		(net 121)
	)
	(segment
		(start 69.75568 129.67588)
		(end 66.94362 129.67588)
		(width 0.25)
		(layer "F.Cu")
		(net 121)
	)
	(segment
		(start 66.94362 129.67588)
		(end 65.8307 130.7888)
		(width 0.25)
		(layer "F.Cu")
		(net 121)
	)
	(segment
		(start 65.8307 130.7888)
		(end 65.8307 131.8008)
		(width 0.25)
		(layer "F.Cu")
		(net 121)
	)
	(via blind
		(at 73.6 152.505)
		(size 0.5)
		(drill 0.2)
		(layers "F.Cu" "In2.Cu")
		(net 121)
	)
	(via
		(at 69.75568 129.67588)
		(size 0.5)
		(drill 0.2)
		(layers "F.Cu" "B.Cu")
		(net 121)
	)
	(segment
		(start 69.7557 129.6759)
		(end 70.7707 129.6759)
		(width 0.25)
		(layer "B.Cu")
		(net 121)
	)
	(segment
		(start 73.914978 131.494978)
		(end 73.914978 152.190022)
		(width 0.15)
		(layer "In2.Cu")
		(net 121)
	)
	(segment
		(start 73.914978 152.190022)
		(end 73.6 152.505)
		(width 0.15)
		(layer "In2.Cu")
		(net 121)
	)
	(segment
		(start 69.75568 129.67588)
		(end 72.09588 129.67588)
		(width 0.15)
		(layer "In2.Cu")
		(net 121)
	)
	(segment
		(start 72.09588 129.67588)
		(end 73.914978 131.494978)
		(width 0.15)
		(layer "In2.Cu")
		(net 121)
	)
	(segment
		(start 67.213606 130.675894)
		(end 67.1007 130.7888)
		(width 0.25)
		(layer "F.Cu")
		(net 122)
	)
	(segment
		(start 69.755694 130.675894)
		(end 67.213606 130.675894)
		(width 0.25)
		(layer "F.Cu")
		(net 122)
	)
	(segment
		(start 67.1007 130.7888)
		(end 67.1007 131.8008)
		(width 0.25)
		(layer "F.Cu")
		(net 122)
	)
	(segment
		(start 73.085 154.44678)
		(end 73.085 153.065)
		(width 0.15)
		(layer "F.Cu")
		(net 122)
	)
	(via
		(at 69.755694 130.675894)
		(size 0.5)
		(drill 0.2)
		(layers "F.Cu" "B.Cu")
		(net 122)
	)
	(via blind
		(at 73.085 153.065)
		(size 0.5)
		(drill 0.2)
		(layers "F.Cu" "In2.Cu")
		(net 122)
	)
	(segment
		(start 69.7557 130.6759)
		(end 70.7707 130.6759)
		(width 0.25)
		(layer "B.Cu")
		(net 122)
	)
	(segment
		(start 73.085 152.005)
		(end 73.085 153.065)
		(width 0.15)
		(layer "In2.Cu")
		(net 122)
	)
	(segment
		(start 73.655 151.435)
		(end 73.085 152.005)
		(width 0.15)
		(layer "In2.Cu")
		(net 122)
	)
	(segment
		(start 72.095894 130.675894)
		(end 73.655 132.235)
		(width 0.15)
		(layer "In2.Cu")
		(net 122)
	)
	(segment
		(start 73.655 132.235)
		(end 73.655 151.435)
		(width 0.15)
		(layer "In2.Cu")
		(net 122)
	)
	(segment
		(start 69.755694 130.675894)
		(end 72.095894 130.675894)
		(width 0.15)
		(layer "In2.Cu")
		(net 122)
	)
	(segment
		(start 69.755702 127.675898)
		(end 66.755698 127.675898)
		(width 0.25)
		(layer "F.Cu")
		(net 123)
	)
	(segment
		(start 66.755698 127.675898)
		(end 65.8307 126.7509)
		(width 0.25)
		(layer "F.Cu")
		(net 123)
	)
	(segment
		(start 65.8307 126.7509)
		(end 65.8307 124.511)
		(width 0.25)
		(layer "F.Cu")
		(net 123)
	)
	(segment
		(start 74.598 154.19378)
		(end 74.598 152.507)
		(width 0.15)
		(layer "F.Cu")
		(net 123)
	)
	(via
		(at 69.755702 127.675898)
		(size 0.5)
		(drill 0.2)
		(layers "F.Cu" "B.Cu")
		(net 123)
	)
	(via blind
		(at 74.6 152.505)
		(size 0.5)
		(drill 0.2)
		(layers "F.Cu" "In2.Cu")
		(net 123)
	)
	(segment
		(start 69.7557 127.6759)
		(end 70.7707 127.6759)
		(width 0.25)
		(layer "B.Cu")
		(net 123)
	)
	(segment
		(start 74.6 152.505)
		(end 74.414989 152.319989)
		(width 0.15)
		(layer "In2.Cu")
		(net 123)
	)
	(segment
		(start 74.414989 130.004989)
		(end 72.085898 127.675898)
		(width 0.15)
		(layer "In2.Cu")
		(net 123)
	)
	(segment
		(start 72.085898 127.675898)
		(end 69.755702 127.675898)
		(width 0.15)
		(layer "In2.Cu")
		(net 123)
	)
	(segment
		(start 74.414989 152.319989)
		(end 74.414989 130.004989)
		(width 0.15)
		(layer "In2.Cu")
		(net 123)
	)
	(segment
		(start 69.755694 128.675906)
		(end 66.673594 128.675906)
		(width 0.25)
		(layer "F.Cu")
		(net 124)
	)
	(segment
		(start 66.648594 128.675906)
		(end 64.5357 130.7888)
		(width 0.25)
		(layer "F.Cu")
		(net 124)
	)
	(segment
		(start 64.5357 130.7888)
		(end 64.5357 131.8008)
		(width 0.25)
		(layer "F.Cu")
		(net 124)
	)
	(segment
		(start 74.085 154.44678)
		(end 74.085 153.065)
		(width 0.15)
		(layer "F.Cu")
		(net 124)
	)
	(via
		(at 69.755694 128.675906)
		(size 0.5)
		(drill 0.2)
		(layers "F.Cu" "B.Cu")
		(net 124)
	)
	(via blind
		(at 74.085 153.065)
		(size 0.5)
		(drill 0.2)
		(layers "F.Cu" "In2.Cu")
		(net 124)
	)
	(segment
		(start 69.7557 128.6759)
		(end 70.7707 128.6759)
		(width 0.25)
		(layer "B.Cu")
		(net 124)
	)
	(segment
		(start 74.164978 152.985022)
		(end 74.164978 130.744978)
		(width 0.15)
		(layer "In2.Cu")
		(net 124)
	)
	(segment
		(start 74.085 153.065)
		(end 74.164978 152.985022)
		(width 0.15)
		(layer "In2.Cu")
		(net 124)
	)
	(segment
		(start 72.095906 128.675906)
		(end 69.755694 128.675906)
		(width 0.15)
		(layer "In2.Cu")
		(net 124)
	)
	(segment
		(start 74.164978 130.744978)
		(end 72.095906 128.675906)
		(width 0.15)
		(layer "In2.Cu")
		(net 124)
	)
	(segment
		(start 68.4107 115.973)
		(end 68.4107 114.961)
		(width 0.25)
		(layer "F.Cu")
		(net 125)
	)
	(segment
		(start 68.563588 116.125888)
		(end 68.4107 115.973)
		(width 0.25)
		(layer "F.Cu")
		(net 125)
	)
	(segment
		(start 69.795688 116.125888)
		(end 68.563588 116.125888)
		(width 0.25)
		(layer "F.Cu")
		(net 125)
	)
	(segment
		(start 78.072 154.34712)
		(end 78.072 150.472)
		(width 0.15)
		(layer "F.Cu")
		(net 125)
	)
	(segment
		(start 76.775 149.175)
		(end 78.072 150.472)
		(width 0.15)
		(layer "F.Cu")
		(net 125)
	)
	(via
		(at 69.795688 116.125888)
		(size 0.5)
		(drill 0.2)
		(layers "F.Cu" "B.Cu")
		(net 125)
	)
	(via blind
		(at 76.775 149.175)
		(size 0.5)
		(drill 0.2)
		(layers "F.Cu" "In2.Cu")
		(net 125)
	)
	(segment
		(start 69.7957 116.1259)
		(end 70.8107 116.1259)
		(width 0.25)
		(layer "B.Cu")
		(net 125)
	)
	(segment
		(start 73.815888 116.125888)
		(end 76.175 118.485)
		(width 0.15)
		(layer "In2.Cu")
		(net 125)
	)
	(segment
		(start 69.795688 116.125888)
		(end 73.815888 116.125888)
		(width 0.15)
		(layer "In2.Cu")
		(net 125)
	)
	(segment
		(start 76.175 118.485)
		(end 76.175 148.775)
		(width 0.15)
		(layer "In2.Cu")
		(net 125)
	)
	(segment
		(start 76.175 148.775)
		(end 76.575 149.175)
		(width 0.15)
		(layer "In2.Cu")
		(net 125)
	)
	(segment
		(start 76.575 149.175)
		(end 76.775 149.175)
		(width 0.15)
		(layer "In2.Cu")
		(net 125)
	)
	(segment
		(start 69.79568 120.12588)
		(end 66.98362 120.12588)
		(width 0.25)
		(layer "F.Cu")
		(net 126)
	)
	(segment
		(start 66.98362 120.12588)
		(end 65.8707 121.2388)
		(width 0.25)
		(layer "F.Cu")
		(net 126)
	)
	(segment
		(start 65.8707 121.2388)
		(end 65.8707 122.2508)
		(width 0.25)
		(layer "F.Cu")
		(net 126)
	)
	(segment
		(start 76.085 154.44678)
		(end 76.085 153.065)
		(width 0.15)
		(layer "F.Cu")
		(net 126)
	)
	(via
		(at 69.79568 120.12588)
		(size 0.5)
		(drill 0.2)
		(layers "F.Cu" "B.Cu")
		(net 126)
	)
	(via blind
		(at 76.085 153.065)
		(size 0.5)
		(drill 0.2)
		(layers "F.Cu" "In2.Cu")
		(net 126)
	)
	(segment
		(start 69.7957 120.1259)
		(end 70.8107 120.1259)
		(width 0.25)
		(layer "B.Cu")
		(net 126)
	)
	(segment
		(start 75.174956 121.484956)
		(end 73.81588 120.12588)
		(width 0.15)
		(layer "In2.Cu")
		(net 126)
	)
	(segment
		(start 76.085 151.631432)
		(end 75.174956 150.721388)
		(width 0.15)
		(layer "In2.Cu")
		(net 126)
	)
	(segment
		(start 75.174956 150.721388)
		(end 75.174956 121.484956)
		(width 0.15)
		(layer "In2.Cu")
		(net 126)
	)
	(segment
		(start 73.81588 120.12588)
		(end 69.79568 120.12588)
		(width 0.15)
		(layer "In2.Cu")
		(net 126)
	)
	(segment
		(start 76.085 153.065)
		(end 76.085 151.631432)
		(width 0.15)
		(layer "In2.Cu")
		(net 126)
	)
	(segment
		(start 67.253606 121.125894)
		(end 67.1407 121.2388)
		(width 0.25)
		(layer "F.Cu")
		(net 127)
	)
	(segment
		(start 69.795694 121.125894)
		(end 67.253606 121.125894)
		(width 0.25)
		(layer "F.Cu")
		(net 127)
	)
	(segment
		(start 67.1407 121.2388)
		(end 67.1407 122.2508)
		(width 0.25)
		(layer "F.Cu")
		(net 127)
	)
	(segment
		(start 75.598 154.19378)
		(end 75.598 152.507)
		(width 0.15)
		(layer "F.Cu")
		(net 127)
	)
	(via
		(at 69.795694 121.125894)
		(size 0.5)
		(drill 0.2)
		(layers "F.Cu" "B.Cu")
		(net 127)
	)
	(via blind
		(at 75.6 152.505)
		(size 0.5)
		(drill 0.2)
		(layers "F.Cu" "In2.Cu")
		(net 127)
	)
	(segment
		(start 69.7957 121.1259)
		(end 70.8107 121.1259)
		(width 0.25)
		(layer "B.Cu")
		(net 127)
	)
	(segment
		(start 75.6 151.5)
		(end 74.924945 150.824945)
		(width 0.15)
		(layer "In2.Cu")
		(net 127)
	)
	(segment
		(start 75.6 152.505)
		(end 75.6 151.5)
		(width 0.15)
		(layer "In2.Cu")
		(net 127)
	)
	(segment
		(start 74.924945 150.824945)
		(end 74.924945 122.234945)
		(width 0.15)
		(layer "In2.Cu")
		(net 127)
	)
	(segment
		(start 73.815894 121.125894)
		(end 69.795694 121.125894)
		(width 0.15)
		(layer "In2.Cu")
		(net 127)
	)
	(segment
		(start 74.924945 122.234945)
		(end 73.815894 121.125894)
		(width 0.15)
		(layer "In2.Cu")
		(net 127)
	)
	(segment
		(start 69.795702 118.125898)
		(end 66.795698 118.125898)
		(width 0.25)
		(layer "F.Cu")
		(net 128)
	)
	(segment
		(start 66.795698 118.125898)
		(end 65.8707 117.2009)
		(width 0.25)
		(layer "F.Cu")
		(net 128)
	)
	(segment
		(start 65.8707 117.2009)
		(end 65.8707 114.961)
		(width 0.25)
		(layer "F.Cu")
		(net 128)
	)
	(segment
		(start 77.072 151.472)
		(end 76.775 151.175)
		(width 0.15)
		(layer "F.Cu")
		(net 128)
	)
	(segment
		(start 77.072 154.34712)
		(end 77.072 151.472)
		(width 0.15)
		(layer "F.Cu")
		(net 128)
	)
	(via
		(at 69.795702 118.125898)
		(size 0.5)
		(drill 0.2)
		(layers "F.Cu" "B.Cu")
		(net 128)
	)
	(via blind
		(at 76.775 151.175)
		(size 0.5)
		(drill 0.2)
		(layers "F.Cu" "In2.Cu")
		(net 128)
	)
	(segment
		(start 69.7957 118.1259)
		(end 70.8107 118.1259)
		(width 0.25)
		(layer "B.Cu")
		(net 128)
	)
	(segment
		(start 76.775 151.175)
		(end 75.674978 150.074978)
		(width 0.15)
		(layer "In2.Cu")
		(net 128)
	)
	(segment
		(start 75.674978 150.074978)
		(end 75.674978 119.974978)
		(width 0.15)
		(layer "In2.Cu")
		(net 128)
	)
	(segment
		(start 69.795702 118.125898)
		(end 73.825898 118.125898)
		(width 0.15)
		(layer "In2.Cu")
		(net 128)
	)
	(segment
		(start 75.674978 119.974978)
		(end 73.825898 118.125898)
		(width 0.15)
		(layer "In2.Cu")
		(net 128)
	)
	(segment
		(start 64.6007 121.2388)
		(end 64.6007 122.2508)
		(width 0.25)
		(layer "F.Cu")
		(net 129)
	)
	(segment
		(start 69.795694 119.125906)
		(end 66.713594 119.125906)
		(width 0.25)
		(layer "F.Cu")
		(net 129)
	)
	(segment
		(start 66.713594 119.125906)
		(end 64.6007 121.2388)
		(width 0.25)
		(layer "F.Cu")
		(net 129)
	)
	(segment
		(start 76.598 154.19378)
		(end 76.598 152.507)
		(width 0.15)
		(layer "F.Cu")
		(net 129)
	)
	(via
		(at 69.795694 119.125906)
		(size 0.5)
		(drill 0.2)
		(layers "F.Cu" "B.Cu")
		(net 129)
	)
	(via blind
		(at 76.6 152.505)
		(size 0.5)
		(drill 0.2)
		(layers "F.Cu" "In2.Cu")
		(net 129)
	)
	(segment
		(start 69.7957 119.1259)
		(end 70.8107 119.1259)
		(width 0.25)
		(layer "B.Cu")
		(net 129)
	)
	(segment
		(start 73.805906 119.125906)
		(end 69.795694 119.125906)
		(width 0.15)
		(layer "In2.Cu")
		(net 129)
	)
	(segment
		(start 75.424967 120.744967)
		(end 73.805906 119.125906)
		(width 0.15)
		(layer "In2.Cu")
		(net 129)
	)
	(segment
		(start 75.424967 150.617831)
		(end 75.424967 120.744967)
		(width 0.15)
		(layer "In2.Cu")
		(net 129)
	)
	(segment
		(start 76.6 152.505)
		(end 76.6 151.792864)
		(width 0.15)
		(layer "In2.Cu")
		(net 129)
	)
	(segment
		(start 76.6 151.792864)
		(end 75.424967 150.617831)
		(width 0.15)
		(layer "In2.Cu")
		(net 129)
	)
	(segment
		(start 69.765696 136.315896)
		(end 67.515696 136.315896)
		(width 0.25)
		(layer "F.Cu")
		(net 130)
	)
	(segment
		(start 67.1107 135.9109)
		(end 67.1107 134.151)
		(width 0.25)
		(layer "F.Cu")
		(net 130)
	)
	(segment
		(start 67.515696 136.315896)
		(end 67.1107 135.9109)
		(width 0.25)
		(layer "F.Cu")
		(net 130)
	)
	(segment
		(start 69.739996 145.924996)
		(end 67.489996 145.924996)
		(width 0.25)
		(layer "F.Cu")
		(net 130)
	)
	(segment
		(start 67.489996 145.924996)
		(end 67.085 145.52)
		(width 0.25)
		(layer "F.Cu")
		(net 130)
	)
	(segment
		(start 67.085 145.52)
		(end 67.085 143.7601)
		(width 0.25)
		(layer "F.Cu")
		(net 130)
	)
	(segment
		(start 72.085 154.42178)
		(end 72.085 153.04)
		(width 0.15)
		(layer "F.Cu")
		(net 130)
	)
	(via
		(at 69.765696 136.315896)
		(size 0.5)
		(drill 0.2)
		(layers "F.Cu" "B.Cu")
		(net 130)
	)
	(via
		(at 69.739996 145.924996)
		(size 0.5)
		(drill 0.2)
		(layers "F.Cu" "B.Cu")
		(net 130)
	)
	(via blind
		(at 72.085 153.04)
		(size 0.5)
		(drill 0.2)
		(layers "F.Cu" "In2.Cu")
		(net 130)
	)
	(segment
		(start 69.7657 136.3159)
		(end 70.7807 136.3159)
		(width 0.25)
		(layer "B.Cu")
		(net 130)
	)
	(segment
		(start 69.74 145.925)
		(end 70.755 145.925)
		(width 0.25)
		(layer "B.Cu")
		(net 130)
	)
	(segment
		(start 72.085 151.991434)
		(end 73.15498 150.921454)
		(width 0.15)
		(layer "In2.Cu")
		(net 130)
	)
	(segment
		(start 73.15498 150.921454)
		(end 73.15498 138.26498)
		(width 0.15)
		(layer "In2.Cu")
		(net 130)
	)
	(segment
		(start 73.15498 138.26498)
		(end 71.205896 136.315896)
		(width 0.15)
		(layer "In2.Cu")
		(net 130)
	)
	(segment
		(start 72.085 153.04)
		(end 72.085 151.991434)
		(width 0.15)
		(layer "In2.Cu")
		(net 130)
	)
	(segment
		(start 71.205896 136.315896)
		(end 69.765696 136.315896)
		(width 0.15)
		(layer "In2.Cu")
		(net 130)
	)
	(segment
		(start 68.305 136.995)
		(end 68.984104 136.315896)
		(width 0.15)
		(layer "In5.Cu")
		(net 130)
	)
	(segment
		(start 68.994996 145.924996)
		(end 68.305 145.235)
		(width 0.15)
		(layer "In5.Cu")
		(net 130)
	)
	(segment
		(start 69.739996 145.924996)
		(end 68.994996 145.924996)
		(width 0.15)
		(layer "In5.Cu")
		(net 130)
	)
	(segment
		(start 68.984104 136.315896)
		(end 69.765696 136.315896)
		(width 0.15)
		(layer "In5.Cu")
		(net 130)
	)
	(segment
		(start 68.305 145.235)
		(end 68.305 136.995)
		(width 0.15)
		(layer "In5.Cu")
		(net 130)
	)
	(segment
		(start 71.602 158.45122)
		(end 71.602 159.848)
		(width 0.15)
		(layer "F.Cu")
		(net 131)
	)
	(segment
		(start 71.597 158.44622)
		(end 71.602 158.45122)
		(width 0.15)
		(layer "F.Cu")
		(net 131)
	)
	(segment
		(start 69.739988 144.924988)
		(end 68.507888 144.924988)
		(width 0.25)
		(layer "F.Cu")
		(net 131)
	)
	(segment
		(start 68.507888 144.924988)
		(end 68.355 144.7721)
		(width 0.25)
		(layer "F.Cu")
		(net 131)
	)
	(segment
		(start 68.355 144.7721)
		(end 68.355 143.7601)
		(width 0.25)
		(layer "F.Cu")
		(net 131)
	)
	(via
		(at 71.602 159.848)
		(size 0.5)
		(drill 0.2)
		(layers "F.Cu" "B.Cu")
		(net 131)
	)
	(via
		(at 69.739988 144.924988)
		(size 0.5)
		(drill 0.2)
		(layers "F.Cu" "B.Cu")
		(net 131)
	)
	(segment
		(start 69.74 144.925)
		(end 70.755 144.925)
		(width 0.25)
		(layer "B.Cu")
		(net 131)
	)
	(segment
		(start 69.749976 144.915)
		(end 69.739988 144.924988)
		(width 0.15)
		(layer "In5.Cu")
		(net 131)
	)
	(segment
		(start 70.755 144.915)
		(end 69.749976 144.915)
		(width 0.15)
		(layer "In5.Cu")
		(net 131)
	)
	(segment
		(start 71.985022 159.464978)
		(end 71.985022 146.145022)
		(width 0.15)
		(layer "In5.Cu")
		(net 131)
	)
	(segment
		(start 71.602 159.848)
		(end 71.985022 159.464978)
		(width 0.15)
		(layer "In5.Cu")
		(net 131)
	)
	(segment
		(start 71.985022 146.145022)
		(end 70.755 144.915)
		(width 0.15)
		(layer "In5.Cu")
		(net 131)
	)
	(segment
		(start 70.077 158.73122)
		(end 70.077 160.418)
		(width 0.15)
		(layer "F.Cu")
		(net 132)
	)
	(segment
		(start 70.077 160.418)
		(end 70.075 160.42)
		(width 0.15)
		(layer "F.Cu")
		(net 132)
	)
	(segment
		(start 65.8207 150.0888)
		(end 65.8207 151.1008)
		(width 0.25)
		(layer "F.Cu")
		(net 132)
	)
	(segment
		(start 66.92792 148.92498)
		(end 69.65999 148.92498)
		(width 0.25)
		(layer "F.Cu")
		(net 132)
	)
	(segment
		(start 65.815 150.0379)
		(end 66.92792 148.92498)
		(width 0.25)
		(layer "F.Cu")
		(net 132)
	)
	(via
		(at 70.075 160.42)
		(size 0.5)
		(drill 0.2)
		(layers "F.Cu" "B.Cu")
		(net 132)
	)
	(via
		(at 69.65999 148.92498)
		(size 0.5)
		(drill 0.2)
		(layers "F.Cu" "B.Cu")
		(net 132)
	)
	(segment
		(start 69.74 148.925)
		(end 70.755 148.925)
		(width 0.25)
		(layer "B.Cu")
		(net 132)
	)
	(segment
		(start 70.075 160.42)
		(end 70.075 159.720998)
		(width 0.15)
		(layer "In5.Cu")
		(net 132)
	)
	(segment
		(start 70.74498 148.92498)
		(end 69.65999 148.92498)
		(width 0.15)
		(layer "In5.Cu")
		(net 132)
	)
	(segment
		(start 71.23499 158.561008)
		(end 71.23499 149.41499)
		(width 0.15)
		(layer "In5.Cu")
		(net 132)
	)
	(segment
		(start 70.075 159.720998)
		(end 71.23499 158.561008)
		(width 0.15)
		(layer "In5.Cu")
		(net 132)
	)
	(segment
		(start 71.23499 149.41499)
		(end 70.74498 148.92498)
		(width 0.15)
		(layer "In5.Cu")
		(net 132)
	)
	(segment
		(start 69.59 158.47822)
		(end 69.59 159.86)
		(width 0.15)
		(layer "F.Cu")
		(net 133)
	)
	(segment
		(start 67.0907 150.0888)
		(end 67.0907 151.1008)
		(width 0.25)
		(layer "F.Cu")
		(net 133)
	)
	(segment
		(start 67.265006 149.924994)
		(end 69.65999 149.924994)
		(width 0.25)
		(layer "F.Cu")
		(net 133)
	)
	(segment
		(start 67.115 150.075)
		(end 67.265006 149.924994)
		(width 0.25)
		(layer "F.Cu")
		(net 133)
	)
	(via
		(at 69.59 159.86)
		(size 0.5)
		(drill 0.2)
		(layers "F.Cu" "B.Cu")
		(net 133)
	)
	(via
		(at 69.65999 149.924994)
		(size 0.5)
		(drill 0.2)
		(layers "F.Cu" "B.Cu")
		(net 133)
	)
	(segment
		(start 69.74 149.925)
		(end 70.755 149.925)
		(width 0.25)
		(layer "B.Cu")
		(net 133)
	)
	(segment
		(start 69.59 159.852432)
		(end 70.98498 158.457452)
		(width 0.15)
		(layer "In5.Cu")
		(net 133)
	)
	(segment
		(start 69.59 159.86)
		(end 69.59 159.852432)
		(width 0.15)
		(layer "In5.Cu")
		(net 133)
	)
	(segment
		(start 70.724994 149.924994)
		(end 69.65999 149.924994)
		(width 0.15)
		(layer "In5.Cu")
		(net 133)
	)
	(segment
		(start 70.98498 158.457452)
		(end 70.98498 150.18498)
		(width 0.15)
		(layer "In5.Cu")
		(net 133)
	)
	(segment
		(start 70.98498 150.18498)
		(end 70.724994 149.924994)
		(width 0.15)
		(layer "In5.Cu")
		(net 133)
	)
	(segment
		(start 71.102 158.45122)
		(end 71.102 160.448)
		(width 0.15)
		(layer "F.Cu")
		(net 134)
	)
	(segment
		(start 71.102 160.448)
		(end 71.09 160.46)
		(width 0.15)
		(layer "F.Cu")
		(net 134)
	)
	(segment
		(start 71.097 158.44622)
		(end 71.102 158.45122)
		(width 0.15)
		(layer "F.Cu")
		(net 134)
	)
	(segment
		(start 69.740002 146.924998)
		(end 66.739998 146.924998)
		(width 0.25)
		(layer "F.Cu")
		(net 134)
	)
	(segment
		(start 65.815 146)
		(end 65.815 143.7601)
		(width 0.25)
		(layer "F.Cu")
		(net 134)
	)
	(segment
		(start 66.739998 146.924998)
		(end 65.815 146)
		(width 0.25)
		(layer "F.Cu")
		(net 134)
	)
	(via
		(at 71.09 160.46)
		(size 0.5)
		(drill 0.2)
		(layers "F.Cu" "B.Cu")
		(net 134)
	)
	(via
		(at 69.740002 146.924998)
		(size 0.5)
		(drill 0.2)
		(layers "F.Cu" "B.Cu")
		(net 134)
	)
	(segment
		(start 69.74 146.925)
		(end 70.755 146.925)
		(width 0.25)
		(layer "B.Cu")
		(net 134)
	)
	(segment
		(start 71.09 160.46)
		(end 71.09 159.688568)
		(width 0.15)
		(layer "In5.Cu")
		(net 134)
	)
	(segment
		(start 71.09 159.688568)
		(end 71.735011 159.043557)
		(width 0.15)
		(layer "In5.Cu")
		(net 134)
	)
	(segment
		(start 70.724998 146.924998)
		(end 69.740002 146.924998)
		(width 0.15)
		(layer "In5.Cu")
		(net 134)
	)
	(segment
		(start 71.735011 159.043557)
		(end 71.735011 147.935011)
		(width 0.15)
		(layer "In5.Cu")
		(net 134)
	)
	(segment
		(start 71.735011 147.935011)
		(end 70.724998 146.924998)
		(width 0.15)
		(layer "In5.Cu")
		(net 134)
	)
	(segment
		(start 70.565 158.47822)
		(end 70.565 159.86)
		(width 0.15)
		(layer "F.Cu")
		(net 135)
	)
	(segment
		(start 69.739994 147.925006)
		(end 66.657894 147.925006)
		(width 0.25)
		(layer "F.Cu")
		(net 135)
	)
	(segment
		(start 66.657894 147.925006)
		(end 64.545 150.0379)
		(width 0.25)
		(layer "F.Cu")
		(net 135)
	)
	(segment
		(start 64.5507 150.0888)
		(end 64.5507 151.1008)
		(width 0.25)
		(layer "F.Cu")
		(net 135)
	)
	(via
		(at 70.565 159.86)
		(size 0.5)
		(drill 0.2)
		(layers "F.Cu" "B.Cu")
		(net 135)
	)
	(via
		(at 69.739994 147.925006)
		(size 0.5)
		(drill 0.2)
		(layers "F.Cu" "B.Cu")
		(net 135)
	)
	(segment
		(start 69.74 147.925)
		(end 70.755 147.925)
		(width 0.25)
		(layer "B.Cu")
		(net 135)
	)
	(segment
		(start 70.735006 147.925006)
		(end 69.739994 147.925006)
		(width 0.15)
		(layer "In5.Cu")
		(net 135)
	)
	(segment
		(start 71.485 158.94)
		(end 71.485 148.675)
		(width 0.15)
		(layer "In5.Cu")
		(net 135)
	)
	(segment
		(start 71.485 148.675)
		(end 70.735006 147.925006)
		(width 0.15)
		(layer "In5.Cu")
		(net 135)
	)
	(segment
		(start 70.565 159.86)
		(end 71.485 158.94)
		(width 0.15)
		(layer "In5.Cu")
		(net 135)
	)
	(segment
		(start 68.3807 135.163)
		(end 68.3807 134.151)
		(width 0.25)
		(layer "F.Cu")
		(net 136)
	)
	(segment
		(start 68.533588 135.315888)
		(end 68.3807 135.163)
		(width 0.25)
		(layer "F.Cu")
		(net 136)
	)
	(segment
		(start 69.765688 135.315888)
		(end 68.533588 135.315888)
		(width 0.25)
		(layer "F.Cu")
		(net 136)
	)
	(segment
		(start 72.598 154.19378)
		(end 72.598 152.507)
		(width 0.15)
		(layer "F.Cu")
		(net 136)
	)
	(via
		(at 69.765688 135.315888)
		(size 0.5)
		(drill 0.2)
		(layers "F.Cu" "B.Cu")
		(net 136)
	)
	(via blind
		(at 72.6 152.505)
		(size 0.5)
		(drill 0.2)
		(layers "F.Cu" "In2.Cu")
		(net 136)
	)
	(segment
		(start 69.7657 135.3159)
		(end 70.7807 135.3159)
		(width 0.25)
		(layer "B.Cu")
		(net 136)
	)
	(segment
		(start 72.6 151.83)
		(end 72.6 152.505)
		(width 0.15)
		(layer "In2.Cu")
		(net 136)
	)
	(segment
		(start 69.765688 135.315888)
		(end 72.455888 135.315888)
		(width 0.15)
		(layer "In2.Cu")
		(net 136)
	)
	(segment
		(start 72.455888 135.315888)
		(end 73.40499 136.26499)
		(width 0.15)
		(layer "In2.Cu")
		(net 136)
	)
	(segment
		(start 73.40499 136.26499)
		(end 73.40499 151.02501)
		(width 0.15)
		(layer "In2.Cu")
		(net 136)
	)
	(segment
		(start 73.40499 151.02501)
		(end 72.6 151.83)
		(width 0.15)
		(layer "In2.Cu")
		(net 136)
	)
	(segment
		(start 69.76568 139.31588)
		(end 66.95362 139.31588)
		(width 0.25)
		(layer "F.Cu")
		(net 137)
	)
	(segment
		(start 66.95362 139.31588)
		(end 65.8407 140.4288)
		(width 0.25)
		(layer "F.Cu")
		(net 137)
	)
	(segment
		(start 65.8407 140.4288)
		(end 65.8407 141.4408)
		(width 0.25)
		(layer "F.Cu")
		(net 137)
	)
	(segment
		(start 70.598 154.16878)
		(end 70.598 152.482)
		(width 0.15)
		(layer "F.Cu")
		(net 137)
	)
	(via
		(at 69.76568 139.31588)
		(size 0.5)
		(drill 0.2)
		(layers "F.Cu" "B.Cu")
		(net 137)
	)
	(via blind
		(at 70.6 152.48)
		(size 0.5)
		(drill 0.2)
		(layers "F.Cu" "In2.Cu")
		(net 137)
	)
	(segment
		(start 69.7657 139.3159)
		(end 70.7807 139.3159)
		(width 0.25)
		(layer "B.Cu")
		(net 137)
	)
	(segment
		(start 72.40495 150.610786)
		(end 72.40495 140.51495)
		(width 0.15)
		(layer "In2.Cu")
		(net 137)
	)
	(segment
		(start 72.40495 140.51495)
		(end 71.20588 139.31588)
		(width 0.15)
		(layer "In2.Cu")
		(net 137)
	)
	(segment
		(start 70.6 152.415736)
		(end 72.40495 150.610786)
		(width 0.15)
		(layer "In2.Cu")
		(net 137)
	)
	(segment
		(start 70.6 152.48)
		(end 70.6 152.415736)
		(width 0.15)
		(layer "In2.Cu")
		(net 137)
	)
	(segment
		(start 71.20588 139.31588)
		(end 69.76568 139.31588)
		(width 0.15)
		(layer "In2.Cu")
		(net 137)
	)
	(segment
		(start 67.223606 140.315894)
		(end 67.1107 140.4288)
		(width 0.25)
		(layer "F.Cu")
		(net 138)
	)
	(segment
		(start 69.765694 140.315894)
		(end 67.223606 140.315894)
		(width 0.25)
		(layer "F.Cu")
		(net 138)
	)
	(segment
		(start 67.1107 140.4288)
		(end 67.1107 141.4408)
		(width 0.25)
		(layer "F.Cu")
		(net 138)
	)
	(segment
		(start 70.085 154.42178)
		(end 70.085 153.04)
		(width 0.15)
		(layer "F.Cu")
		(net 138)
	)
	(via
		(at 69.765694 140.315894)
		(size 0.5)
		(drill 0.2)
		(layers "F.Cu" "B.Cu")
		(net 138)
	)
	(via blind
		(at 70.085 153.04)
		(size 0.5)
		(drill 0.2)
		(layers "F.Cu" "In2.Cu")
		(net 138)
	)
	(segment
		(start 69.7657 140.3159)
		(end 70.7807 140.3159)
		(width 0.25)
		(layer "B.Cu")
		(net 138)
	)
	(segment
		(start 72.15494 141.26494)
		(end 72.15494 150.296058)
		(width 0.15)
		(layer "In2.Cu")
		(net 138)
	)
	(segment
		(start 72.15494 150.296058)
		(end 70.085 152.365998)
		(width 0.15)
		(layer "In2.Cu")
		(net 138)
	)
	(segment
		(start 69.765694 140.315894)
		(end 71.205894 140.315894)
		(width 0.15)
		(layer "In2.Cu")
		(net 138)
	)
	(segment
		(start 70.085 152.365998)
		(end 70.085 153.04)
		(width 0.15)
		(layer "In2.Cu")
		(net 138)
	)
	(segment
		(start 71.205894 140.315894)
		(end 72.15494 141.26494)
		(width 0.15)
		(layer "In2.Cu")
		(net 138)
	)
	(segment
		(start 69.765702 137.315898)
		(end 66.765698 137.315898)
		(width 0.25)
		(layer "F.Cu")
		(net 139)
	)
	(segment
		(start 66.765698 137.315898)
		(end 65.8407 136.3909)
		(width 0.25)
		(layer "F.Cu")
		(net 139)
	)
	(segment
		(start 65.8407 136.3909)
		(end 65.8407 134.151)
		(width 0.25)
		(layer "F.Cu")
		(net 139)
	)
	(segment
		(start 71.598 154.16878)
		(end 71.598 152.482)
		(width 0.15)
		(layer "F.Cu")
		(net 139)
	)
	(via
		(at 69.765702 137.315898)
		(size 0.5)
		(drill 0.2)
		(layers "F.Cu" "B.Cu")
		(net 139)
	)
	(via blind
		(at 71.6 152.48)
		(size 0.5)
		(drill 0.2)
		(layers "F.Cu" "In2.Cu")
		(net 139)
	)
	(segment
		(start 69.7657 137.3159)
		(end 70.7807 137.3159)
		(width 0.25)
		(layer "B.Cu")
		(net 139)
	)
	(segment
		(start 71.6 152.122868)
		(end 72.90497 150.817898)
		(width 0.15)
		(layer "In2.Cu")
		(net 139)
	)
	(segment
		(start 72.90497 139.00497)
		(end 71.215898 137.315898)
		(width 0.15)
		(layer "In2.Cu")
		(net 139)
	)
	(segment
		(start 71.6 152.48)
		(end 71.6 152.122868)
		(width 0.15)
		(layer "In2.Cu")
		(net 139)
	)
	(segment
		(start 72.90497 150.817898)
		(end 72.90497 139.00497)
		(width 0.15)
		(layer "In2.Cu")
		(net 139)
	)
	(segment
		(start 71.215898 137.315898)
		(end 69.765702 137.315898)
		(width 0.15)
		(layer "In2.Cu")
		(net 139)
	)
	(segment
		(start 64.5707 140.4288)
		(end 64.5707 141.4408)
		(width 0.25)
		(layer "F.Cu")
		(net 140)
	)
	(segment
		(start 69.765694 138.315906)
		(end 66.683594 138.315906)
		(width 0.25)
		(layer "F.Cu")
		(net 140)
	)
	(segment
		(start 66.683594 138.315906)
		(end 64.5707 140.4288)
		(width 0.25)
		(layer "F.Cu")
		(net 140)
	)
	(segment
		(start 71.085 154.42178)
		(end 71.085 153.04)
		(width 0.15)
		(layer "F.Cu")
		(net 140)
	)
	(via
		(at 69.765694 138.315906)
		(size 0.5)
		(drill 0.2)
		(layers "F.Cu" "B.Cu")
		(net 140)
	)
	(via blind
		(at 71.085 153.04)
		(size 0.5)
		(drill 0.2)
		(layers "F.Cu" "In2.Cu")
		(net 140)
	)
	(segment
		(start 69.7657 138.3159)
		(end 70.7807 138.3159)
		(width 0.25)
		(layer "B.Cu")
		(net 140)
	)
	(segment
		(start 71.215906 138.315906)
		(end 69.765694 138.315906)
		(width 0.15)
		(layer "In2.Cu")
		(net 140)
	)
	(segment
		(start 72.65496 139.75496)
		(end 71.215906 138.315906)
		(width 0.15)
		(layer "In2.Cu")
		(net 140)
	)
	(segment
		(start 71.085 153.04)
		(end 71.085 152.284302)
		(width 0.15)
		(layer "In2.Cu")
		(net 140)
	)
	(segment
		(start 71.085 152.284302)
		(end 72.65496 150.714342)
		(width 0.15)
		(layer "In2.Cu")
		(net 140)
	)
	(segment
		(start 72.65496 150.714342)
		(end 72.65496 139.75496)
		(width 0.15)
		(layer "In2.Cu")
		(net 140)
	)
	(segment
		(start 104.85 99.702149)
		(end 104.85 101.5)
		(width 0.15)
		(layer "F.Cu")
		(net 141)
	)
	(segment
		(start 102.775 109.175)
		(end 102.275 108.675)
		(width 0.1)
		(layer "F.Cu")
		(net 141)
	)
	(via
		(at 104.85 101.5)
		(size 0.5)
		(drill 0.2)
		(layers "F.Cu" "B.Cu")
		(net 141)
	)
	(via blind
		(at 102.275 108.675)
		(size 0.5)
		(drill 0.2)
		(layers "F.Cu" "In2.Cu")
		(net 141)
	)
	(segment
		(start 102.275 108.675)
		(end 102.275 105.175)
		(width 0.15)
		(layer "In2.Cu")
		(net 141)
	)
	(segment
		(start 104.85 102.6)
		(end 104.85 101.5)
		(width 0.15)
		(layer "In2.Cu")
		(net 141)
	)
	(segment
		(start 102.275 105.175)
		(end 104.85 102.6)
		(width 0.15)
		(layer "In2.Cu")
		(net 141)
	)
	(segment
		(start 105.527149 100.822851)
		(end 105.5 100.85)
		(width 0.15)
		(layer "F.Cu")
		(net 142)
	)
	(segment
		(start 105.527149 98.975)
		(end 105.527149 100.822851)
		(width 0.15)
		(layer "F.Cu")
		(net 142)
	)
	(segment
		(start 101.775 110.175)
		(end 102.275 109.675)
		(width 0.1)
		(layer "F.Cu")
		(net 142)
	)
	(via
		(at 105.5 100.85)
		(size 0.5)
		(drill 0.2)
		(layers "F.Cu" "B.Cu")
		(net 142)
	)
	(via blind
		(at 102.275 109.675)
		(size 0.5)
		(drill 0.2)
		(layers "F.Cu" "In2.Cu")
		(net 142)
	)
	(segment
		(start 105.5 101.1)
		(end 105.5 100.85)
		(width 0.15)
		(layer "B.Cu")
		(net 142)
	)
	(segment
		(start 106.4 102.415)
		(end 106.4 102)
		(width 0.15)
		(layer "B.Cu")
		(net 142)
	)
	(segment
		(start 106.4 102)
		(end 105.5 101.1)
		(width 0.15)
		(layer "B.Cu")
		(net 142)
	)
	(segment
		(start 105.475 102.575)
		(end 102.975 105.075)
		(width 0.15)
		(layer "In2.Cu")
		(net 142)
	)
	(segment
		(start 105.5 100.85)
		(end 105.5 102.55)
		(width 0.15)
		(layer "In2.Cu")
		(net 142)
	)
	(segment
		(start 102.975 105.075)
		(end 102.975 108.975)
		(width 0.15)
		(layer "In2.Cu")
		(net 142)
	)
	(segment
		(start 102.975 108.975)
		(end 102.275 109.675)
		(width 0.15)
		(layer "In2.Cu")
		(net 142)
	)
	(segment
		(start 98.3 159.315)
		(end 98.3 158.5)
		(width 0.2)
		(layer "F.Cu")
		(net 143)
	)
	(segment
		(start 98.61 161.39)
		(end 98.6 161.4)
		(width 0.2)
		(layer "F.Cu")
		(net 143)
	)
	(segment
		(start 99.695 160.775)
		(end 100.2 160.775)
		(width 0.15)
		(layer "F.Cu")
		(net 143)
	)
	(segment
		(start 100.2 160.775)
		(end 100.6375 160.775)
		(width 0.15)
		(layer "F.Cu")
		(net 143)
	)
	(segment
		(start 99.375 161.39)
		(end 98.61 161.39)
		(width 0.2)
		(layer "F.Cu")
		(net 143)
	)
	(segment
		(start 99.375 161.095)
		(end 99.695 160.775)
		(width 0.15)
		(layer "F.Cu")
		(net 143)
	)
	(segment
		(start 98.675 159.775)
		(end 98.275 159.375)
		(width 0.15)
		(layer "F.Cu")
		(net 143)
	)
	(segment
		(start 100.6375 159.775)
		(end 98.675 159.775)
		(width 0.15)
		(layer "F.Cu")
		(net 143)
	)
	(segment
		(start 99.375 161.39)
		(end 99.375 161.095)
		(width 0.15)
		(layer "F.Cu")
		(net 143)
	)
	(via
		(at 98.6 161.4)
		(size 0.5)
		(drill 0.2)
		(layers "F.Cu" "B.Cu")
		(net 143)
	)
	(via
		(at 97.375 145.175)
		(size 0.5)
		(drill 0.2)
		(layers "F.Cu" "B.Cu")
		(net 143)
	)
	(via
		(at 99.7 151.1)
		(size 0.5)
		(drill 0.2)
		(layers "F.Cu" "B.Cu")
		(net 143)
	)
	(via
		(at 98.3 158.5)
		(size 0.5)
		(drill 0.2)
		(layers "F.Cu" "B.Cu")
		(net 143)
	)
	(segment
		(start 104.67 141.39)
		(end 106.575 143.295)
		(width 0.2)
		(layer "B.Cu")
		(net 143)
	)
	(segment
		(start 99.56 145.405)
		(end 99.075 145.89)
		(width 0.2)
		(layer "B.Cu")
		(net 143)
	)
	(segment
		(start 100.855 144.19)
		(end 100.59 144.455)
		(width 0.2)
		(layer "B.Cu")
		(net 143)
	)
	(segment
		(start 102.575 144.19)
		(end 100.855 144.19)
		(width 0.2)
		(layer "B.Cu")
		(net 143)
	)
	(segment
		(start 106.575 143.295)
		(end 106.575 143.59)
		(width 0.2)
		(layer "B.Cu")
		(net 143)
	)
	(segment
		(start 102.36 150.345)
		(end 102.175 150.16)
		(width 0.2)
		(layer "B.Cu")
		(net 143)
	)
	(segment
		(start 100.175 150.455)
		(end 99.7 150.93)
		(width 0.2)
		(layer "B.Cu")
		(net 143)
	)
	(segment
		(start 96.075 150.19)
		(end 104.145 150.19)
		(width 0.2)
		(layer "B.Cu")
		(net 143)
	)
	(segment
		(start 102.36 151.675)
		(end 102.36 150.345)
		(width 0.2)
		(layer "B.Cu")
		(net 143)
	)
	(segment
		(start 99.775 140.99)
		(end 100.26 140.99)
		(width 0.2)
		(layer "B.Cu")
		(net 143)
	)
	(segment
		(start 99.56 144.775)
		(end 100.59 144.775)
		(width 0.2)
		(layer "B.Cu")
		(net 143)
	)
	(segment
		(start 104.075 144.19)
		(end 104.575 144.69)
		(width 0.2)
		(layer "B.Cu")
		(net 143)
	)
	(segment
		(start 101.375 140.59)
		(end 102.175 141.39)
		(width 0.2)
		(layer "B.Cu")
		(net 143)
	)
	(segment
		(start 102.575 144.19)
		(end 103.575 144.19)
		(width 0.2)
		(layer "B.Cu")
		(net 143)
	)
	(segment
		(start 103.175 141.39)
		(end 104.175 141.39)
		(width 0.2)
		(layer "B.Cu")
		(net 143)
	)
	(segment
		(start 99.56 144.775)
		(end 99.56 145.405)
		(width 0.2)
		(layer "B.Cu")
		(net 143)
	)
	(segment
		(start 106.575 143.59)
		(end 106.575 143.69)
		(width 0.2)
		(layer "B.Cu")
		(net 143)
	)
	(segment
		(start 96.075 150.19)
		(end 95.005 150.19)
		(width 0.2)
		(layer "B.Cu")
		(net 143)
	)
	(segment
		(start 99.075 145.89)
		(end 100.075 145.89)
		(width 0.2)
		(layer "B.Cu")
		(net 143)
	)
	(segment
		(start 103.575 144.19)
		(end 104.075 144.19)
		(width 0.2)
		(layer "B.Cu")
		(net 143)
	)
	(segment
		(start 106.575 143.69)
		(end 105.575 144.69)
		(width 0.2)
		(layer "B.Cu")
		(net 143)
	)
	(segment
		(start 100.175 150.16)
		(end 100.175 150.455)
		(width 0.2)
		(layer "B.Cu")
		(net 143)
	)
	(segment
		(start 97.375 145.675)
		(end 97.375 145.175)
		(width 0.2)
		(layer "B.Cu")
		(net 143)
	)
	(segment
		(start 104.145 150.19)
		(end 104.175 150.16)
		(width 0.2)
		(layer "B.Cu")
		(net 143)
	)
	(segment
		(start 100.66 140.59)
		(end 101.175 140.59)
		(width 0.2)
		(layer "B.Cu")
		(net 143)
	)
	(segment
		(start 95.005 150.19)
		(end 94.975 150.16)
		(width 0.2)
		(layer "B.Cu")
		(net 143)
	)
	(segment
		(start 100.26 140.99)
		(end 100.66 140.59)
		(width 0.2)
		(layer "B.Cu")
		(net 143)
	)
	(segment
		(start 101.175 140.59)
		(end 101.375 140.59)
		(width 0.2)
		(layer "B.Cu")
		(net 143)
	)
	(segment
		(start 97.59 145.89)
		(end 97.375 145.675)
		(width 0.2)
		(layer "B.Cu")
		(net 143)
	)
	(segment
		(start 104.575 144.69)
		(end 105.575 144.69)
		(width 0.2)
		(layer "B.Cu")
		(net 143)
	)
	(segment
		(start 99.7 150.93)
		(end 99.7 151.1)
		(width 0.2)
		(layer "B.Cu")
		(net 143)
	)
	(segment
		(start 99.075 145.89)
		(end 97.59 145.89)
		(width 0.2)
		(layer "B.Cu")
		(net 143)
	)
	(segment
		(start 102.175 141.39)
		(end 103.175 141.39)
		(width 0.2)
		(layer "B.Cu")
		(net 143)
	)
	(segment
		(start 104.175 141.39)
		(end 104.67 141.39)
		(width 0.2)
		(layer "B.Cu")
		(net 143)
	)
	(segment
		(start 100.59 144.455)
		(end 100.59 144.775)
		(width 0.2)
		(layer "B.Cu")
		(net 143)
	)
	(segment
		(start 100.075 145.89)
		(end 101.075 145.89)
		(width 0.2)
		(layer "B.Cu")
		(net 143)
	)
	(segment
		(start 103.775 125.175)
		(end 104.275 125.675)
		(width 0.15)
		(layer "F.Cu")
		(net 144)
	)
	(segment
		(start 104.175 145.575)
		(end 106.074 145.575)
		(width 0.1)
		(layer "F.Cu")
		(net 144)
	)
	(via blind
		(at 104.275 125.675)
		(size 0.5)
		(drill 0.2)
		(layers "F.Cu" "In5.Cu")
		(net 144)
	)
	(via
		(at 106.275 145.575)
		(size 0.5)
		(drill 0.2)
		(layers "F.Cu" "B.Cu")
		(net 144)
	)
	(segment
		(start 106.575 145.275)
		(end 106.275 145.575)
		(width 0.2)
		(layer "B.Cu")
		(net 144)
	)
	(segment
		(start 106.575 144.56)
		(end 106.575 145.275)
		(width 0.2)
		(layer "B.Cu")
		(net 144)
	)
	(segment
		(start 104.957349 129.152747)
		(end 104.954842 129.175)
		(width 0.1)
		(layer "In5.Cu")
		(net 144)
	)
	(segment
		(start 106.045158 129.375)
		(end 106.042651 129.397252)
		(width 0.1)
		(layer "In5.Cu")
		(net 144)
	)
	(segment
		(start 105.175 129.565)
		(end 105.175 145.076)
		(width 0.1)
		(layer "In5.Cu")
		(net 144)
	)
	(segment
		(start 105.212652 129.496816)
		(end 105.196817 129.512651)
		(width 0.1)
		(layer "In5.Cu")
		(net 144)
	)
	(segment
		(start 105.054842 129.275)
		(end 105.945158 129.275)
		(width 0.1)
		(layer "In5.Cu")
		(net 144)
	)
	(segment
		(start 106.007507 129.453183)
		(end 105.988547 129.465096)
		(width 0.1)
		(layer "In5.Cu")
		(net 144)
	)
	(segment
		(start 105.165096 129.018388)
		(end 105.153183 129.037348)
		(width 0.1)
		(layer "In5.Cu")
		(net 144)
	)
	(segment
		(start 104.957349 129.197252)
		(end 104.964745 129.218388)
		(width 0.1)
		(layer "In5.Cu")
		(net 144)
	)
	(segment
		(start 106.035255 129.331611)
		(end 106.042651 129.352747)
		(width 0.1)
		(layer "In5.Cu")
		(net 144)
	)
	(segment
		(start 105.988547 129.465096)
		(end 105.967411 129.472492)
		(width 0.1)
		(layer "In5.Cu")
		(net 144)
	)
	(segment
		(start 104.992493 129.253183)
		(end 105.011453 129.265096)
		(width 0.1)
		(layer "In5.Cu")
		(net 144)
	)
	(segment
		(start 106.042651 129.397252)
		(end 106.035255 129.418388)
		(width 0.1)
		(layer "In5.Cu")
		(net 144)
	)
	(segment
		(start 105.172492 128.997252)
		(end 105.165096 129.018388)
		(width 0.1)
		(layer "In5.Cu")
		(net 144)
	)
	(segment
		(start 105.945158 129.475)
		(end 105.275 129.475)
		(width 0.1)
		(layer "In5.Cu")
		(net 144)
	)
	(segment
		(start 105.175 128.975)
		(end 105.172492 128.997252)
		(width 0.1)
		(layer "In5.Cu")
		(net 144)
	)
	(segment
		(start 105.175 145.076)
		(end 105.674 145.575)
		(width 0.1)
		(layer "In5.Cu")
		(net 144)
	)
	(segment
		(start 105.945158 129.275)
		(end 105.967411 129.277507)
		(width 0.1)
		(layer "In5.Cu")
		(net 144)
	)
	(segment
		(start 104.992493 129.096816)
		(end 104.976658 129.112651)
		(width 0.1)
		(layer "In5.Cu")
		(net 144)
	)
	(segment
		(start 105.097252 129.072492)
		(end 105.075 129.075)
		(width 0.1)
		(layer "In5.Cu")
		(net 144)
	)
	(segment
		(start 105.184904 129.531611)
		(end 105.177508 129.552747)
		(width 0.1)
		(layer "In5.Cu")
		(net 144)
	)
	(segment
		(start 105.196817 129.512651)
		(end 105.184904 129.531611)
		(width 0.1)
		(layer "In5.Cu")
		(net 144)
	)
	(segment
		(start 104.976658 129.112651)
		(end 104.964745 129.131611)
		(width 0.1)
		(layer "In5.Cu")
		(net 144)
	)
	(segment
		(start 105.153183 129.037348)
		(end 105.137348 129.053183)
		(width 0.1)
		(layer "In5.Cu")
		(net 144)
	)
	(segment
		(start 105.032589 129.077507)
		(end 105.011453 129.084903)
		(width 0.1)
		(layer "In5.Cu")
		(net 144)
	)
	(segment
		(start 105.967411 129.472492)
		(end 105.945158 129.475)
		(width 0.1)
		(layer "In5.Cu")
		(net 144)
	)
	(segment
		(start 105.075 129.075)
		(end 105.054842 129.075)
		(width 0.1)
		(layer "In5.Cu")
		(net 144)
	)
	(segment
		(start 106.023342 129.312651)
		(end 106.035255 129.331611)
		(width 0.1)
		(layer "In5.Cu")
		(net 144)
	)
	(segment
		(start 105.032589 129.272492)
		(end 105.054842 129.275)
		(width 0.1)
		(layer "In5.Cu")
		(net 144)
	)
	(segment
		(start 105.175 126.575)
		(end 105.175 128.975)
		(width 0.1)
		(layer "In5.Cu")
		(net 144)
	)
	(segment
		(start 106.042651 129.352747)
		(end 106.045158 129.375)
		(width 0.1)
		(layer "In5.Cu")
		(net 144)
	)
	(segment
		(start 105.011453 129.265096)
		(end 105.032589 129.272492)
		(width 0.1)
		(layer "In5.Cu")
		(net 144)
	)
	(segment
		(start 105.275 129.475)
		(end 105.252748 129.477507)
		(width 0.1)
		(layer "In5.Cu")
		(net 144)
	)
	(segment
		(start 104.964745 129.131611)
		(end 104.957349 129.152747)
		(width 0.1)
		(layer "In5.Cu")
		(net 144)
	)
	(segment
		(start 105.011453 129.084903)
		(end 104.992493 129.096816)
		(width 0.1)
		(layer "In5.Cu")
		(net 144)
	)
	(segment
		(start 104.954842 129.175)
		(end 104.957349 129.197252)
		(width 0.1)
		(layer "In5.Cu")
		(net 144)
	)
	(segment
		(start 105.967411 129.277507)
		(end 105.988547 129.284903)
		(width 0.1)
		(layer "In5.Cu")
		(net 144)
	)
	(segment
		(start 105.054842 129.075)
		(end 105.032589 129.077507)
		(width 0.1)
		(layer "In5.Cu")
		(net 144)
	)
	(segment
		(start 105.674 145.575)
		(end 106.074 145.575)
		(width 0.1)
		(layer "In5.Cu")
		(net 144)
	)
	(segment
		(start 105.988547 129.284903)
		(end 106.007507 129.296816)
		(width 0.1)
		(layer "In5.Cu")
		(net 144)
	)
	(segment
		(start 106.007507 129.296816)
		(end 106.023342 129.312651)
		(width 0.1)
		(layer "In5.Cu")
		(net 144)
	)
	(segment
		(start 105.137348 129.053183)
		(end 105.118388 129.065096)
		(width 0.1)
		(layer "In5.Cu")
		(net 144)
	)
	(segment
		(start 104.275 125.675)
		(end 105.175 126.575)
		(width 0.1)
		(layer "In5.Cu")
		(net 144)
	)
	(segment
		(start 105.118388 129.065096)
		(end 105.097252 129.072492)
		(width 0.1)
		(layer "In5.Cu")
		(net 144)
	)
	(segment
		(start 104.976658 129.237348)
		(end 104.992493 129.253183)
		(width 0.1)
		(layer "In5.Cu")
		(net 144)
	)
	(segment
		(start 105.231612 129.484903)
		(end 105.212652 129.496816)
		(width 0.1)
		(layer "In5.Cu")
		(net 144)
	)
	(segment
		(start 105.177508 129.552747)
		(end 105.175 129.575)
		(width 0.1)
		(layer "In5.Cu")
		(net 144)
	)
	(segment
		(start 106.035255 129.418388)
		(end 106.023342 129.437348)
		(width 0.1)
		(layer "In5.Cu")
		(net 144)
	)
	(segment
		(start 106.023342 129.437348)
		(end 106.007507 129.453183)
		(width 0.1)
		(layer "In5.Cu")
		(net 144)
	)
	(segment
		(start 105.252748 129.477507)
		(end 105.231612 129.484903)
		(width 0.1)
		(layer "In5.Cu")
		(net 144)
	)
	(segment
		(start 104.964745 129.218388)
		(end 104.976658 129.237348)
		(width 0.1)
		(layer "In5.Cu")
		(net 144)
	)
	(segment
		(start 101.775 125.175)
		(end 102.275 125.675)
		(width 0.15)
		(layer "F.Cu")
		(net 145)
	)
	(segment
		(start 104.175 144.775)
		(end 103.775 144.375)
		(width 0.1)
		(layer "F.Cu")
		(net 145)
	)
	(segment
		(start 103.775 144.375)
		(end 103.775 143.375)
		(width 0.1)
		(layer "F.Cu")
		(net 145)
	)
	(via blind
		(at 102.275 125.675)
		(size 0.5)
		(drill 0.2)
		(layers "F.Cu" "In5.Cu")
		(net 145)
	)
	(via
		(at 103.775 143.375)
		(size 0.5)
		(drill 0.2)
		(layers "F.Cu" "B.Cu")
		(net 145)
	)
	(segment
		(start 103.775 143.375)
		(end 104.175 142.975)
		(width 0.1)
		(layer "B.Cu")
		(net 145)
	)
	(segment
		(start 104.175 142.975)
		(end 104.175 142.36)
		(width 0.1)
		(layer "B.Cu")
		(net 145)
	)
	(segment
		(start 103.186984 127.375)
		(end 103.164731 127.377507)
		(width 0.1)
		(layer "In5.Cu")
		(net 145)
	)
	(segment
		(start 103.089491 127.497252)
		(end 103.096887 127.518388)
		(width 0.1)
		(layer "In5.Cu")
		(net 145)
	)
	(segment
		(start 103.318388 127.365096)
		(end 103.297252 127.372492)
		(width 0.1)
		(layer "In5.Cu")
		(net 145)
	)
	(segment
		(start 103.096887 127.831611)
		(end 103.089491 127.852747)
		(width 0.1)
		(layer "In5.Cu")
		(net 145)
	)
	(segment
		(start 103.775365 127.753183)
		(end 103.756405 127.765096)
		(width 0.1)
		(layer "In5.Cu")
		(net 145)
	)
	(segment
		(start 103.143595 127.965096)
		(end 103.164731 127.972492)
		(width 0.1)
		(layer "In5.Cu")
		(net 145)
	)
	(segment
		(start 103.089491 127.452747)
		(end 103.086984 127.475)
		(width 0.1)
		(layer "In5.Cu")
		(net 145)
	)
	(segment
		(start 104.003113 128.118388)
		(end 103.9912 128.137348)
		(width 0.1)
		(layer "In5.Cu")
		(net 145)
	)
	(segment
		(start 103.775 142.675)
		(end 103.775 143.375)
		(width 0.1)
		(layer "In5.Cu")
		(net 145)
	)
	(segment
		(start 103.713016 127.575)
		(end 103.735269 127.577507)
		(width 0.1)
		(layer "In5.Cu")
		(net 145)
	)
	(segment
		(start 103.735269 127.772492)
		(end 103.713016 127.775)
		(width 0.1)
		(layer "In5.Cu")
		(net 145)
	)
	(segment
		(start 103.975365 128.153183)
		(end 103.956405 128.165096)
		(width 0.1)
		(layer "In5.Cu")
		(net 145)
	)
	(segment
		(start 103.475 128.175)
		(end 103.452748 128.177507)
		(width 0.1)
		(layer "In5.Cu")
		(net 145)
	)
	(segment
		(start 103.452748 128.177507)
		(end 103.431612 128.184903)
		(width 0.1)
		(layer "In5.Cu")
		(net 145)
	)
	(segment
		(start 103.9912 128.012651)
		(end 104.003113 128.031611)
		(width 0.1)
		(layer "In5.Cu")
		(net 145)
	)
	(segment
		(start 102.275 125.675)
		(end 103.375 126.775)
		(width 0.1)
		(layer "In5.Cu")
		(net 145)
	)
	(segment
		(start 103.143595 127.565096)
		(end 103.164731 127.572492)
		(width 0.1)
		(layer "In5.Cu")
		(net 145)
	)
	(segment
		(start 103.810509 127.652747)
		(end 103.813016 127.675)
		(width 0.1)
		(layer "In5.Cu")
		(net 145)
	)
	(segment
		(start 103.375 127.275)
		(end 103.372492 127.297252)
		(width 0.1)
		(layer "In5.Cu")
		(net 145)
	)
	(segment
		(start 103.803113 127.631611)
		(end 103.810509 127.652747)
		(width 0.1)
		(layer "In5.Cu")
		(net 145)
	)
	(segment
		(start 103.124635 127.553183)
		(end 103.143595 127.565096)
		(width 0.1)
		(layer "In5.Cu")
		(net 145)
	)
	(segment
		(start 103.9912 128.137348)
		(end 103.975365 128.153183)
		(width 0.1)
		(layer "In5.Cu")
		(net 145)
	)
	(segment
		(start 103.124635 127.796816)
		(end 103.1088 127.812651)
		(width 0.1)
		(layer "In5.Cu")
		(net 145)
	)
	(segment
		(start 103.913016 128.175)
		(end 103.475 128.175)
		(width 0.1)
		(layer "In5.Cu")
		(net 145)
	)
	(segment
		(start 103.7912 127.612651)
		(end 103.803113 127.631611)
		(width 0.1)
		(layer "In5.Cu")
		(net 145)
	)
	(segment
		(start 103.375 126.775)
		(end 103.375 127.275)
		(width 0.1)
		(layer "In5.Cu")
		(net 145)
	)
	(segment
		(start 103.756405 127.584903)
		(end 103.775365 127.596816)
		(width 0.1)
		(layer "In5.Cu")
		(net 145)
	)
	(segment
		(start 103.096887 127.431611)
		(end 103.089491 127.452747)
		(width 0.1)
		(layer "In5.Cu")
		(net 145)
	)
	(segment
		(start 103.143595 127.384903)
		(end 103.124635 127.396816)
		(width 0.1)
		(layer "In5.Cu")
		(net 145)
	)
	(segment
		(start 103.275 127.375)
		(end 103.186984 127.375)
		(width 0.1)
		(layer "In5.Cu")
		(net 145)
	)
	(segment
		(start 103.935269 127.977507)
		(end 103.956405 127.984903)
		(width 0.1)
		(layer "In5.Cu")
		(net 145)
	)
	(segment
		(start 103.803113 127.718388)
		(end 103.7912 127.737348)
		(width 0.1)
		(layer "In5.Cu")
		(net 145)
	)
	(segment
		(start 103.377508 128.252747)
		(end 103.375 128.275)
		(width 0.1)
		(layer "In5.Cu")
		(net 145)
	)
	(segment
		(start 103.975365 127.996816)
		(end 103.9912 128.012651)
		(width 0.1)
		(layer "In5.Cu")
		(net 145)
	)
	(segment
		(start 103.431612 128.184903)
		(end 103.412652 128.196816)
		(width 0.1)
		(layer "In5.Cu")
		(net 145)
	)
	(segment
		(start 103.1088 127.412651)
		(end 103.096887 127.431611)
		(width 0.1)
		(layer "In5.Cu")
		(net 145)
	)
	(segment
		(start 103.186984 127.975)
		(end 103.913016 127.975)
		(width 0.1)
		(layer "In5.Cu")
		(net 145)
	)
	(segment
		(start 103.935269 128.172492)
		(end 103.913016 128.175)
		(width 0.1)
		(layer "In5.Cu")
		(net 145)
	)
	(segment
		(start 103.096887 127.518388)
		(end 103.1088 127.537348)
		(width 0.1)
		(layer "In5.Cu")
		(net 145)
	)
	(segment
		(start 103.384904 128.231611)
		(end 103.377508 128.252747)
		(width 0.1)
		(layer "In5.Cu")
		(net 145)
	)
	(segment
		(start 103.143595 127.784903)
		(end 103.124635 127.796816)
		(width 0.1)
		(layer "In5.Cu")
		(net 145)
	)
	(segment
		(start 103.1088 127.937348)
		(end 103.124635 127.953183)
		(width 0.1)
		(layer "In5.Cu")
		(net 145)
	)
	(segment
		(start 103.186984 127.775)
		(end 103.164731 127.777507)
		(width 0.1)
		(layer "In5.Cu")
		(net 145)
	)
	(segment
		(start 103.375 142.275)
		(end 103.775 142.675)
		(width 0.1)
		(layer "In5.Cu")
		(net 145)
	)
	(segment
		(start 103.337348 127.353183)
		(end 103.318388 127.365096)
		(width 0.1)
		(layer "In5.Cu")
		(net 145)
	)
	(segment
		(start 103.956405 127.984903)
		(end 103.975365 127.996816)
		(width 0.1)
		(layer "In5.Cu")
		(net 145)
	)
	(segment
		(start 103.124635 127.953183)
		(end 103.143595 127.965096)
		(width 0.1)
		(layer "In5.Cu")
		(net 145)
	)
	(segment
		(start 103.089491 127.852747)
		(end 103.086984 127.875)
		(width 0.1)
		(layer "In5.Cu")
		(net 145)
	)
	(segment
		(start 103.372492 127.297252)
		(end 103.365096 127.318388)
		(width 0.1)
		(layer "In5.Cu")
		(net 145)
	)
	(segment
		(start 103.164731 127.972492)
		(end 103.186984 127.975)
		(width 0.1)
		(layer "In5.Cu")
		(net 145)
	)
	(segment
		(start 103.297252 127.372492)
		(end 103.275 127.375)
		(width 0.1)
		(layer "In5.Cu")
		(net 145)
	)
	(segment
		(start 103.810509 127.697252)
		(end 103.803113 127.718388)
		(width 0.1)
		(layer "In5.Cu")
		(net 145)
	)
	(segment
		(start 103.1088 127.812651)
		(end 103.096887 127.831611)
		(width 0.1)
		(layer "In5.Cu")
		(net 145)
	)
	(segment
		(start 103.713016 127.775)
		(end 103.186984 127.775)
		(width 0.1)
		(layer "In5.Cu")
		(net 145)
	)
	(segment
		(start 103.086984 127.475)
		(end 103.089491 127.497252)
		(width 0.1)
		(layer "In5.Cu")
		(net 145)
	)
	(segment
		(start 104.003113 128.031611)
		(end 104.010509 128.052747)
		(width 0.1)
		(layer "In5.Cu")
		(net 145)
	)
	(segment
		(start 103.775365 127.596816)
		(end 103.7912 127.612651)
		(width 0.1)
		(layer "In5.Cu")
		(net 145)
	)
	(segment
		(start 103.086984 127.875)
		(end 103.089491 127.897252)
		(width 0.1)
		(layer "In5.Cu")
		(net 145)
	)
	(segment
		(start 103.913016 127.975)
		(end 103.935269 127.977507)
		(width 0.1)
		(layer "In5.Cu")
		(net 145)
	)
	(segment
		(start 103.353183 127.337348)
		(end 103.337348 127.353183)
		(width 0.1)
		(layer "In5.Cu")
		(net 145)
	)
	(segment
		(start 103.813016 127.675)
		(end 103.810509 127.697252)
		(width 0.1)
		(layer "In5.Cu")
		(net 145)
	)
	(segment
		(start 103.956405 128.165096)
		(end 103.935269 128.172492)
		(width 0.1)
		(layer "In5.Cu")
		(net 145)
	)
	(segment
		(start 103.124635 127.396816)
		(end 103.1088 127.412651)
		(width 0.1)
		(layer "In5.Cu")
		(net 145)
	)
	(segment
		(start 103.164731 127.572492)
		(end 103.186984 127.575)
		(width 0.1)
		(layer "In5.Cu")
		(net 145)
	)
	(segment
		(start 103.089491 127.897252)
		(end 103.096887 127.918388)
		(width 0.1)
		(layer "In5.Cu")
		(net 145)
	)
	(segment
		(start 103.164731 127.777507)
		(end 103.143595 127.784903)
		(width 0.1)
		(layer "In5.Cu")
		(net 145)
	)
	(segment
		(start 103.164731 127.377507)
		(end 103.143595 127.384903)
		(width 0.1)
		(layer "In5.Cu")
		(net 145)
	)
	(segment
		(start 103.396817 128.212651)
		(end 103.384904 128.231611)
		(width 0.1)
		(layer "In5.Cu")
		(net 145)
	)
	(segment
		(start 103.375 128.275)
		(end 103.375 142.275)
		(width 0.1)
		(layer "In5.Cu")
		(net 145)
	)
	(segment
		(start 103.096887 127.918388)
		(end 103.1088 127.937348)
		(width 0.1)
		(layer "In5.Cu")
		(net 145)
	)
	(segment
		(start 103.735269 127.577507)
		(end 103.756405 127.584903)
		(width 0.1)
		(layer "In5.Cu")
		(net 145)
	)
	(segment
		(start 103.7912 127.737348)
		(end 103.775365 127.753183)
		(width 0.1)
		(layer "In5.Cu")
		(net 145)
	)
	(segment
		(start 104.010509 128.052747)
		(end 104.013016 128.075)
		(width 0.1)
		(layer "In5.Cu")
		(net 145)
	)
	(segment
		(start 103.756405 127.765096)
		(end 103.735269 127.772492)
		(width 0.1)
		(layer "In5.Cu")
		(net 145)
	)
	(segment
		(start 103.412652 128.196816)
		(end 103.396817 128.212651)
		(width 0.1)
		(layer "In5.Cu")
		(net 145)
	)
	(segment
		(start 103.1088 127.537348)
		(end 103.124635 127.553183)
		(width 0.1)
		(layer "In5.Cu")
		(net 145)
	)
	(segment
		(start 104.010509 128.097252)
		(end 104.003113 128.118388)
		(width 0.1)
		(layer "In5.Cu")
		(net 145)
	)
	(segment
		(start 104.013016 128.075)
		(end 104.010509 128.097252)
		(width 0.1)
		(layer "In5.Cu")
		(net 145)
	)
	(segment
		(start 103.365096 127.318388)
		(end 103.353183 127.337348)
		(width 0.1)
		(layer "In5.Cu")
		(net 145)
	)
	(segment
		(start 103.186984 127.575)
		(end 103.713016 127.575)
		(width 0.1)
		(layer "In5.Cu")
		(net 145)
	)
	(segment
		(start 103.375 144.775)
		(end 102.975 144.375)
		(width 0.1)
		(layer "F.Cu")
		(net 146)
	)
	(segment
		(start 102.975 144.375)
		(end 102.975 143.375)
		(width 0.1)
		(layer "F.Cu")
		(net 146)
	)
	(segment
		(start 102.775 128.175)
		(end 103.275 127.675)
		(width 0.15)
		(layer "F.Cu")
		(net 146)
	)
	(via
		(at 102.975 143.375)
		(size 0.5)
		(drill 0.2)
		(layers "F.Cu" "B.Cu")
		(net 146)
	)
	(via blind
		(at 103.275 127.675)
		(size 0.5)
		(drill 0.2)
		(layers "F.Cu" "In2.Cu")
		(net 146)
	)
	(segment
		(start 102.975 143.375)
		(end 102.975 142.56)
		(width 0.1)
		(layer "B.Cu")
		(net 146)
	)
	(segment
		(start 102.975 142.56)
		(end 103.175 142.36)
		(width 0.1)
		(layer "B.Cu")
		(net 146)
	)
	(segment
		(start 103.149967 138.611971)
		(end 103.161665 138.630589)
		(width 0.1)
		(layer "In2.Cu")
		(net 146)
	)
	(segment
		(start 102.781072 137.651343)
		(end 102.778611 137.673194)
		(width 0.1)
		(layer "In2.Cu")
		(net 146)
	)
	(segment
		(start 102.953577 139.411971)
		(end 102.965275 139.430589)
		(width 0.1)
		(layer "In2.Cu")
		(net 146)
	)
	(segment
		(start 103.134418 137.396422)
		(end 103.149967 137.411971)
		(width 0.1)
		(layer "In2.Cu")
		(net 146)
	)
	(segment
		(start 103.073195 137.975)
		(end 102.876805 137.975)
		(width 0.1)
		(layer "In2.Cu")
		(net 146)
	)
	(segment
		(start 102.876805 138.175)
		(end 103.073195 138.175)
		(width 0.1)
		(layer "In2.Cu")
		(net 146)
	)
	(segment
		(start 102.778611 136.876806)
		(end 102.781072 136.898656)
		(width 0.1)
		(layer "In2.Cu")
		(net 146)
	)
	(segment
		(start 102.788335 138.430589)
		(end 102.781072 138.451343)
		(width 0.1)
		(layer "In2.Cu")
		(net 146)
	)
	(segment
		(start 103.171389 139.073194)
		(end 103.171389 139.076806)
		(width 0.1)
		(layer "In2.Cu")
		(net 146)
	)
	(segment
		(start 103.161665 138.630589)
		(end 103.168928 138.651343)
		(width 0.1)
		(layer "In2.Cu")
		(net 146)
	)
	(segment
		(start 103.073195 138.175)
		(end 103.095046 138.177461)
		(width 0.1)
		(layer "In2.Cu")
		(net 146)
	)
	(segment
		(start 103.134418 137.796422)
		(end 103.149967 137.811971)
		(width 0.1)
		(layer "In2.Cu")
		(net 146)
	)
	(segment
		(start 102.8342 136.565275)
		(end 102.854954 136.572538)
		(width 0.1)
		(layer "In2.Cu")
		(net 146)
	)
	(segment
		(start 102.778611 137.276806)
		(end 102.781072 137.298656)
		(width 0.1)
		(layer "In2.Cu")
		(net 146)
	)
	(segment
		(start 102.8342 138.165275)
		(end 102.854954 138.172538)
		(width 0.1)
		(layer "In2.Cu")
		(net 146)
	)
	(segment
		(start 102.778611 137.676806)
		(end 102.781072 137.698656)
		(width 0.1)
		(layer "In2.Cu")
		(net 146)
	)
	(segment
		(start 102.854954 136.972538)
		(end 102.876805 136.975)
		(width 0.1)
		(layer "In2.Cu")
		(net 146)
	)
	(segment
		(start 102.876805 137.175)
		(end 102.854954 137.177461)
		(width 0.1)
		(layer "In2.Cu")
		(net 146)
	)
	(segment
		(start 102.875011 128.074989)
		(end 102.875011 129.300097)
		(width 0.1)
		(layer "In2.Cu")
		(net 146)
	)
	(segment
		(start 102.800033 139.338028)
		(end 102.815582 139.353577)
		(width 0.1)
		(layer "In2.Cu")
		(net 146)
	)
	(segment
		(start 102.8342 137.765275)
		(end 102.854954 137.772538)
		(width 0.1)
		(layer "In2.Cu")
		(net 146)
	)
	(segment
		(start 102.854954 137.977461)
		(end 102.8342 137.984724)
		(width 0.1)
		(layer "In2.Cu")
		(net 146)
	)
	(segment
		(start 102.800033 139.211971)
		(end 102.788335 139.230589)
		(width 0.1)
		(layer "In2.Cu")
		(net 146)
	)
	(segment
		(start 103.134418 137.953577)
		(end 103.1158 137.965275)
		(width 0.1)
		(layer "In2.Cu")
		(net 146)
	)
	(segment
		(start 102.788335 136.117604)
		(end 102.800033 136.136222)
		(width 0.1)
		(layer "In2.Cu")
		(net 146)
	)
	(segment
		(start 103.073195 136.975)
		(end 103.095046 136.977461)
		(width 0.1)
		(layer "In2.Cu")
		(net 146)
	)
	(segment
		(start 102.800033 138.411971)
		(end 102.788335 138.430589)
		(width 0.1)
		(layer "In2.Cu")
		(net 146)
	)
	(segment
		(start 102.8342 137.365275)
		(end 102.854954 137.372538)
		(width 0.1)
		(layer "In2.Cu")
		(net 146)
	)
	(segment
		(start 102.800033 138.538028)
		(end 102.815582 138.553577)
		(width 0.1)
		(layer "In2.Cu")
		(net 146)
	)
	(segment
		(start 103.149967 137.538028)
		(end 103.134418 137.553577)
		(width 0.1)
		(layer "In2.Cu")
		(net 146)
	)
	(segment
		(start 103.168928 137.851343)
		(end 103.171389 137.873194)
		(width 0.1)
		(layer "In2.Cu")
		(net 146)
	)
	(segment
		(start 102.854954 136.777461)
		(end 102.8342 136.784724)
		(width 0.1)
		(layer "In2.Cu")
		(net 146)
	)
	(segment
		(start 103.149967 136.338028)
		(end 103.134418 136.353577)
		(width 0.1)
		(layer "In2.Cu")
		(net 146)
	)
	(segment
		(start 103.175022 142.584392)
		(end 102.975 142.784414)
		(width 0.1)
		(layer "In2.Cu")
		(net 146)
	)
	(segment
		(start 102.8342 139.184724)
		(end 102.815582 139.196422)
		(width 0.1)
		(layer "In2.Cu")
		(net 146)
	)
	(segment
		(start 103.161665 136.630589)
		(end 103.168928 136.651343)
		(width 0.1)
		(layer "In2.Cu")
		(net 146)
	)
	(segment
		(start 102.876805 138.775)
		(end 102.854954 138.777461)
		(width 0.1)
		(layer "In2.Cu")
		(net 146)
	)
	(segment
		(start 102.876805 137.375)
		(end 103.073195 137.375)
		(width 0.1)
		(layer "In2.Cu")
		(net 146)
	)
	(segment
		(start 103.134418 138.353577)
		(end 103.1158 138.365275)
		(width 0.1)
		(layer "In2.Cu")
		(net 146)
	)
	(segment
		(start 103.095046 137.572538)
		(end 103.073195 137.575)
		(width 0.1)
		(layer "In2.Cu")
		(net 146)
	)
	(segment
		(start 102.815582 139.353577)
		(end 102.8342 139.365275)
		(width 0.1)
		(layer "In2.Cu")
		(net 146)
	)
	(segment
		(start 103.095046 137.377461)
		(end 103.1158 137.384724)
		(width 0.1)
		(layer "In2.Cu")
		(net 146)
	)
	(segment
		(start 102.854954 137.372538)
		(end 102.876805 137.375)
		(width 0.1)
		(layer "In2.Cu")
		(net 146)
	)
	(segment
		(start 103.161665 137.830589)
		(end 103.168928 137.851343)
		(width 0.1)
		(layer "In2.Cu")
		(net 146)
	)
	(segment
		(start 102.800033 138.938028)
		(end 102.815582 138.953577)
		(width 0.1)
		(layer "In2.Cu")
		(net 146)
	)
	(segment
		(start 102.876805 137.975)
		(end 102.854954 137.977461)
		(width 0.1)
		(layer "In2.Cu")
		(net 146)
	)
	(segment
		(start 102.781072 136.049537)
		(end 102.778611 136.071388)
		(width 0.1)
		(layer "In2.Cu")
		(net 146)
	)
	(segment
		(start 102.8342 137.584724)
		(end 102.815582 137.596422)
		(width 0.1)
		(layer "In2.Cu")
		(net 146)
	)
	(segment
		(start 103.149967 137.138028)
		(end 103.134418 137.153577)
		(width 0.1)
		(layer "In2.Cu")
		(net 146)
	)
	(segment
		(start 103.095046 136.372538)
		(end 103.073195 136.375)
		(width 0.1)
		(layer "In2.Cu")
		(net 146)
	)
	(segment
		(start 102.778611 136.873194)
		(end 102.778611 136.876806)
		(width 0.1)
		(layer "In2.Cu")
		(net 146)
	)
	(segment
		(start 102.876805 136.775)
		(end 102.854954 136.777461)
		(width 0.1)
		(layer "In2.Cu")
		(net 146)
	)
	(segment
		(start 102.815582 135.994616)
		(end 102.800033 136.010165)
		(width 0.1)
		(layer "In2.Cu")
		(net 146)
	)
	(segment
		(start 103.134418 136.753577)
		(end 103.1158 136.765275)
		(width 0.1)
		(layer "In2.Cu")
		(net 146)
	)
	(segment
		(start 102.876805 138.575)
		(end 103.073195 138.575)
		(width 0.1)
		(layer "In2.Cu")
		(net 146)
	)
	(segment
		(start 102.815582 137.996422)
		(end 102.800033 138.011971)
		(width 0.1)
		(layer "In2.Cu")
		(net 146)
	)
	(segment
		(start 102.975066 129.400152)
		(end 102.975065 130.757793)
		(width 0.1)
		(layer "In2.Cu")
		(net 146)
	)
	(segment
		(start 102.778611 136.476806)
		(end 102.781072 136.498656)
		(width 0.1)
		(layer "In2.Cu")
		(net 146)
	)
	(segment
		(start 102.8342 138.965275)
		(end 102.854954 138.972538)
		(width 0.1)
		(layer "In2.Cu")
		(net 146)
	)
	(segment
		(start 102.815582 138.796422)
		(end 102.800033 138.811971)
		(width 0.1)
		(layer "In2.Cu")
		(net 146)
	)
	(segment
		(start 102.800033 138.811971)
		(end 102.788335 138.830589)
		(width 0.1)
		(layer "In2.Cu")
		(net 146)
	)
	(segment
		(start 102.975 142.784414)
		(end 102.975 143.375)
		(width 0.1)
		(layer "In2.Cu")
		(net 146)
	)
	(segment
		(start 103.149967 138.738028)
		(end 103.134418 138.753577)
		(width 0.1)
		(layer "In2.Cu")
		(net 146)
	)
	(segment
		(start 103.171389 136.673194)
		(end 103.171389 136.676806)
		(width 0.1)
		(layer "In2.Cu")
		(net 146)
	)
	(segment
		(start 102.800033 137.611971)
		(end 102.788335 137.630589)
		(width 0.1)
		(layer "In2.Cu")
		(net 146)
	)
	(segment
		(start 103.171389 137.476806)
		(end 103.168928 137.498656)
		(width 0.1)
		(layer "In2.Cu")
		(net 146)
	)
	(segment
		(start 103.134418 136.596422)
		(end 103.149967 136.611971)
		(width 0.1)
		(layer "In2.Cu")
		(net 146)
	)
	(segment
		(start 103.149967 137.938028)
		(end 103.134418 137.953577)
		(width 0.1)
		(layer "In2.Cu")
		(net 146)
	)
	(segment
		(start 103.134418 137.153577)
		(end 103.1158 137.165275)
		(width 0.1)
		(layer "In2.Cu")
		(net 146)
	)
	(segment
		(start 102.815582 137.353577)
		(end 102.8342 137.365275)
		(width 0.1)
		(layer "In2.Cu")
		(net 146)
	)
	(segment
		(start 102.781072 137.298656)
		(end 102.788335 137.31941)
		(width 0.1)
		(layer "In2.Cu")
		(net 146)
	)
	(segment
		(start 103.095046 136.772538)
		(end 103.073195 136.775)
		(width 0.1)
		(layer "In2.Cu")
		(net 146)
	)
	(segment
		(start 103.168928 138.298656)
		(end 103.161665 138.31941)
		(width 0.1)
		(layer "In2.Cu")
		(net 146)
	)
	(segment
		(start 103.149967 138.338028)
		(end 103.134418 138.353577)
		(width 0.1)
		(layer "In2.Cu")
		(net 146)
	)
	(segment
		(start 102.91941 135.963469)
		(end 102.898656 135.970732)
		(width 0.1)
		(layer "In2.Cu")
		(net 146)
	)
	(segment
		(start 102.815582 136.396422)
		(end 102.800033 136.411971)
		(width 0.1)
		(layer "In2.Cu")
		(net 146)
	)
	(segment
		(start 102.8342 138.565275)
		(end 102.854954 138.572538)
		(width 0.1)
		(layer "In2.Cu")
		(net 146)
	)
	(segment
		(start 102.938028 139.396422)
		(end 102.953577 139.411971)
		(width 0.1)
		(layer "In2.Cu")
		(net 146)
	)
	(segment
		(start 102.800033 136.411971)
		(end 102.788335 136.430589)
		(width 0.1)
		(layer "In2.Cu")
		(net 146)
	)
	(segment
		(start 103.168928 137.098656)
		(end 103.161665 137.11941)
		(width 0.1)
		(layer "In2.Cu")
		(net 146)
	)
	(segment
		(start 103.134418 136.996422)
		(end 103.149967 137.011971)
		(width 0.1)
		(layer "In2.Cu")
		(net 146)
	)
	(segment
		(start 103.073195 136.575)
		(end 103.095046 136.577461)
		(width 0.1)
		(layer "In2.Cu")
		(net 146)
	)
	(segment
		(start 102.815582 138.153577)
		(end 102.8342 138.165275)
		(width 0.1)
		(layer "In2.Cu")
		(net 146)
	)
	(segment
		(start 103.161665 139.11941)
		(end 103.149967 139.138028)
		(width 0.1)
		(layer "In2.Cu")
		(net 146)
	)
	(segment
		(start 102.788335 138.030589)
		(end 102.781072 138.051343)
		(width 0.1)
		(layer "In2.Cu")
		(net 146)
	)
	(segment
		(start 102.8342 137.184724)
		(end 102.815582 137.196422)
		(width 0.1)
		(layer "In2.Cu")
		(net 146)
	)
	(segment
		(start 102.778611 136.075)
		(end 102.781072 136.09685)
		(width 0.1)
		(layer "In2.Cu")
		(net 146)
	)
	(segment
		(start 103.171389 138.276806)
		(end 103.168928 138.298656)
		(width 0.1)
		(layer "In2.Cu")
		(net 146)
	)
	(segment
		(start 103.073195 136.775)
		(end 102.876805 136.775)
		(width 0.1)
		(layer "In2.Cu")
		(net 146)
	)
	(segment
		(start 102.778611 138.073194)
		(end 102.778611 138.076806)
		(width 0.1)
		(layer "In2.Cu")
		(net 146)
	)
	(segment
		(start 102.876805 138.975)
		(end 103.073195 138.975)
		(width 0.1)
		(layer "In2.Cu")
		(net 146)
	)
	(segment
		(start 102.876805 137.775)
		(end 103.073195 137.775)
		(width 0.1)
		(layer "In2.Cu")
		(net 146)
	)
	(segment
		(start 103.095046 138.177461)
		(end 103.1158 138.184724)
		(width 0.1)
		(layer "In2.Cu")
		(net 146)
	)
	(segment
		(start 103.1158 138.365275)
		(end 103.095046 138.372538)
		(width 0.1)
		(layer "In2.Cu")
		(net 146)
	)
	(segment
		(start 102.815582 138.553577)
		(end 102.8342 138.565275)
		(width 0.1)
		(layer "In2.Cu")
		(net 146)
	)
	(segment
		(start 103.171389 137.873194)
		(end 103.171389 137.876806)
		(width 0.1)
		(layer "In2.Cu")
		(net 146)
	)
	(segment
		(start 102.876805 136.975)
		(end 103.073195 136.975)
		(width 0.1)
		(layer "In2.Cu")
		(net 146)
	)
	(segment
		(start 102.781072 138.451343)
		(end 102.778611 138.473194)
		(width 0.1)
		(layer "In2.Cu")
		(net 146)
	)
	(segment
		(start 102.778611 136.071388)
		(end 102.778611 136.075)
		(width 0.1)
		(layer "In2.Cu")
		(net 146)
	)
	(segment
		(start 103.171389 136.276806)
		(end 103.168928 136.298656)
		(width 0.1)
		(layer "In2.Cu")
		(net 146)
	)
	(segment
		(start 102.815582 137.753577)
		(end 102.8342 137.765275)
		(width 0.1)
		(layer "In2.Cu")
		(net 146)
	)
	(segment
		(start 103.1158 137.965275)
		(end 103.095046 137.972538)
		(width 0.1)
		(layer "In2.Cu")
		(net 146)
	)
	(segment
		(start 102.781072 138.498656)
		(end 102.788335 138.51941)
		(width 0.1)
		(layer "In2.Cu")
		(net 146)
	)
	(segment
		(start 102.854954 138.972538)
		(end 102.876805 138.975)
		(width 0.1)
		(layer "In2.Cu")
		(net 146)
	)
	(segment
		(start 102.800033 137.211971)
		(end 102.788335 137.230589)
		(width 0.1)
		(layer "In2.Cu")
		(net 146)
	)
	(segment
		(start 102.972538 139.451343)
		(end 102.975 139.473194)
		(width 0.1)
		(layer "In2.Cu")
		(net 146)
	)
	(segment
		(start 102.781072 138.851343)
		(end 102.778611 138.873194)
		(width 0.1)
		(layer "In2.Cu")
		(net 146)
	)
	(segment
		(start 103.168928 139.051343)
		(end 103.171389 139.073194)
		(width 0.1)
		(layer "In2.Cu")
		(net 146)
	)
	(segment
		(start 102.876805 137.575)
		(end 102.854954 137.577461)
		(width 0.1)
		(layer "In2.Cu")
		(net 146)
	)
	(segment
		(start 103.1158 137.384724)
		(end 103.134418 137.396422)
		(width 0.1)
		(layer "In2.Cu")
		(net 146)
	)
	(segment
		(start 103.161665 138.71941)
		(end 103.149967 138.738028)
		(width 0.1)
		(layer "In2.Cu")
		(net 146)
	)
	(segment
		(start 102.854954 135.975655)
		(end 102.8342 135.982918)
		(width 0.1)
		(layer "In2.Cu")
		(net 146)
	)
	(segment
		(start 103.149967 136.738028)
		(end 103.134418 136.753577)
		(width 0.1)
		(layer "In2.Cu")
		(net 146)
	)
	(segment
		(start 103.073195 137.375)
		(end 103.095046 137.377461)
		(width 0.1)
		(layer "In2.Cu")
		(net 146)
	)
	(segment
		(start 102.815582 136.953577)
		(end 102.8342 136.965275)
		(width 0.1)
		(layer "In2.Cu")
		(net 146)
	)
	(segment
		(start 103.073195 136.375)
		(end 102.876805 136.375)
		(width 0.1)
		(layer "In2.Cu")
		(net 146)
	)
	(segment
		(start 102.975 136.173194)
		(end 102.975 136.175)
		(width 0.1)
		(layer "In2.Cu")
		(net 146)
	)
	(segment
		(start 103.168928 137.898656)
		(end 103.161665 137.91941)
		(width 0.1)
		(layer "In2.Cu")
		(net 146)
	)
	(segment
		(start 102.854954 138.572538)
		(end 102.876805 138.575)
		(width 0.1)
		(layer "In2.Cu")
		(net 146)
	)
	(segment
		(start 103.168928 136.698656)
		(end 103.161665 136.71941)
		(width 0.1)
		(layer "In2.Cu")
		(net 146)
	)
	(segment
		(start 103.171389 137.876806)
		(end 103.168928 137.898656)
		(width 0.1)
		(layer "In2.Cu")
		(net 146)
	)
	(segment
		(start 103.275 127.675)
		(end 102.875011 128.074989)
		(width 0.1)
		(layer "In2.Cu")
		(net 146)
	)
	(segment
		(start 102.781072 139.298656)
		(end 102.788335 139.31941)
		(width 0.1)
		(layer "In2.Cu")
		(net 146)
	)
	(segment
		(start 102.788335 138.91941)
		(end 102.800033 138.938028)
		(width 0.1)
		(layer "In2.Cu")
		(net 146)
	)
	(segment
		(start 102.781072 137.251343)
		(end 102.778611 137.273194)
		(width 0.1)
		(layer "In2.Cu")
		(net 146)
	)
	(segment
		(start 102.854954 139.372538)
		(end 102.898656 139.377461)
		(width 0.1)
		(layer "In2.Cu")
		(net 146)
	)
	(segment
		(start 102.965275 139.430589)
		(end 102.972538 139.451343)
		(width 0.1)
		(layer "In2.Cu")
		(net 146)
	)
	(segment
		(start 103.1158 138.184724)
		(end 103.134418 138.196422)
		(width 0.1)
		(layer "In2.Cu")
		(net 146)
	)
	(segment
		(start 102.778611 138.076806)
		(end 102.781072 138.098656)
		(width 0.1)
		(layer "In2.Cu")
		(net 146)
	)
	(segment
		(start 103.095046 138.977461)
		(end 103.1158 138.984724)
		(width 0.1)
		(layer "In2.Cu")
		(net 146)
	)
	(segment
		(start 102.788335 136.830589)
		(end 102.781072 136.851343)
		(width 0.1)
		(layer "In2.Cu")
		(net 146)
	)
	(segment
		(start 103.171389 139.076806)
		(end 103.168928 139.098656)
		(width 0.1)
		(layer "In2.Cu")
		(net 146)
	)
	(segment
		(start 103.161665 136.31941)
		(end 103.149967 136.338028)
		(width 0.1)
		(layer "In2.Cu")
		(net 146)
	)
	(segment
		(start 103.168928 138.651343)
		(end 103.171389 138.673194)
		(width 0.1)
		(layer "In2.Cu")
		(net 146)
	)
	(segment
		(start 102.788335 138.11941)
		(end 102.800033 138.138028)
		(width 0.1)
		(layer "In2.Cu")
		(net 146)
	)
	(segment
		(start 102.778611 139.276806)
		(end 102.781072 139.298656)
		(width 0.1)
		(layer "In2.Cu")
		(net 146)
	)
	(segment
		(start 102.788335 138.830589)
		(end 102.781072 138.851343)
		(width 0.1)
		(layer "In2.Cu")
		(net 146)
	)
	(segment
		(start 103.1158 139.165275)
		(end 103.095046 139.172538)
		(width 0.1)
		(layer "In2.Cu")
		(net 146)
	)
	(segment
		(start 103.171389 138.673194)
		(end 103.171389 138.676806)
		(width 0.1)
		(layer "In2.Cu")
		(net 146)
	)
	(segment
		(start 102.788335 138.51941)
		(end 102.800033 138.538028)
		(width 0.1)
		(layer "In2.Cu")
		(net 146)
	)
	(segment
		(start 103.149967 137.411971)
		(end 103.161665 137.430589)
		(width 0.1)
		(layer "In2.Cu")
		(net 146)
	)
	(segment
		(start 103.168928 136.298656)
		(end 103.161665 136.31941)
		(width 0.1)
		(layer "In2.Cu")
		(net 146)
	)
	(segment
		(start 102.854954 137.177461)
		(end 102.8342 137.184724)
		(width 0.1)
		(layer "In2.Cu")
		(net 146)
	)
	(segment
		(start 102.875011 129.300097)
		(end 102.975066 129.400152)
		(width 0.1)
		(layer "In2.Cu")
		(net 146)
	)
	(segment
		(start 103.134418 138.996422)
		(end 103.149967 139.011971)
		(width 0.1)
		(layer "In2.Cu")
		(net 146)
	)
	(segment
		(start 103.095046 138.577461)
		(end 103.1158 138.584724)
		(width 0.1)
		(layer "In2.Cu")
		(net 146)
	)
	(segment
		(start 103.168928 137.498656)
		(end 103.161665 137.51941)
		(width 0.1)
		(layer "In2.Cu")
		(net 146)
	)
	(segment
		(start 103.168928 138.251343)
		(end 103.171389 138.273194)
		(width 0.1)
		(layer "In2.Cu")
		(net 146)
	)
	(segment
		(start 102.781072 136.498656)
		(end 102.788335 136.51941)
		(width 0.1)
		(layer "In2.Cu")
		(net 146)
	)
	(segment
		(start 103.161665 137.430589)
		(end 103.168928 137.451343)
		(width 0.1)
		(layer "In2.Cu")
		(net 146)
	)
	(segment
		(start 102.788335 137.31941)
		(end 102.800033 137.338028)
		(width 0.1)
		(layer "In2.Cu")
		(net 146)
	)
	(segment
		(start 102.781072 136.451343)
		(end 102.778611 136.473194)
		(width 0.1)
		(layer "In2.Cu")
		(net 146)
	)
	(segment
		(start 102.800033 136.010165)
		(end 102.788335 136.028783)
		(width 0.1)
		(layer "In2.Cu")
		(net 146)
	)
	(segment
		(start 103.161665 137.11941)
		(end 103.149967 137.138028)
		(width 0.1)
		(layer "In2.Cu")
		(net 146)
	)
	(segment
		(start 103.134418 138.596422)
		(end 103.149967 138.611971)
		(width 0.1)
		(layer "In2.Cu")
		(net 146)
	)
	(segment
		(start 102.781072 136.09685)
		(end 102.788335 136.117604)
		(width 0.1)
		(layer "In2.Cu")
		(net 146)
	)
	(segment
		(start 103.168928 139.098656)
		(end 103.161665 139.11941)
		(width 0.1)
		(layer "In2.Cu")
		(net 146)
	)
	(segment
		(start 103.095046 137.777461)
		(end 103.1158 137.784724)
		(width 0.1)
		(layer "In2.Cu")
		(net 146)
	)
	(segment
		(start 102.876805 136.375)
		(end 102.854954 136.377461)
		(width 0.1)
		(layer "In2.Cu")
		(net 146)
	)
	(segment
		(start 102.778611 137.273194)
		(end 102.778611 137.276806)
		(width 0.1)
		(layer "In2.Cu")
		(net 146)
	)
	(segment
		(start 102.781072 137.698656)
		(end 102.788335 137.71941)
		(width 0.1)
		(layer "In2.Cu")
		(net 146)
	)
	(segment
		(start 102.815582 137.596422)
		(end 102.800033 137.611971)
		(width 0.1)
		(layer "In2.Cu")
		(net 146)
	)
	(segment
		(start 102.815582 136.796422)
		(end 102.800033 136.811971)
		(width 0.1)
		(layer "In2.Cu")
		(net 146)
	)
	(segment
		(start 102.778611 138.873194)
		(end 102.778611 138.876806)
		(width 0.1)
		(layer "In2.Cu")
		(net 146)
	)
	(segment
		(start 102.815582 136.553577)
		(end 102.8342 136.565275)
		(width 0.1)
		(layer "In2.Cu")
		(net 146)
	)
	(segment
		(start 103.171389 136.273194)
		(end 103.171389 136.276806)
		(width 0.1)
		(layer "In2.Cu")
		(net 146)
	)
	(segment
		(start 103.1158 136.765275)
		(end 103.095046 136.772538)
		(width 0.1)
		(layer "In2.Cu")
		(net 146)
	)
	(segment
		(start 102.975 130.757858)
		(end 102.975 135.875)
		(width 0.1)
		(layer "In2.Cu")
		(net 146)
	)
	(segment
		(start 102.788335 137.230589)
		(end 102.781072 137.251343)
		(width 0.1)
		(layer "In2.Cu")
		(net 146)
	)
	(segment
		(start 102.815582 137.196422)
		(end 102.800033 137.211971)
		(width 0.1)
		(layer "In2.Cu")
		(net 146)
	)
	(segment
		(start 102.778611 136.473194)
		(end 102.778611 136.476806)
		(width 0.1)
		(layer "In2.Cu")
		(net 146)
	)
	(segment
		(start 102.800033 137.338028)
		(end 102.815582 137.353577)
		(width 0.1)
		(layer "In2.Cu")
		(net 146)
	)
	(segment
		(start 103.134418 139.153577)
		(end 103.1158 139.165275)
		(width 0.1)
		(layer "In2.Cu")
		(net 146)
	)
	(segment
		(start 102.898656 135.970732)
		(end 102.854954 135.975655)
		(width 0.1)
		(layer "In2.Cu")
		(net 146)
	)
	(segment
		(start 103.1158 138.984724)
		(end 103.134418 138.996422)
		(width 0.1)
		(layer "In2.Cu")
		(net 146)
	)
	(segment
		(start 102.876805 139.175)
		(end 102.854954 139.177461)
		(width 0.1)
		(layer "In2.Cu")
		(net 146)
	)
	(segment
		(start 102.91941 139.384724)
		(end 102.938028 139.396422)
		(width 0.1)
		(layer "In2.Cu")
		(net 146)
	)
	(segment
		(start 102.788335 139.230589)
		(end 102.781072 139.251343)
		(width 0.1)
		(layer "In2.Cu")
		(net 146)
	)
	(segment
		(start 103.134418 136.353577)
		(end 103.1158 136.365275)
		(width 0.1)
		(layer "In2.Cu")
		(net 146)
	)
	(segment
		(start 102.781072 139.251343)
		(end 102.778611 139.273194)
		(width 0.1)
		(layer "In2.Cu")
		(net 146)
	)
	(segment
		(start 102.938028 135.951771)
		(end 102.91941 135.963469)
		(width 0.1)
		(layer "In2.Cu")
		(net 146)
	)
	(segment
		(start 103.095046 136.177461)
		(end 103.1158 136.184724)
		(width 0.1)
		(layer "In2.Cu")
		(net 146)
	)
	(segment
		(start 102.876805 136.575)
		(end 103.073195 136.575)
		(width 0.1)
		(layer "In2.Cu")
		(net 146)
	)
	(segment
		(start 103.095046 136.977461)
		(end 103.1158 136.984724)
		(width 0.1)
		(layer "In2.Cu")
		(net 146)
	)
	(segment
		(start 102.800033 138.011971)
		(end 102.788335 138.030589)
		(width 0.1)
		(layer "In2.Cu")
		(net 146)
	)
	(segment
		(start 102.8342 137.984724)
		(end 102.815582 137.996422)
		(width 0.1)
		(layer "In2.Cu")
		(net 146)
	)
	(segment
		(start 103.149967 138.211971)
		(end 103.161665 138.230589)
		(width 0.1)
		(layer "In2.Cu")
		(net 146)
	)
	(segment
		(start 102.781072 138.898656)
		(end 102.788335 138.91941)
		(width 0.1)
		(layer "In2.Cu")
		(net 146)
	)
	(segment
		(start 102.854954 139.177461)
		(end 102.8342 139.184724)
		(width 0.1)
		(layer "In2.Cu")
		(net 146)
	)
	(segment
		(start 102.778611 137.673194)
		(end 102.778611 137.676806)
		(width 0.1)
		(layer "In2.Cu")
		(net 146)
	)
	(segment
		(start 103.149967 139.138028)
		(end 103.134418 139.153577)
		(width 0.1)
		(layer "In2.Cu")
		(net 146)
	)
	(segment
		(start 103.073195 136.175)
		(end 103.095046 136.177461)
		(width 0.1)
		(layer "In2.Cu")
		(net 146)
	)
	(segment
		(start 103.168928 136.251343)
		(end 103.171389 136.273194)
		(width 0.1)
		(layer "In2.Cu")
		(net 146)
	)
	(segment
		(start 102.788335 136.430589)
		(end 102.781072 136.451343)
		(width 0.1)
		(layer "In2.Cu")
		(net 146)
	)
	(segment
		(start 102.778611 138.876806)
		(end 102.781072 138.898656)
		(width 0.1)
		(layer "In2.Cu")
		(net 146)
	)
	(segment
		(start 102.778611 139.273194)
		(end 102.778611 139.276806)
		(width 0.1)
		(layer "In2.Cu")
		(net 146)
	)
	(segment
		(start 103.073195 138.575)
		(end 103.095046 138.577461)
		(width 0.1)
		(layer "In2.Cu")
		(net 146)
	)
	(segment
		(start 102.854954 137.577461)
		(end 102.8342 137.584724)
		(width 0.1)
		(layer "In2.Cu")
		(net 146)
	)
	(segment
		(start 103.134418 136.196422)
		(end 103.149967 136.211971)
		(width 0.1)
		(layer "In2.Cu")
		(net 146)
	)
	(segment
		(start 102.815582 138.953577)
		(end 102.8342 138.965275)
		(width 0.1)
		(layer "In2.Cu")
		(net 146)
	)
	(segment
		(start 102.800033 136.938028)
		(end 102.815582 136.953577)
		(width 0.1)
		(layer "In2.Cu")
		(net 146)
	)
	(segment
		(start 102.788335 137.71941)
		(end 102.800033 137.738028)
		(width 0.1)
		(layer "In2.Cu")
		(net 146)
	)
	(segment
		(start 103.095046 138.772538)
		(end 103.073195 138.775)
		(width 0.1)
		(layer "In2.Cu")
		(net 146)
	)
	(segment
		(start 102.876805 138.375)
		(end 102.854954 138.377461)
		(width 0.1)
		(layer "In2.Cu")
		(net 146)
	)
	(segment
		(start 103.1158 136.584724)
		(end 103.134418 136.596422)
		(width 0.1)
		(layer "In2.Cu")
		(net 146)
	)
	(segment
		(start 102.953577 135.936222)
		(end 102.938028 135.951771)
		(width 0.1)
		(layer "In2.Cu")
		(net 146)
	)
	(segment
		(start 103.073195 138.775)
		(end 102.876805 138.775)
		(width 0.1)
		(layer "In2.Cu")
		(net 146)
	)
	(segment
		(start 103.171389 136.676806)
		(end 103.168928 136.698656)
		(width 0.1)
		(layer "In2.Cu")
		(net 146)
	)
	(segment
		(start 103.095046 136.577461)
		(end 103.1158 136.584724)
		(width 0.1)
		(layer "In2.Cu")
		(net 146)
	)
	(segment
		(start 102.788335 136.028783)
		(end 102.781072 136.049537)
		(width 0.1)
		(layer "In2.Cu")
		(net 146)
	)
	(segment
		(start 103.168928 137.051343)
		(end 103.171389 137.073194)
		(width 0.1)
		(layer "In2.Cu")
		(net 146)
	)
	(segment
		(start 102.8342 139.365275)
		(end 102.854954 139.372538)
		(width 0.1)
		(layer "In2.Cu")
		(net 146)
	)
	(segment
		(start 103.161665 136.230589)
		(end 103.168928 136.251343)
		(width 0.1)
		(layer "In2.Cu")
		(net 146)
	)
	(segment
		(start 103.1158 137.165275)
		(end 103.095046 137.172538)
		(width 0.1)
		(layer "In2.Cu")
		(net 146)
	)
	(segment
		(start 102.854954 136.170732)
		(end 102.876806 136.173194)
		(width 0.1)
		(layer "In2.Cu")
		(net 146)
	)
	(segment
		(start 102.8342 136.384724)
		(end 102.815582 136.396422)
		(width 0.1)
		(layer "In2.Cu")
		(net 146)
	)
	(segment
		(start 102.815582 138.396422)
		(end 102.800033 138.411971)
		(width 0.1)
		(layer "In2.Cu")
		(net 146)
	)
	(segment
		(start 103.1158 136.184724)
		(end 103.134418 136.196422)
		(width 0.1)
		(layer "In2.Cu")
		(net 146)
	)
	(segment
		(start 103.134418 137.553577)
		(end 103.1158 137.565275)
		(width 0.1)
		(layer "In2.Cu")
		(net 146)
	)
	(segment
		(start 103.1158 136.365275)
		(end 103.095046 136.372538)
		(width 0.1)
		(layer "In2.Cu")
		(net 146)
	)
	(segment
		(start 103.073195 137.775)
		(end 103.095046 137.777461)
		(width 0.1)
		(layer "In2.Cu")
		(net 146)
	)
	(segment
		(start 102.8342 138.784724)
		(end 102.815582 138.796422)
		(width 0.1)
		(layer "In2.Cu")
		(net 146)
	)
	(segment
		(start 102.815582 139.196422)
		(end 102.800033 139.211971)
		(width 0.1)
		(layer "In2.Cu")
		(net 146)
	)
	(segment
		(start 102.781072 136.851343)
		(end 102.778611 136.873194)
		(width 0.1)
		(layer "In2.Cu")
		(net 146)
	)
	(segment
		(start 102.972538 135.89685)
		(end 102.965275 135.917604)
		(width 0.1)
		(layer "In2.Cu")
		(net 146)
	)
	(segment
		(start 103.134418 138.196422)
		(end 103.149967 138.211971)
		(width 0.1)
		(layer "In2.Cu")
		(net 146)
	)
	(segment
		(start 102.854954 138.377461)
		(end 102.8342 138.384724)
		(width 0.1)
		(layer "In2.Cu")
		(net 146)
	)
	(segment
		(start 102.781072 138.098656)
		(end 102.788335 138.11941)
		(width 0.1)
		(layer "In2.Cu")
		(net 146)
	)
	(segment
		(start 103.073195 138.375)
		(end 102.876805 138.375)
		(width 0.1)
		(layer "In2.Cu")
		(net 146)
	)
	(segment
		(start 103.149967 139.011971)
		(end 103.161665 139.030589)
		(width 0.1)
		(layer "In2.Cu")
		(net 146)
	)
	(segment
		(start 103.161665 136.71941)
		(end 103.149967 136.738028)
		(width 0.1)
		(layer "In2.Cu")
		(net 146)
	)
	(segment
		(start 102.854954 137.772538)
		(end 102.876805 137.775)
		(width 0.1)
		(layer "In2.Cu")
		(net 146)
	)
	(segment
		(start 102.975 140.075)
		(end 103.175022 140.275022)
		(width 0.1)
		(layer "In2.Cu")
		(net 146)
	)
	(segment
		(start 103.171389 137.076806)
		(end 103.168928 137.098656)
		(width 0.1)
		(layer "In2.Cu")
		(net 146)
	)
	(segment
		(start 102.8342 136.784724)
		(end 102.815582 136.796422)
		(width 0.1)
		(layer "In2.Cu")
		(net 146)
	)
	(segment
		(start 103.073195 137.575)
		(end 102.876805 137.575)
		(width 0.1)
		(layer "In2.Cu")
		(net 146)
	)
	(segment
		(start 103.168928 137.451343)
		(end 103.171389 137.473194)
		(width 0.1)
		(layer "In2.Cu")
		(net 146)
	)
	(segment
		(start 102.8342 138.384724)
		(end 102.815582 138.396422)
		(width 0.1)
		(layer "In2.Cu")
		(net 146)
	)
	(segment
		(start 102.788335 139.31941)
		(end 102.800033 139.338028)
		(width 0.1)
		(layer "In2.Cu")
		(net 146)
	)
	(segment
		(start 103.161665 137.91941)
		(end 103.149967 137.938028)
		(width 0.1)
		(layer "In2.Cu")
		(net 146)
	)
	(segment
		(start 103.149967 136.211971)
		(end 103.161665 136.230589)
		(width 0.1)
		(layer "In2.Cu")
		(net 146)
	)
	(segment
		(start 103.149967 137.811971)
		(end 103.161665 137.830589)
		(width 0.1)
		(layer "In2.Cu")
		(net 146)
	)
	(segment
		(start 103.171389 137.073194)
		(end 103.171389 137.076806)
		(width 0.1)
		(layer "In2.Cu")
		(net 146)
	)
	(segment
		(start 102.800033 136.136222)
		(end 102.815582 136.151771)
		(width 0.1)
		(layer "In2.Cu")
		(net 146)
	)
	(segment
		(start 102.781072 136.898656)
		(end 102.788335 136.91941)
		(width 0.1)
		(layer "In2.Cu")
		(net 146)
	)
	(segment
		(start 102.800033 136.811971)
		(end 102.788335 136.830589)
		(width 0.1)
		(layer "In2.Cu")
		(net 146)
	)
	(segment
		(start 103.1158 137.565275)
		(end 103.095046 137.572538)
		(width 0.1)
		(layer "In2.Cu")
		(net 146)
	)
	(segment
		(start 102.975 139.473194)
		(end 102.975 140.075)
		(width 0.1)
		(layer "In2.Cu")
		(net 146)
	)
	(segment
		(start 103.073195 137.175)
		(end 102.876805 137.175)
		(width 0.1)
		(layer "In2.Cu")
		(net 146)
	)
	(segment
		(start 103.095046 139.172538)
		(end 103.073195 139.175)
		(width 0.1)
		(layer "In2.Cu")
		(net 146)
	)
	(segment
		(start 103.1158 136.984724)
		(end 103.134418 136.996422)
		(width 0.1)
		(layer "In2.Cu")
		(net 146)
	)
	(segment
		(start 103.161665 137.030589)
		(end 103.168928 137.051343)
		(width 0.1)
		(layer "In2.Cu")
		(net 146)
	)
	(segment
		(start 102.854954 136.377461)
		(end 102.8342 136.384724)
		(width 0.1)
		(layer "In2.Cu")
		(net 146)
	)
	(segment
		(start 102.778611 138.473194)
		(end 102.778611 138.476806)
		(width 0.1)
		(layer "In2.Cu")
		(net 146)
	)
	(segment
		(start 103.171389 138.676806)
		(end 103.168928 138.698656)
		(width 0.1)
		(layer "In2.Cu")
		(net 146)
	)
	(segment
		(start 103.095046 137.172538)
		(end 103.073195 137.175)
		(width 0.1)
		(layer "In2.Cu")
		(net 146)
	)
	(segment
		(start 103.168928 138.698656)
		(end 103.161665 138.71941)
		(width 0.1)
		(layer "In2.Cu")
		(net 146)
	)
	(segment
		(start 103.134418 138.753577)
		(end 103.1158 138.765275)
		(width 0.1)
		(layer "In2.Cu")
		(net 146)
	)
	(segment
		(start 103.073195 138.975)
		(end 103.095046 138.977461)
		(width 0.1)
		(layer "In2.Cu")
		(net 146)
	)
	(segment
		(start 103.1158 137.784724)
		(end 103.134418 137.796422)
		(width 0.1)
		(layer "In2.Cu")
		(net 146)
	)
	(segment
		(start 103.161665 139.030589)
		(end 103.168928 139.051343)
		(width 0.1)
		(layer "In2.Cu")
		(net 146)
	)
	(segment
		(start 102.800033 136.538028)
		(end 102.815582 136.553577)
		(width 0.1)
		(layer "In2.Cu")
		(net 146)
	)
	(segment
		(start 102.778611 138.476806)
		(end 102.781072 138.498656)
		(width 0.1)
		(layer "In2.Cu")
		(net 146)
	)
	(segment
		(start 102.898656 139.377461)
		(end 102.91941 139.384724)
		(width 0.1)
		(layer "In2.Cu")
		(net 146)
	)
	(segment
		(start 102.788335 137.630589)
		(end 102.781072 137.651343)
		(width 0.1)
		(layer "In2.Cu")
		(net 146)
	)
	(segment
		(start 102.8342 135.982918)
		(end 102.815582 135.994616)
		(width 0.1)
		(layer "In2.Cu")
		(net 146)
	)
	(segment
		(start 103.175022 140.275022)
		(end 103.175022 142.584392)
		(width 0.1)
		(layer "In2.Cu")
		(net 146)
	)
	(segment
		(start 103.168928 136.651343)
		(end 103.171389 136.673194)
		(width 0.1)
		(layer "In2.Cu")
		(net 146)
	)
	(segment
		(start 103.149967 136.611971)
		(end 103.161665 136.630589)
		(width 0.1)
		(layer "In2.Cu")
		(net 146)
	)
	(segment
		(start 103.161665 138.230589)
		(end 103.168928 138.251343)
		(width 0.1)
		(layer "In2.Cu")
		(net 146)
	)
	(segment
		(start 102.781072 138.051343)
		(end 102.778611 138.073194)
		(width 0.1)
		(layer "In2.Cu")
		(net 146)
	)
	(segment
		(start 102.8342 136.163469)
		(end 102.854954 136.170732)
		(width 0.1)
		(layer "In2.Cu")
		(net 146)
	)
	(segment
		(start 103.171389 138.273194)
		(end 103.171389 138.276806)
		(width 0.1)
		(layer "In2.Cu")
		(net 146)
	)
	(segment
		(start 103.095046 137.972538)
		(end 103.073195 137.975)
		(width 0.1)
		(layer "In2.Cu")
		(net 146)
	)
	(segment
		(start 102.788335 136.91941)
		(end 102.800033 136.938028)
		(width 0.1)
		(layer "In2.Cu")
		(net 146)
	)
	(segment
		(start 103.1158 138.765275)
		(end 103.095046 138.772538)
		(width 0.1)
		(layer "In2.Cu")
		(net 146)
	)
	(segment
		(start 103.161665 138.31941)
		(end 103.149967 138.338028)
		(width 0.1)
		(layer "In2.Cu")
		(net 146)
	)
	(segment
		(start 102.854954 138.172538)
		(end 102.876805 138.175)
		(width 0.1)
		(layer "In2.Cu")
		(net 146)
	)
	(segment
		(start 103.149967 137.011971)
		(end 103.161665 137.030589)
		(width 0.1)
		(layer "In2.Cu")
		(net 146)
	)
	(segment
		(start 103.1158 138.584724)
		(end 103.134418 138.596422)
		(width 0.1)
		(layer "In2.Cu")
		(net 146)
	)
	(segment
		(start 102.975 135.875)
		(end 102.972538 135.89685)
		(width 0.1)
		(layer "In2.Cu")
		(net 146)
	)
	(segment
		(start 102.788335 136.51941)
		(end 102.800033 136.538028)
		(width 0.1)
		(layer "In2.Cu")
		(net 146)
	)
	(segment
		(start 103.095046 138.372538)
		(end 103.073195 138.375)
		(width 0.1)
		(layer "In2.Cu")
		(net 146)
	)
	(segment
		(start 102.800033 138.138028)
		(end 102.815582 138.153577)
		(width 0.1)
		(layer "In2.Cu")
		(net 146)
	)
	(segment
		(start 102.854954 138.777461)
		(end 102.8342 138.784724)
		(width 0.1)
		(layer "In2.Cu")
		(net 146)
	)
	(segment
		(start 103.161665 137.51941)
		(end 103.149967 137.538028)
		(width 0.1)
		(layer "In2.Cu")
		(net 146)
	)
	(segment
		(start 102.975065 130.757793)
		(end 102.975 130.757858)
		(width 0.1)
		(layer "In2.Cu")
		(net 146)
	)
	(segment
		(start 102.8342 136.965275)
		(end 102.854954 136.972538)
		(width 0.1)
		(layer "In2.Cu")
		(net 146)
	)
	(segment
		(start 102.975 136.175)
		(end 103.073195 136.175)
		(width 0.1)
		(layer "In2.Cu")
		(net 146)
	)
	(segment
		(start 103.073195 139.175)
		(end 102.876805 139.175)
		(width 0.1)
		(layer "In2.Cu")
		(net 146)
	)
	(segment
		(start 103.171389 137.473194)
		(end 103.171389 137.476806)
		(width 0.1)
		(layer "In2.Cu")
		(net 146)
	)
	(segment
		(start 102.876806 136.173194)
		(end 102.975 136.173194)
		(width 0.1)
		(layer "In2.Cu")
		(net 146)
	)
	(segment
		(start 102.854954 136.572538)
		(end 102.876805 136.575)
		(width 0.1)
		(layer "In2.Cu")
		(net 146)
	)
	(segment
		(start 102.815582 136.151771)
		(end 102.8342 136.163469)
		(width 0.1)
		(layer "In2.Cu")
		(net 146)
	)
	(segment
		(start 102.800033 137.738028)
		(end 102.815582 137.753577)
		(width 0.1)
		(layer "In2.Cu")
		(net 146)
	)
	(segment
		(start 102.965275 135.917604)
		(end 102.953577 135.936222)
		(width 0.1)
		(layer "In2.Cu")
		(net 146)
	)
	(segment
		(start 102.575 148.775)
		(end 102.575 148.175)
		(width 0.1)
		(layer "F.Cu")
		(net 147)
	)
	(segment
		(start 101.775 128.175)
		(end 102.275 128.675)
		(width 0.15)
		(layer "F.Cu")
		(net 147)
	)
	(via
		(at 102.575 148.175)
		(size 0.5)
		(drill 0.2)
		(layers "F.Cu" "B.Cu")
		(net 147)
	)
	(via blind
		(at 102.275 128.675)
		(size 0.5)
		(drill 0.2)
		(layers "F.Cu" "In2.Cu")
		(net 147)
	)
	(segment
		(start 102.575 148.175)
		(end 102.575 148.475)
		(width 0.1)
		(layer "B.Cu")
		(net 147)
	)
	(segment
		(start 102.575 148.475)
		(end 102.375 148.675)
		(width 0.1)
		(layer "B.Cu")
		(net 147)
	)
	(segment
		(start 102.375 148.675)
		(end 102.375 149.19)
		(width 0.1)
		(layer "B.Cu")
		(net 147)
	)
	(segment
		(start 102.355364 131.396286)
		(end 102.344061 131.414276)
		(width 0.1)
		(layer "In2.Cu")
		(net 147)
	)
	(segment
		(start 102.0748 131.45692)
		(end 102.06155 131.465245)
		(width 0.1)
		(layer "In2.Cu")
		(net 147)
	)
	(segment
		(start 102.159754 131.018569)
		(end 102.148689 131.029634)
		(width 0.1)
		(layer "In2.Cu")
		(net 147)
	)
	(segment
		(start 102.173247 130.990549)
		(end 102.168079 131.005319)
		(width 0.1)
		(layer "In2.Cu")
		(net 147)
	)
	(segment
		(start 102.0748 131.643079)
		(end 102.08957 131.648247)
		(width 0.1)
		(layer "In2.Cu")
		(net 147)
	)
	(segment
		(start 102.329037 131.4293)
		(end 102.311047 131.440603)
		(width 0.1)
		(layer "In2.Cu")
		(net 147)
	)
	(segment
		(start 102.08957 131.046632)
		(end 102.0748 131.0518)
		(width 0.1)
		(layer "In2.Cu")
		(net 147)
	)
	(segment
		(start 102.050485 131.07119)
		(end 102.04216 131.08444)
		(width 0.1)
		(layer "In2.Cu")
		(net 147)
	)
	(segment
		(start 102.175 142.375044)
		(end 101.975044 142.575)
		(width 0.1)
		(layer "In2.Cu")
		(net 147)
	)
	(segment
		(start 102.175 130.975)
		(end 102.173247 130.990549)
		(width 0.1)
		(layer "In2.Cu")
		(net 147)
	)
	(segment
		(start 102.175 130.375)
		(end 102.175 130.975)
		(width 0.1)
		(layer "In2.Cu")
		(net 147)
	)
	(segment
		(start 102.120669 131.651752)
		(end 102.135439 131.65692)
		(width 0.1)
		(layer "In2.Cu")
		(net 147)
	)
	(segment
		(start 102.08957 131.243127)
		(end 102.10512 131.24488)
		(width 0.1)
		(layer "In2.Cu")
		(net 147)
	)
	(segment
		(start 102.10512 131.45)
		(end 102.08957 131.451752)
		(width 0.1)
		(layer "In2.Cu")
		(net 147)
	)
	(segment
		(start 102.344061 131.285723)
		(end 102.355364 131.303713)
		(width 0.1)
		(layer "In2.Cu")
		(net 147)
	)
	(segment
		(start 102.120669 131.043127)
		(end 102.08957 131.046632)
		(width 0.1)
		(layer "In2.Cu")
		(net 147)
	)
	(segment
		(start 102.06155 131.060125)
		(end 102.050485 131.07119)
		(width 0.1)
		(layer "In2.Cu")
		(net 147)
	)
	(segment
		(start 101.375044 146.375044)
		(end 102.575 147.575)
		(width 0.1)
		(layer "In2.Cu")
		(net 147)
	)
	(segment
		(start 102.290993 131.447621)
		(end 102.26988 131.45)
		(width 0.1)
		(layer "In2.Cu")
		(net 147)
	)
	(segment
		(start 102.06155 131.634754)
		(end 102.0748 131.643079)
		(width 0.1)
		(layer "In2.Cu")
		(net 147)
	)
	(segment
		(start 102.575 147.575)
		(end 102.575 148.175)
		(width 0.1)
		(layer "In2.Cu")
		(net 147)
	)
	(segment
		(start 101.975044 142.575)
		(end 101.975 142.575)
		(width 0.1)
		(layer "In2.Cu")
		(net 147)
	)
	(segment
		(start 101.375044 143.174956)
		(end 101.375044 146.375044)
		(width 0.1)
		(layer "In2.Cu")
		(net 147)
	)
	(segment
		(start 102.168079 131.68956)
		(end 102.173247 131.70433)
		(width 0.1)
		(layer "In2.Cu")
		(net 147)
	)
	(segment
		(start 102.06155 131.229634)
		(end 102.0748 131.237959)
		(width 0.1)
		(layer "In2.Cu")
		(net 147)
	)
	(segment
		(start 102.036992 131.595669)
		(end 102.04216 131.610439)
		(width 0.1)
		(layer "In2.Cu")
		(net 147)
	)
	(segment
		(start 102.26988 131.25)
		(end 102.290993 131.252378)
		(width 0.1)
		(layer "In2.Cu")
		(net 147)
	)
	(segment
		(start 102.148689 131.029634)
		(end 102.135439 131.037959)
		(width 0.1)
		(layer "In2.Cu")
		(net 147)
	)
	(segment
		(start 102.050485 131.47631)
		(end 102.04216 131.48956)
		(width 0.1)
		(layer "In2.Cu")
		(net 147)
	)
	(segment
		(start 102.0748 131.237959)
		(end 102.08957 131.243127)
		(width 0.1)
		(layer "In2.Cu")
		(net 147)
	)
	(segment
		(start 101.975044 128.974956)
		(end 101.975044 130.175044)
		(width 0.1)
		(layer "In2.Cu")
		(net 147)
	)
	(segment
		(start 102.290993 131.252378)
		(end 102.311047 131.259396)
		(width 0.1)
		(layer "In2.Cu")
		(net 147)
	)
	(segment
		(start 101.975044 130.175044)
		(end 102.175 130.375)
		(width 0.1)
		(layer "In2.Cu")
		(net 147)
	)
	(segment
		(start 102.04216 131.08444)
		(end 102.036992 131.09921)
		(width 0.1)
		(layer "In2.Cu")
		(net 147)
	)
	(segment
		(start 102.03524 131.58012)
		(end 102.036992 131.595669)
		(width 0.1)
		(layer "In2.Cu")
		(net 147)
	)
	(segment
		(start 102.355364 131.303713)
		(end 102.362382 131.323767)
		(width 0.1)
		(layer "In2.Cu")
		(net 147)
	)
	(segment
		(start 102.36476 131.35512)
		(end 102.362382 131.376232)
		(width 0.1)
		(layer "In2.Cu")
		(net 147)
	)
	(segment
		(start 102.148689 131.665245)
		(end 102.159754 131.67631)
		(width 0.1)
		(layer "In2.Cu")
		(net 147)
	)
	(segment
		(start 102.362382 131.376232)
		(end 102.355364 131.396286)
		(width 0.1)
		(layer "In2.Cu")
		(net 147)
	)
	(segment
		(start 102.175 131.71988)
		(end 102.175 142.375044)
		(width 0.1)
		(layer "In2.Cu")
		(net 147)
	)
	(segment
		(start 102.08957 131.648247)
		(end 102.120669 131.651752)
		(width 0.1)
		(layer "In2.Cu")
		(net 147)
	)
	(segment
		(start 102.036992 131.09921)
		(end 102.03524 131.11476)
		(width 0.1)
		(layer "In2.Cu")
		(net 147)
	)
	(segment
		(start 102.03524 131.11476)
		(end 102.03524 131.175)
		(width 0.1)
		(layer "In2.Cu")
		(net 147)
	)
	(segment
		(start 102.135439 131.037959)
		(end 102.120669 131.043127)
		(width 0.1)
		(layer "In2.Cu")
		(net 147)
	)
	(segment
		(start 102.036992 131.190549)
		(end 102.04216 131.205319)
		(width 0.1)
		(layer "In2.Cu")
		(net 147)
	)
	(segment
		(start 102.173247 131.70433)
		(end 102.175 131.71988)
		(width 0.1)
		(layer "In2.Cu")
		(net 147)
	)
	(segment
		(start 102.362382 131.323767)
		(end 102.36476 131.34488)
		(width 0.1)
		(layer "In2.Cu")
		(net 147)
	)
	(segment
		(start 102.159754 131.67631)
		(end 102.168079 131.68956)
		(width 0.1)
		(layer "In2.Cu")
		(net 147)
	)
	(segment
		(start 102.175 131.24488)
		(end 102.175 131.25)
		(width 0.1)
		(layer "In2.Cu")
		(net 147)
	)
	(segment
		(start 102.03524 131.51988)
		(end 102.03524 131.58012)
		(width 0.1)
		(layer "In2.Cu")
		(net 147)
	)
	(segment
		(start 102.04216 131.610439)
		(end 102.050485 131.623689)
		(width 0.1)
		(layer "In2.Cu")
		(net 147)
	)
	(segment
		(start 102.175 131.25)
		(end 102.26988 131.25)
		(width 0.1)
		(layer "In2.Cu")
		(net 147)
	)
	(segment
		(start 102.275 128.675)
		(end 101.975044 128.974956)
		(width 0.1)
		(layer "In2.Cu")
		(net 147)
	)
	(segment
		(start 102.06155 131.465245)
		(end 102.050485 131.47631)
		(width 0.1)
		(layer "In2.Cu")
		(net 147)
	)
	(segment
		(start 102.311047 131.440603)
		(end 102.290993 131.447621)
		(width 0.1)
		(layer "In2.Cu")
		(net 147)
	)
	(segment
		(start 102.0748 131.0518)
		(end 102.06155 131.060125)
		(width 0.1)
		(layer "In2.Cu")
		(net 147)
	)
	(segment
		(start 102.04216 131.48956)
		(end 102.036992 131.50433)
		(width 0.1)
		(layer "In2.Cu")
		(net 147)
	)
	(segment
		(start 102.050485 131.218569)
		(end 102.06155 131.229634)
		(width 0.1)
		(layer "In2.Cu")
		(net 147)
	)
	(segment
		(start 102.26988 131.45)
		(end 102.10512 131.45)
		(width 0.1)
		(layer "In2.Cu")
		(net 147)
	)
	(segment
		(start 102.344061 131.414276)
		(end 102.329037 131.4293)
		(width 0.1)
		(layer "In2.Cu")
		(net 147)
	)
	(segment
		(start 102.36476 131.34488)
		(end 102.36476 131.35512)
		(width 0.1)
		(layer "In2.Cu")
		(net 147)
	)
	(segment
		(start 102.050485 131.623689)
		(end 102.06155 131.634754)
		(width 0.1)
		(layer "In2.Cu")
		(net 147)
	)
	(segment
		(start 102.135439 131.65692)
		(end 102.148689 131.665245)
		(width 0.1)
		(layer "In2.Cu")
		(net 147)
	)
	(segment
		(start 102.168079 131.005319)
		(end 102.159754 131.018569)
		(width 0.1)
		(layer "In2.Cu")
		(net 147)
	)
	(segment
		(start 102.329037 131.270699)
		(end 102.344061 131.285723)
		(width 0.1)
		(layer "In2.Cu")
		(net 147)
	)
	(segment
		(start 101.975 142.575)
		(end 101.375044 143.174956)
		(width 0.1)
		(layer "In2.Cu")
		(net 147)
	)
	(segment
		(start 102.036992 131.50433)
		(end 102.03524 131.51988)
		(width 0.1)
		(layer "In2.Cu")
		(net 147)
	)
	(segment
		(start 102.04216 131.205319)
		(end 102.050485 131.218569)
		(width 0.1)
		(layer "In2.Cu")
		(net 147)
	)
	(segment
		(start 102.03524 131.175)
		(end 102.036992 131.190549)
		(width 0.1)
		(layer "In2.Cu")
		(net 147)
	)
	(segment
		(start 102.10512 131.24488)
		(end 102.175 131.24488)
		(width 0.1)
		(layer "In2.Cu")
		(net 147)
	)
	(segment
		(start 102.08957 131.451752)
		(end 102.0748 131.45692)
		(width 0.1)
		(layer "In2.Cu")
		(net 147)
	)
	(segment
		(start 102.311047 131.259396)
		(end 102.329037 131.270699)
		(width 0.1)
		(layer "In2.Cu")
		(net 147)
	)
	(segment
		(start 103.375 149.575)
		(end 102.975 149.175)
		(width 0.1)
		(layer "F.Cu")
		(net 148)
	)
	(segment
		(start 102.975 149.175)
		(end 102.975 147.675)
		(width 0.1)
		(layer "F.Cu")
		(net 148)
	)
	(segment
		(start 102.775 129.175)
		(end 103.275 129.675)
		(width 0.15)
		(layer "F.Cu")
		(net 148)
	)
	(segment
		(start 103.275 129.675)
		(end 103.375076 129.675)
		(width 0.15)
		(layer "F.Cu")
		(net 148)
	)
	(via
		(at 102.975 147.675)
		(size 0.5)
		(drill 0.2)
		(layers "F.Cu" "B.Cu")
		(net 148)
	)
	(via blind
		(at 103.375076 129.675)
		(size 0.5)
		(drill 0.2)
		(layers "F.Cu" "In2.Cu")
		(net 148)
	)
	(segment
		(start 102.975 147.675)
		(end 102.975 149.11)
		(width 0.1)
		(layer "B.Cu")
		(net 148)
	)
	(segment
		(start 102.975 149.11)
		(end 103.055 149.19)
		(width 0.1)
		(layer "B.Cu")
		(net 148)
	)
	(segment
		(start 103.340812 134.045991)
		(end 103.323595 134.056809)
		(width 0.1)
		(layer "In2.Cu")
		(net 148)
	)
	(segment
		(start 103.599993 134.865096)
		(end 103.578857 134.872492)
		(width 0.1)
		(layer "In2.Cu")
		(net 148)
	)
	(segment
		(start 103.646701 135.218388)
		(end 103.634788 135.237348)
		(width 0.1)
		(layer "In2.Cu")
		(net 148)
	)
	(segment
		(start 103.263992 134.672723)
		(end 103.284198 134.675)
		(width 0.1)
		(layer "In2.Cu")
		(net 148)
	)
	(segment
		(start 103.193396 134.584198)
		(end 103.195672 134.604403)
		(width 0.1)
		(layer "In2.Cu")
		(net 148)
	)
	(segment
		(start 103.213206 134.909187)
		(end 103.202388 134.926404)
		(width 0.1)
		(layer "In2.Cu")
		(net 148)
	)
	(segment
		(start 103.654097 134.352747)
		(end 103.656604 134.375)
		(width 0.1)
		(layer "In2.Cu")
		(net 148)
	)
	(segment
		(start 103.375076 129.675)
		(end 103.375076 130.028553)
		(width 0.1)
		(layer "In2.Cu")
		(net 148)
	)
	(segment
		(start 103.2448 134.666007)
		(end 103.263992 134.672723)
		(width 0.1)
		(layer "In2.Cu")
		(net 148)
	)
	(segment
		(start 103.656604 134.375)
		(end 103.654097 134.397252)
		(width 0.1)
		(layer "In2.Cu")
		(net 148)
	)
	(segment
		(start 103.656604 135.175)
		(end 103.654097 135.197252)
		(width 0.1)
		(layer "In2.Cu")
		(net 148)
	)
	(segment
		(start 103.618953 135.253183)
		(end 103.599993 135.265096)
		(width 0.1)
		(layer "In2.Cu")
		(net 148)
	)
	(segment
		(start 103.284198 134.475)
		(end 103.263992 134.477276)
		(width 0.1)
		(layer "In2.Cu")
		(net 148)
	)
	(segment
		(start 103.384904 135.731611)
		(end 103.377508 135.752747)
		(width 0.1)
		(layer "In2.Cu")
		(net 148)
	)
	(segment
		(start 103.634788 135.637348)
		(end 103.618953 135.653183)
		(width 0.1)
		(layer "In2.Cu")
		(net 148)
	)
	(segment
		(start 103.646701 134.818388)
		(end 103.634788 134.837348)
		(width 0.1)
		(layer "In2.Cu")
		(net 148)
	)
	(segment
		(start 103.227583 134.49481)
		(end 103.213206 134.509187)
		(width 0.1)
		(layer "In2.Cu")
		(net 148)
	)
	(segment
		(start 103.195672 134.195205)
		(end 103.202388 134.214397)
		(width 0.1)
		(layer "In2.Cu")
		(net 148)
	)
	(segment
		(start 103.578857 135.672492)
		(end 103.556604 135.675)
		(width 0.1)
		(layer "In2.Cu")
		(net 148)
	)
	(segment
		(start 103.654097 135.597252)
		(end 103.646701 135.618388)
		(width 0.1)
		(layer "In2.Cu")
		(net 148)
	)
	(segment
		(start 103.599993 134.465096)
		(end 103.578857 134.472492)
		(width 0.1)
		(layer "In2.Cu")
		(net 148)
	)
	(segment
		(start 103.2448 134.883992)
		(end 103.227583 134.89481)
		(width 0.1)
		(layer "In2.Cu")
		(net 148)
	)
	(segment
		(start 103.654097 135.152747)
		(end 103.656604 135.175)
		(width 0.1)
		(layer "In2.Cu")
		(net 148)
	)
	(segment
		(start 103.634788 135.512651)
		(end 103.646701 135.531611)
		(width 0.1)
		(layer "In2.Cu")
		(net 148)
	)
	(segment
		(start 103.213206 135.309187)
		(end 103.202388 135.326404)
		(width 0.1)
		(layer "In2.Cu")
		(net 148)
	)
	(segment
		(start 103.556604 134.275)
		(end 103.578857 134.277507)
		(width 0.1)
		(layer "In2.Cu")
		(net 148)
	)
	(segment
		(start 103.646701 135.131611)
		(end 103.654097 135.152747)
		(width 0.1)
		(layer "In2.Cu")
		(net 148)
	)
	(segment
		(start 103.556604 134.675)
		(end 103.578857 134.677507)
		(width 0.1)
		(layer "In2.Cu")
		(net 148)
	)
	(segment
		(start 103.284198 134.265802)
		(end 103.375 134.265802)
		(width 0.1)
		(layer "In2.Cu")
		(net 148)
	)
	(segment
		(start 103.618953 135.653183)
		(end 103.599993 135.665096)
		(width 0.1)
		(layer "In2.Cu")
		(net 148)
	)
	(segment
		(start 103.578857 134.677507)
		(end 103.599993 134.684903)
		(width 0.1)
		(layer "In2.Cu")
		(net 148)
	)
	(segment
		(start 103.227583 135.455189)
		(end 103.2448 135.466007)
		(width 0.1)
		(layer "In2.Cu")
		(net 148)
	)
	(segment
		(start 103.263992 134.263525)
		(end 103.284198 134.265802)
		(width 0.1)
		(layer "In2.Cu")
		(net 148)
	)
	(segment
		(start 103.195672 135.004403)
		(end 103.202388 135.023595)
		(width 0.1)
		(layer "In2.Cu")
		(net 148)
	)
	(segment
		(start 103.366007 134.014397)
		(end 103.355189 134.031614)
		(width 0.1)
		(layer "In2.Cu")
		(net 148)
	)
	(segment
		(start 103.372723 133.995205)
		(end 103.366007 134.014397)
		(width 0.1)
		(layer "In2.Cu")
		(net 148)
	)
	(segment
		(start 103.2448 134.483992)
		(end 103.227583 134.49481)
		(width 0.1)
		(layer "In2.Cu")
		(net 148)
	)
	(segment
		(start 103.375 134.265802)
		(end 103.375 134.275)
		(width 0.1)
		(layer "In2.Cu")
		(net 148)
	)
	(segment
		(start 103.195672 135.404403)
		(end 103.202388 135.423595)
		(width 0.1)
		(layer "In2.Cu")
		(net 148)
	)
	(segment
		(start 103.656604 135.575)
		(end 103.654097 135.597252)
		(width 0.1)
		(layer "In2.Cu")
		(net 148)
	)
	(segment
		(start 103.654097 134.752747)
		(end 103.656604 134.775)
		(width 0.1)
		(layer "In2.Cu")
		(net 148)
	)
	(segment
		(start 103.599993 135.084903)
		(end 103.618953 135.096816)
		(width 0.1)
		(layer "In2.Cu")
		(net 148)
	)
	(segment
		(start 103.646701 134.418388)
		(end 103.634788 134.437348)
		(width 0.1)
		(layer "In2.Cu")
		(net 148)
	)
	(segment
		(start 103.284198 134.675)
		(end 103.556604 134.675)
		(width 0.1)
		(layer "In2.Cu")
		(net 148)
	)
	(segment
		(start 103.323595 134.056809)
		(end 103.304403 134.063525)
		(width 0.1)
		(layer "In2.Cu")
		(net 148)
	)
	(segment
		(start 103.227583 134.655189)
		(end 103.2448 134.666007)
		(width 0.1)
		(layer "In2.Cu")
		(net 148)
	)
	(segment
		(start 103.654097 134.397252)
		(end 103.646701 134.418388)
		(width 0.1)
		(layer "In2.Cu")
		(net 148)
	)
	(segment
		(start 103.195672 134.136398)
		(end 103.193396 134.156604)
		(width 0.1)
		(layer "In2.Cu")
		(net 148)
	)
	(segment
		(start 103.634788 134.312651)
		(end 103.646701 134.331611)
		(width 0.1)
		(layer "In2.Cu")
		(net 148)
	)
	(segment
		(start 103.618953 134.696816)
		(end 103.634788 134.712651)
		(width 0.1)
		(layer "In2.Cu")
		(net 148)
	)
	(segment
		(start 103.599993 135.665096)
		(end 103.578857 135.672492)
		(width 0.1)
		(layer "In2.Cu")
		(net 148)
	)
	(segment
		(start 103.227583 134.245991)
		(end 103.2448 134.256809)
		(width 0.1)
		(layer "In2.Cu")
		(net 148)
	)
	(segment
		(start 103.646701 135.531611)
		(end 103.654097 135.552747)
		(width 0.1)
		(layer "In2.Cu")
		(net 148)
	)
	(segment
		(start 103.431612 135.684903)
		(end 103.412652 135.696816)
		(width 0.1)
		(layer "In2.Cu")
		(net 148)
	)
	(segment
		(start 103.618953 135.496816)
		(end 103.634788 135.512651)
		(width 0.1)
		(layer "In2.Cu")
		(net 148)
	)
	(segment
		(start 103.556604 134.475)
		(end 103.284198 134.475)
		(width 0.1)
		(layer "In2.Cu")
		(net 148)
	)
	(segment
		(start 103.634788 134.437348)
		(end 103.618953 134.453183)
		(width 0.1)
		(layer "In2.Cu")
		(net 148)
	)
	(segment
		(start 103.213206 134.099989)
		(end 103.202388 134.117206)
		(width 0.1)
		(layer "In2.Cu")
		(net 148)
	)
	(segment
		(start 103.2448 134.074794)
		(end 103.227583 134.085612)
		(width 0.1)
		(layer "In2.Cu")
		(net 148)
	)
	(segment
		(start 103.475 135.675)
		(end 103.452748 135.677507)
		(width 0.1)
		(layer "In2.Cu")
		(net 148)
	)
	(segment
		(start 103.202388 134.623595)
		(end 103.213206 134.640812)
		(width 0.1)
		(layer "In2.Cu")
		(net 148)
	)
	(segment
		(start 103.263992 135.072723)
		(end 103.284198 135.075)
		(width 0.1)
		(layer "In2.Cu")
		(net 148)
	)
	(segment
		(start 103.195672 135.345596)
		(end 103.193396 135.365802)
		(width 0.1)
		(layer "In2.Cu")
		(net 148)
	)
	(segment
		(start 103.618953 134.853183)
		(end 103.599993 134.865096)
		(width 0.1)
		(layer "In2.Cu")
		(net 148)
	)
	(segment
		(start 103.202388 135.023595)
		(end 103.213206 135.040812)
		(width 0.1)
		(layer "In2.Cu")
		(net 148)
	)
	(segment
		(start 103.227583 134.89481)
		(end 103.213206 134.909187)
		(width 0.1)
		(layer "In2.Cu")
		(net 148)
	)
	(segment
		(start 103.213206 134.640812)
		(end 103.227583 134.655189)
		(width 0.1)
		(layer "In2.Cu")
		(net 148)
	)
	(segment
		(start 103.284198 135.275)
		(end 103.263992 135.277276)
		(width 0.1)
		(layer "In2.Cu")
		(net 148)
	)
	(segment
		(start 103.599993 134.684903)
		(end 103.618953 134.696816)
		(width 0.1)
		(layer "In2.Cu")
		(net 148)
	)
	(segment
		(start 102.975 144.175)
		(end 102.975 147.675)
		(width 0.1)
		(layer "In2.Cu")
		(net 148)
	)
	(segment
		(start 103.375 142.667272)
		(end 103.375 143.775)
		(width 0.1)
		(layer "In2.Cu")
		(net 148)
	)
	(segment
		(start 103.2448 134.256809)
		(end 103.263992 134.263525)
		(width 0.1)
		(layer "In2.Cu")
		(net 148)
	)
	(segment
		(start 103.284198 134.875)
		(end 103.263992 134.877276)
		(width 0.1)
		(layer "In2.Cu")
		(net 148)
	)
	(segment
		(start 103.193396 135.384198)
		(end 103.195672 135.404403)
		(width 0.1)
		(layer "In2.Cu")
		(net 148)
	)
	(segment
		(start 103.599993 134.284903)
		(end 103.618953 134.296816)
		(width 0.1)
		(layer "In2.Cu")
		(net 148)
	)
	(segment
		(start 103.263992 135.472723)
		(end 103.284198 135.475)
		(width 0.1)
		(layer "In2.Cu")
		(net 148)
	)
	(segment
		(start 103.375 139.092142)
		(end 103.375033 139.092175)
		(width 0.1)
		(layer "In2.Cu")
		(net 148)
	)
	(segment
		(start 103.646701 135.618388)
		(end 103.634788 135.637348)
		(width 0.1)
		(layer "In2.Cu")
		(net 148)
	)
	(segment
		(start 103.634788 134.837348)
		(end 103.618953 134.853183)
		(width 0.1)
		(layer "In2.Cu")
		(net 148)
	)
	(segment
		(start 103.375 134.275)
		(end 103.556604 134.275)
		(width 0.1)
		(layer "In2.Cu")
		(net 148)
	)
	(segment
		(start 103.634788 135.237348)
		(end 103.618953 135.253183)
		(width 0.1)
		(layer "In2.Cu")
		(net 148)
	)
	(segment
		(start 103.578857 135.272492)
		(end 103.556604 135.275)
		(width 0.1)
		(layer "In2.Cu")
		(net 148)
	)
	(segment
		(start 103.284198 135.475)
		(end 103.556604 135.475)
		(width 0.1)
		(layer "In2.Cu")
		(net 148)
	)
	(segment
		(start 103.263992 134.477276)
		(end 103.2448 134.483992)
		(width 0.1)
		(layer "In2.Cu")
		(net 148)
	)
	(segment
		(start 103.452748 135.677507)
		(end 103.431612 135.684903)
		(width 0.1)
		(layer "In2.Cu")
		(net 148)
	)
	(segment
		(start 103.213206 134.509187)
		(end 103.202388 134.526404)
		(width 0.1)
		(layer "In2.Cu")
		(net 148)
	)
	(segment
		(start 103.599993 135.265096)
		(end 103.578857 135.272492)
		(width 0.1)
		(layer "In2.Cu")
		(net 148)
	)
	(segment
		(start 103.284198 135.075)
		(end 103.556604 135.075)
		(width 0.1)
		(layer "In2.Cu")
		(net 148)
	)
	(segment
		(start 103.227583 135.29481)
		(end 103.213206 135.309187)
		(width 0.1)
		(layer "In2.Cu")
		(net 148)
	)
	(segment
		(start 103.193396 134.965802)
		(end 103.193396 134.984198)
		(width 0.1)
		(layer "In2.Cu")
		(net 148)
	)
	(segment
		(start 103.618953 135.096816)
		(end 103.634788 135.112651)
		(width 0.1)
		(layer "In2.Cu")
		(net 148)
	)
	(segment
		(start 103.396817 135.712651)
		(end 103.384904 135.731611)
		(width 0.1)
		(layer "In2.Cu")
		(net 148)
	)
	(segment
		(start 103.263992 134.877276)
		(end 103.2448 134.883992)
		(width 0.1)
		(layer "In2.Cu")
		(net 148)
	)
	(segment
		(start 103.213206 135.440812)
		(end 103.227583 135.455189)
		(width 0.1)
		(layer "In2.Cu")
		(net 148)
	)
	(segment
		(start 103.202388 135.326404)
		(end 103.195672 135.345596)
		(width 0.1)
		(layer "In2.Cu")
		(net 148)
	)
	(segment
		(start 103.2448 135.283992)
		(end 103.227583 135.29481)
		(width 0.1)
		(layer "In2.Cu")
		(net 148)
	)
	(segment
		(start 103.634788 134.712651)
		(end 103.646701 134.731611)
		(width 0.1)
		(layer "In2.Cu")
		(net 148)
	)
	(segment
		(start 103.213206 134.231614)
		(end 103.227583 134.245991)
		(width 0.1)
		(layer "In2.Cu")
		(net 148)
	)
	(segment
		(start 103.656604 134.775)
		(end 103.654097 134.797252)
		(width 0.1)
		(layer "In2.Cu")
		(net 148)
	)
	(segment
		(start 103.193396 135.365802)
		(end 103.193396 135.384198)
		(width 0.1)
		(layer "In2.Cu")
		(net 148)
	)
	(segment
		(start 103.556604 135.475)
		(end 103.578857 135.477507)
		(width 0.1)
		(layer "In2.Cu")
		(net 148)
	)
	(segment
		(start 103.556604 135.075)
		(end 103.578857 135.077507)
		(width 0.1)
		(layer "In2.Cu")
		(net 148)
	)
	(segment
		(start 103.618953 134.453183)
		(end 103.599993 134.465096)
		(width 0.1)
		(layer "In2.Cu")
		(net 148)
	)
	(segment
		(start 103.375 143.775)
		(end 102.975 144.175)
		(width 0.1)
		(layer "In2.Cu")
		(net 148)
	)
	(segment
		(start 103.193396 134.984198)
		(end 103.195672 135.004403)
		(width 0.1)
		(layer "In2.Cu")
		(net 148)
	)
	(segment
		(start 103.412652 135.696816)
		(end 103.396817 135.712651)
		(width 0.1)
		(layer "In2.Cu")
		(net 148)
	)
	(segment
		(start 103.578857 134.472492)
		(end 103.556604 134.475)
		(width 0.1)
		(layer "In2.Cu")
		(net 148)
	)
	(segment
		(start 103.634788 135.112651)
		(end 103.646701 135.131611)
		(width 0.1)
		(layer "In2.Cu")
		(net 148)
	)
	(segment
		(start 103.193396 134.175)
		(end 103.195672 134.195205)
		(width 0.1)
		(layer "In2.Cu")
		(net 148)
	)
	(segment
		(start 103.377508 135.752747)
		(end 103.375 135.775)
		(width 0.1)
		(layer "In2.Cu")
		(net 148)
	)
	(segment
		(start 103.213206 135.040812)
		(end 103.227583 135.055189)
		(width 0.1)
		(layer "In2.Cu")
		(net 148)
	)
	(segment
		(start 103.646701 134.731611)
		(end 103.654097 134.752747)
		(width 0.1)
		(layer "In2.Cu")
		(net 148)
	)
	(segment
		(start 103.578857 134.872492)
		(end 103.556604 134.875)
		(width 0.1)
		(layer "In2.Cu")
		(net 148)
	)
	(segment
		(start 103.202388 134.214397)
		(end 103.213206 134.231614)
		(width 0.1)
		(layer "In2.Cu")
		(net 148)
	)
	(segment
		(start 103.654097 135.552747)
		(end 103.656604 135.575)
		(width 0.1)
		(layer "In2.Cu")
		(net 148)
	)
	(segment
		(start 103.202388 134.526404)
		(end 103.195672 134.545596)
		(width 0.1)
		(layer "In2.Cu")
		(net 148)
	)
	(segment
		(start 103.227583 134.085612)
		(end 103.213206 134.099989)
		(width 0.1)
		(layer "In2.Cu")
		(net 148)
	)
	(segment
		(start 103.193396 134.156604)
		(end 103.193396 134.175)
		(width 0.1)
		(layer "In2.Cu")
		(net 148)
	)
	(segment
		(start 103.202388 134.926404)
		(end 103.195672 134.945596)
		(width 0.1)
		(layer "In2.Cu")
		(net 148)
	)
	(segment
		(start 103.375 130.028629)
		(end 103.375 133.975)
		(width 0.1)
		(layer "In2.Cu")
		(net 148)
	)
	(segment
		(start 103.263992 134.068078)
		(end 103.2448 134.074794)
		(width 0.1)
		(layer "In2.Cu")
		(net 148)
	)
	(segment
		(start 103.2448 135.066007)
		(end 103.263992 135.072723)
		(width 0.1)
		(layer "In2.Cu")
		(net 148)
	)
	(segment
		(start 103.556604 135.675)
		(end 103.475 135.675)
		(width 0.1)
		(layer "In2.Cu")
		(net 148)
	)
	(segment
		(start 103.195672 134.604403)
		(end 103.202388 134.623595)
		(width 0.1)
		(layer "In2.Cu")
		(net 148)
	)
	(segment
		(start 103.578857 134.277507)
		(end 103.599993 134.284903)
		(width 0.1)
		(layer "In2.Cu")
		(net 148)
	)
	(segment
		(start 103.227583 135.055189)
		(end 103.2448 135.066007)
		(width 0.1)
		(layer "In2.Cu")
		(net 148)
	)
	(segment
		(start 103.202388 135.423595)
		(end 103.213206 135.440812)
		(width 0.1)
		(layer "In2.Cu")
		(net 148)
	)
	(segment
		(start 103.304403 134.063525)
		(end 103.263992 134.068078)
		(width 0.1)
		(layer "In2.Cu")
		(net 148)
	)
	(segment
		(start 103.599993 135.484903)
		(end 103.618953 135.496816)
		(width 0.1)
		(layer "In2.Cu")
		(net 148)
	)
	(segment
		(start 103.578857 135.477507)
		(end 103.599993 135.484903)
		(width 0.1)
		(layer "In2.Cu")
		(net 148)
	)
	(segment
		(start 103.193396 134.565802)
		(end 103.193396 134.584198)
		(width 0.1)
		(layer "In2.Cu")
		(net 148)
	)
	(segment
		(start 103.556604 135.275)
		(end 103.284198 135.275)
		(width 0.1)
		(layer "In2.Cu")
		(net 148)
	)
	(segment
		(start 103.195672 134.545596)
		(end 103.193396 134.565802)
		(width 0.1)
		(layer "In2.Cu")
		(net 148)
	)
	(segment
		(start 103.355189 134.031614)
		(end 103.340812 134.045991)
		(width 0.1)
		(layer "In2.Cu")
		(net 148)
	)
	(segment
		(start 103.2448 135.466007)
		(end 103.263992 135.472723)
		(width 0.1)
		(layer "In2.Cu")
		(net 148)
	)
	(segment
		(start 103.375 133.975)
		(end 103.372723 133.995205)
		(width 0.1)
		(layer "In2.Cu")
		(net 148)
	)
	(segment
		(start 103.654097 134.797252)
		(end 103.646701 134.818388)
		(width 0.1)
		(layer "In2.Cu")
		(net 148)
	)
	(segment
		(start 103.202388 134.117206)
		(end 103.195672 134.136398)
		(width 0.1)
		(layer "In2.Cu")
		(net 148)
	)
	(segment
		(start 103.375033 142.667239)
		(end 103.375 142.667272)
		(width 0.1)
		(layer "In2.Cu")
		(net 148)
	)
	(segment
		(start 103.375076 130.028553)
		(end 103.375 130.028629)
		(width 0.1)
		(layer "In2.Cu")
		(net 148)
	)
	(segment
		(start 103.556604 134.875)
		(end 103.284198 134.875)
		(width 0.1)
		(layer "In2.Cu")
		(net 148)
	)
	(segment
		(start 103.375033 139.092175)
		(end 103.375033 142.667239)
		(width 0.1)
		(layer "In2.Cu")
		(net 148)
	)
	(segment
		(start 103.375 135.775)
		(end 103.375 139.092142)
		(width 0.1)
		(layer "In2.Cu")
		(net 148)
	)
	(segment
		(start 103.263992 135.277276)
		(end 103.2448 135.283992)
		(width 0.1)
		(layer "In2.Cu")
		(net 148)
	)
	(segment
		(start 103.618953 134.296816)
		(end 103.634788 134.312651)
		(width 0.1)
		(layer "In2.Cu")
		(net 148)
	)
	(segment
		(start 103.195672 134.945596)
		(end 103.193396 134.965802)
		(width 0.1)
		(layer "In2.Cu")
		(net 148)
	)
	(segment
		(start 103.654097 135.197252)
		(end 103.646701 135.218388)
		(width 0.1)
		(layer "In2.Cu")
		(net 148)
	)
	(segment
		(start 103.646701 134.331611)
		(end 103.654097 134.352747)
		(width 0.1)
		(layer "In2.Cu")
		(net 148)
	)
	(segment
		(start 103.578857 135.077507)
		(end 103.599993 135.084903)
		(width 0.1)
		(layer "In2.Cu")
		(net 148)
	)
	(segment
		(start 103.375 148.775)
		(end 103.375 148.175)
		(width 0.1)
		(layer "F.Cu")
		(net 149)
	)
	(segment
		(start 104.775 130.175)
		(end 104.25537 130.69463)
		(width 0.15)
		(layer "F.Cu")
		(net 149)
	)
	(segment
		(start 104.25537 130.69463)
		(end 104.074998 130.69463)
		(width 0.15)
		(layer "F.Cu")
		(net 149)
	)
	(via
		(at 103.375 148.175)
		(size 0.5)
		(drill 0.2)
		(layers "F.Cu" "B.Cu")
		(net 149)
	)
	(via blind
		(at 104.074998 130.69463)
		(size 0.5)
		(drill 0.2)
		(layers "F.Cu" "In2.Cu")
		(net 149)
	)
	(segment
		(start 103.375 148.175)
		(end 104.175 148.975)
		(width 0.1)
		(layer "B.Cu")
		(net 149)
	)
	(segment
		(start 104.175 148.975)
		(end 104.175 149.19)
		(width 0.1)
		(layer "B.Cu")
		(net 149)
	)
	(segment
		(start 104.237349 133.453183)
		(end 104.218389 133.465096)
		(width 0.1)
		(layer "In2.Cu")
		(net 149)
	)
	(segment
		(start 104.175 133.475)
		(end 103.675 133.475)
		(width 0.1)
		(layer "In2.Cu")
		(net 149)
	)
	(segment
		(start 104.074998 131.048183)
		(end 104.175011 131.148196)
		(width 0.1)
		(layer "In2.Cu")
		(net 149)
	)
	(segment
		(start 103.631611 132.684903)
		(end 103.612651 132.696816)
		(width 0.1)
		(layer "In2.Cu")
		(net 149)
	)
	(segment
		(start 103.577507 133.152747)
		(end 103.575 133.175)
		(width 0.1)
		(layer "In2.Cu")
		(net 149)
	)
	(segment
		(start 103.853183 132.637348)
		(end 103.837348 132.653183)
		(width 0.1)
		(layer "In2.Cu")
		(net 149)
	)
	(segment
		(start 104.074998 130.69463)
		(end 104.074998 131.048183)
		(width 0.1)
		(layer "In2.Cu")
		(net 149)
	)
	(segment
		(start 103.652747 132.872492)
		(end 103.675 132.875)
		(width 0.1)
		(layer "In2.Cu")
		(net 149)
	)
	(segment
		(start 103.596816 132.837348)
		(end 103.612651 132.853183)
		(width 0.1)
		(layer "In2.Cu")
		(net 149)
	)
	(segment
		(start 103.612651 133.653183)
		(end 103.631611 133.665096)
		(width 0.1)
		(layer "In2.Cu")
		(net 149)
	)
	(segment
		(start 103.652747 133.272492)
		(end 103.675 133.275)
		(width 0.1)
		(layer "In2.Cu")
		(net 149)
	)
	(segment
		(start 104.175042 141.517001)
		(end 104.175 141.517043)
		(width 0.1)
		(layer "In2.Cu")
		(net 149)
	)
	(segment
		(start 104.175011 131.148196)
		(end 104.175011 131.667001)
		(width 0.1)
		(layer "In2.Cu")
		(net 149)
	)
	(segment
		(start 103.584903 133.618388)
		(end 103.596816 133.637348)
		(width 0.1)
		(layer "In2.Cu")
		(net 149)
	)
	(segment
		(start 103.596816 133.112651)
		(end 103.584903 133.131611)
		(width 0.1)
		(layer "In2.Cu")
		(net 149)
	)
	(segment
		(start 103.375 147.375)
		(end 103.375 148.175)
		(width 0.1)
		(layer "In2.Cu")
		(net 149)
	)
	(segment
		(start 103.584903 133.218388)
		(end 103.596816 133.237348)
		(width 0.1)
		(layer "In2.Cu")
		(net 149)
	)
	(segment
		(start 103.865096 132.618388)
		(end 103.853183 132.637348)
		(width 0.1)
		(layer "In2.Cu")
		(net 149)
	)
	(segment
		(start 104.253184 133.037348)
		(end 104.237349 133.053183)
		(width 0.1)
		(layer "In2.Cu")
		(net 149)
	)
	(segment
		(start 104.272493 133.397252)
		(end 104.265097 133.418388)
		(width 0.1)
		(layer "In2.Cu")
		(net 149)
	)
	(segment
		(start 104.275 132.975)
		(end 104.272493 132.997252)
		(width 0.1)
		(layer "In2.Cu")
		(net 149)
	)
	(segment
		(start 103.577507 133.197252)
		(end 103.584903 133.218388)
		(width 0.1)
		(layer "In2.Cu")
		(net 149)
	)
	(segment
		(start 103.837348 133.696816)
		(end 103.853183 133.712651)
		(width 0.1)
		(layer "In2.Cu")
		(net 149)
	)
	(segment
		(start 103.872492 132.597252)
		(end 103.865096 132.618388)
		(width 0.1)
		(layer "In2.Cu")
		(net 149)
	)
	(segment
		(start 104.175 140.975)
		(end 104.175 141.132957)
		(width 0.1)
		(layer "In2.Cu")
		(net 149)
	)
	(segment
		(start 104.218389 133.284903)
		(end 104.237349 133.296816)
		(width 0.1)
		(layer "In2.Cu")
		(net 149)
	)
	(segment
		(start 104.197253 133.277507)
		(end 104.218389 133.284903)
		(width 0.1)
		(layer "In2.Cu")
		(net 149)
	)
	(segment
		(start 103.837348 132.653183)
		(end 103.818388 132.665096)
		(width 0.1)
		(layer "In2.Cu")
		(net 149)
	)
	(segment
		(start 103.575 132.775)
		(end 103.577507 132.797252)
		(width 0.1)
		(layer "In2.Cu")
		(net 149)
	)
	(segment
		(start 104.175 131.667012)
		(end 104.175 132.075)
		(width 0.1)
		(layer "In2.Cu")
		(net 149)
	)
	(segment
		(start 104.272493 132.952747)
		(end 104.275 132.975)
		(width 0.1)
		(layer "In2.Cu")
		(net 149)
	)
	(segment
		(start 103.577507 132.797252)
		(end 103.584903 132.818388)
		(width 0.1)
		(layer "In2.Cu")
		(net 149)
	)
	(segment
		(start 104.175 132.875)
		(end 104.197253 132.877507)
		(width 0.1)
		(layer "In2.Cu")
		(net 149)
	)
	(segment
		(start 104.175 141.132957)
		(end 104.175042 141.132999)
		(width 0.1)
		(layer "In2.Cu")
		(net 149)
	)
	(segment
		(start 103.797252 133.677507)
		(end 103.818388 133.684903)
		(width 0.1)
		(layer "In2.Cu")
		(net 149)
	)
	(segment
		(start 103.652747 133.477507)
		(end 103.631611 133.484903)
		(width 0.1)
		(layer "In2.Cu")
		(net 149)
	)
	(segment
		(start 104.197253 133.472492)
		(end 104.175 133.475)
		(width 0.1)
		(layer "In2.Cu")
		(net 149)
	)
	(segment
		(start 103.577507 132.752747)
		(end 103.575 132.775)
		(width 0.1)
		(layer "In2.Cu")
		(net 149)
	)
	(segment
		(start 103.675 133.275)
		(end 104.175 133.275)
		(width 0.1)
		(layer "In2.Cu")
		(net 149)
	)
	(segment
		(start 103.675 133.075)
		(end 103.652747 133.077507)
		(width 0.1)
		(layer "In2.Cu")
		(net 149)
	)
	(segment
		(start 104.175 146.575)
		(end 103.375 147.375)
		(width 0.1)
		(layer "In2.Cu")
		(net 149)
	)
	(segment
		(start 103.577507 133.552747)
		(end 103.575 133.575)
		(width 0.1)
		(layer "In2.Cu")
		(net 149)
	)
	(segment
		(start 104.197253 133.072492)
		(end 104.175 133.075)
		(width 0.1)
		(layer "In2.Cu")
		(net 149)
	)
	(segment
		(start 103.652747 133.672492)
		(end 103.675 133.675)
		(width 0.1)
		(layer "In2.Cu")
		(net 149)
	)
	(segment
		(start 103.675 133.675)
		(end 103.775 133.675)
		(width 0.1)
		(layer "In2.Cu")
		(net 149)
	)
	(segment
		(start 103.675 133.475)
		(end 103.652747 133.477507)
		(width 0.1)
		(layer "In2.Cu")
		(net 149)
	)
	(segment
		(start 104.265097 133.418388)
		(end 104.253184 133.437348)
		(width 0.1)
		(layer "In2.Cu")
		(net 149)
	)
	(segment
		(start 104.175 141.517043)
		(end 104.175 146.575)
		(width 0.1)
		(layer "In2.Cu")
		(net 149)
	)
	(segment
		(start 103.584903 133.131611)
		(end 103.577507 133.152747)
		(width 0.1)
		(layer "In2.Cu")
		(net 149)
	)
	(segment
		(start 103.875 133.775)
		(end 103.875 140.675)
		(width 0.1)
		(layer "In2.Cu")
		(net 149)
	)
	(segment
		(start 103.797252 132.672492)
		(end 103.775 132.675)
		(width 0.1)
		(layer "In2.Cu")
		(net 149)
	)
	(segment
		(start 103.875 132.575)
		(end 103.872492 132.597252)
		(width 0.1)
		(layer "In2.Cu")
		(net 149)
	)
	(segment
		(start 103.612651 133.496816)
		(end 103.596816 133.512651)
		(width 0.1)
		(layer "In2.Cu")
		(net 149)
	)
	(segment
		(start 104.272493 132.997252)
		(end 104.265097 133.018388)
		(width 0.1)
		(layer "In2.Cu")
		(net 149)
	)
	(segment
		(start 104.175042 141.132999)
		(end 104.175042 141.517001)
		(width 0.1)
		(layer "In2.Cu")
		(net 149)
	)
	(segment
		(start 103.631611 133.265096)
		(end 103.652747 133.272492)
		(width 0.1)
		(layer "In2.Cu")
		(net 149)
	)
	(segment
		(start 104.237349 132.896816)
		(end 104.253184 132.912651)
		(width 0.1)
		(layer "In2.Cu")
		(net 149)
	)
	(segment
		(start 103.596816 132.712651)
		(end 103.584903 132.731611)
		(width 0.1)
		(layer "In2.Cu")
		(net 149)
	)
	(segment
		(start 104.175 132.075)
		(end 103.875 132.375)
		(width 0.1)
		(layer "In2.Cu")
		(net 149)
	)
	(segment
		(start 104.253184 133.437348)
		(end 104.237349 133.453183)
		(width 0.1)
		(layer "In2.Cu")
		(net 149)
	)
	(segment
		(start 104.265097 133.018388)
		(end 104.253184 133.037348)
		(width 0.1)
		(layer "In2.Cu")
		(net 149)
	)
	(segment
		(start 104.175011 131.667001)
		(end 104.175 131.667012)
		(width 0.1)
		(layer "In2.Cu")
		(net 149)
	)
	(segment
		(start 103.631611 133.484903)
		(end 103.612651 133.496816)
		(width 0.1)
		(layer "In2.Cu")
		(net 149)
	)
	(segment
		(start 103.875 140.675)
		(end 104.175 140.975)
		(width 0.1)
		(layer "In2.Cu")
		(net 149)
	)
	(segment
		(start 103.575 133.575)
		(end 103.577507 133.597252)
		(width 0.1)
		(layer "In2.Cu")
		(net 149)
	)
	(segment
		(start 103.775 132.675)
		(end 103.675 132.675)
		(width 0.1)
		(layer "In2.Cu")
		(net 149)
	)
	(segment
		(start 104.253184 133.312651)
		(end 104.265097 133.331611)
		(width 0.1)
		(layer "In2.Cu")
		(net 149)
	)
	(segment
		(start 103.775 133.675)
		(end 103.797252 133.677507)
		(width 0.1)
		(layer "In2.Cu")
		(net 149)
	)
	(segment
		(start 104.175 133.275)
		(end 104.197253 133.277507)
		(width 0.1)
		(layer "In2.Cu")
		(net 149)
	)
	(segment
		(start 103.865096 133.731611)
		(end 103.872492 133.752747)
		(width 0.1)
		(layer "In2.Cu")
		(net 149)
	)
	(segment
		(start 103.675 132.875)
		(end 104.175 132.875)
		(width 0.1)
		(layer "In2.Cu")
		(net 149)
	)
	(segment
		(start 103.584903 133.531611)
		(end 103.577507 133.552747)
		(width 0.1)
		(layer "In2.Cu")
		(net 149)
	)
	(segment
		(start 103.872492 133.752747)
		(end 103.875 133.775)
		(width 0.1)
		(layer "In2.Cu")
		(net 149)
	)
	(segment
		(start 104.237349 133.296816)
		(end 104.253184 133.312651)
		(width 0.1)
		(layer "In2.Cu")
		(net 149)
	)
	(segment
		(start 104.218389 132.884903)
		(end 104.237349 132.896816)
		(width 0.1)
		(layer "In2.Cu")
		(net 149)
	)
	(segment
		(start 103.596816 133.512651)
		(end 103.584903 133.531611)
		(width 0.1)
		(layer "In2.Cu")
		(net 149)
	)
	(segment
		(start 103.584903 132.731611)
		(end 103.577507 132.752747)
		(width 0.1)
		(layer "In2.Cu")
		(net 149)
	)
	(segment
		(start 103.612651 132.853183)
		(end 103.631611 132.865096)
		(width 0.1)
		(layer "In2.Cu")
		(net 149)
	)
	(segment
		(start 103.631611 133.084903)
		(end 103.612651 133.096816)
		(width 0.1)
		(layer "In2.Cu")
		(net 149)
	)
	(segment
		(start 104.218389 133.465096)
		(end 104.197253 133.472492)
		(width 0.1)
		(layer "In2.Cu")
		(net 149)
	)
	(segment
		(start 103.612651 133.096816)
		(end 103.596816 133.112651)
		(width 0.1)
		(layer "In2.Cu")
		(net 149)
	)
	(segment
		(start 103.853183 133.712651)
		(end 103.865096 133.731611)
		(width 0.1)
		(layer "In2.Cu")
		(net 149)
	)
	(segment
		(start 103.612651 132.696816)
		(end 103.596816 132.712651)
		(width 0.1)
		(layer "In2.Cu")
		(net 149)
	)
	(segment
		(start 104.253184 132.912651)
		(end 104.265097 132.931611)
		(width 0.1)
		(layer "In2.Cu")
		(net 149)
	)
	(segment
		(start 103.652747 132.677507)
		(end 103.631611 132.684903)
		(width 0.1)
		(layer "In2.Cu")
		(net 149)
	)
	(segment
		(start 103.818388 133.684903)
		(end 103.837348 133.696816)
		(width 0.1)
		(layer "In2.Cu")
		(net 149)
	)
	(segment
		(start 103.612651 133.253183)
		(end 103.631611 133.265096)
		(width 0.1)
		(layer "In2.Cu")
		(net 149)
	)
	(segment
		(start 103.631611 132.865096)
		(end 103.652747 132.872492)
		(width 0.1)
		(layer "In2.Cu")
		(net 149)
	)
	(segment
		(start 104.218389 133.065096)
		(end 104.197253 133.072492)
		(width 0.1)
		(layer "In2.Cu")
		(net 149)
	)
	(segment
		(start 104.265097 133.331611)
		(end 104.272493 133.352747)
		(width 0.1)
		(layer "In2.Cu")
		(net 149)
	)
	(segment
		(start 103.818388 132.665096)
		(end 103.797252 132.672492)
		(width 0.1)
		(layer "In2.Cu")
		(net 149)
	)
	(segment
		(start 103.631611 133.665096)
		(end 103.652747 133.672492)
		(width 0.1)
		(layer "In2.Cu")
		(net 149)
	)
	(segment
		(start 104.197253 132.877507)
		(end 104.218389 132.884903)
		(width 0.1)
		(layer "In2.Cu")
		(net 149)
	)
	(segment
		(start 103.575 133.175)
		(end 103.577507 133.197252)
		(width 0.1)
		(layer "In2.Cu")
		(net 149)
	)
	(segment
		(start 104.237349 133.053183)
		(end 104.218389 133.065096)
		(width 0.1)
		(layer "In2.Cu")
		(net 149)
	)
	(segment
		(start 104.272493 133.352747)
		(end 104.275 133.375)
		(width 0.1)
		(layer "In2.Cu")
		(net 149)
	)
	(segment
		(start 103.584903 132.818388)
		(end 103.596816 132.837348)
		(width 0.1)
		(layer "In2.Cu")
		(net 149)
	)
	(segment
		(start 103.652747 133.077507)
		(end 103.631611 133.084903)
		(width 0.1)
		(layer "In2.Cu")
		(net 149)
	)
	(segment
		(start 103.596816 133.637348)
		(end 103.612651 133.653183)
		(width 0.1)
		(layer "In2.Cu")
		(net 149)
	)
	(segment
		(start 103.577507 133.597252)
		(end 103.584903 133.618388)
		(width 0.1)
		(layer "In2.Cu")
		(net 149)
	)
	(segment
		(start 103.596816 133.237348)
		(end 103.612651 133.253183)
		(width 0.1)
		(layer "In2.Cu")
		(net 149)
	)
	(segment
		(start 104.265097 132.931611)
		(end 104.272493 132.952747)
		(width 0.1)
		(layer "In2.Cu")
		(net 149)
	)
	(segment
		(start 103.675 132.675)
		(end 103.652747 132.677507)
		(width 0.1)
		(layer "In2.Cu")
		(net 149)
	)
	(segment
		(start 103.875 132.375)
		(end 103.875 132.575)
		(width 0.1)
		(layer "In2.Cu")
		(net 149)
	)
	(segment
		(start 104.175 133.075)
		(end 103.675 133.075)
		(width 0.1)
		(layer "In2.Cu")
		(net 149)
	)
	(segment
		(start 104.275 133.375)
		(end 104.272493 133.397252)
		(width 0.1)
		(layer "In2.Cu")
		(net 149)
	)
	(segment
		(start 103.375 145.575)
		(end 103.375 146.175)
		(width 0.1)
		(layer "F.Cu")
		(net 150)
	)
	(segment
		(start 102.37501 126.57499)
		(end 102.37501 126.675)
		(width 0.15)
		(layer "F.Cu")
		(net 150)
	)
	(segment
		(start 102.775 126.175)
		(end 102.37501 126.57499)
		(width 0.15)
		(layer "F.Cu")
		(net 150)
	)
	(via blind
		(at 102.37501 126.675)
		(size 0.5)
		(drill 0.2)
		(layers "F.Cu" "In5.Cu")
		(net 150)
	)
	(via
		(at 103.375 146.175)
		(size 0.5)
		(drill 0.2)
		(layers "F.Cu" "B.Cu")
		(net 150)
	)
	(segment
		(start 103.575 145.975)
		(end 103.375 146.175)
		(width 0.15)
		(layer "B.Cu")
		(net 150)
	)
	(segment
		(start 103.575 145.16)
		(end 103.575 145.975)
		(width 0.15)
		(layer "B.Cu")
		(net 150)
	)
	(segment
		(start 102.257652 128.352802)
		(end 102.255145 128.375055)
		(width 0.1)
		(layer "In5.Cu")
		(net 150)
	)
	(segment
		(start 102.355145 128.475055)
		(end 102.944965 128.475055)
		(width 0.1)
		(layer "In5.Cu")
		(net 150)
	)
	(segment
		(start 102.265048 128.418443)
		(end 102.276961 128.437403)
		(width 0.1)
		(layer "In5.Cu")
		(net 150)
	)
	(segment
		(start 103.007314 128.496871)
		(end 103.023149 128.512706)
		(width 0.1)
		(layer "In5.Cu")
		(net 150)
	)
	(segment
		(start 102.718443 128.265151)
		(end 102.697307 128.272547)
		(width 0.1)
		(layer "In5.Cu")
		(net 150)
	)
	(segment
		(start 103.023149 128.512706)
		(end 103.035062 128.531666)
		(width 0.1)
		(layer "In5.Cu")
		(net 150)
	)
	(segment
		(start 102.775055 128.775055)
		(end 102.775055 142.075055)
		(width 0.1)
		(layer "In5.Cu")
		(net 150)
	)
	(segment
		(start 103.007314 128.653238)
		(end 102.988354 128.665151)
		(width 0.1)
		(layer "In5.Cu")
		(net 150)
	)
	(segment
		(start 103.023149 128.637403)
		(end 103.007314 128.653238)
		(width 0.1)
		(layer "In5.Cu")
		(net 150)
	)
	(segment
		(start 102.257652 128.397307)
		(end 102.265048 128.418443)
		(width 0.1)
		(layer "In5.Cu")
		(net 150)
	)
	(segment
		(start 102.772547 128.197307)
		(end 102.765151 128.218443)
		(width 0.1)
		(layer "In5.Cu")
		(net 150)
	)
	(segment
		(start 103.375 142.675)
		(end 103.375 146.175)
		(width 0.1)
		(layer "In5.Cu")
		(net 150)
	)
	(segment
		(start 102.812707 128.696871)
		(end 102.796872 128.712706)
		(width 0.1)
		(layer "In5.Cu")
		(net 150)
	)
	(segment
		(start 102.737403 128.253238)
		(end 102.718443 128.265151)
		(width 0.1)
		(layer "In5.Cu")
		(net 150)
	)
	(segment
		(start 102.831667 128.684958)
		(end 102.812707 128.696871)
		(width 0.1)
		(layer "In5.Cu")
		(net 150)
	)
	(segment
		(start 103.042458 128.597307)
		(end 103.035062 128.618443)
		(width 0.1)
		(layer "In5.Cu")
		(net 150)
	)
	(segment
		(start 102.775055 128.175055)
		(end 102.772547 128.197307)
		(width 0.1)
		(layer "In5.Cu")
		(net 150)
	)
	(segment
		(start 102.967218 128.672547)
		(end 102.944965 128.675055)
		(width 0.1)
		(layer "In5.Cu")
		(net 150)
	)
	(segment
		(start 102.265048 128.331666)
		(end 102.257652 128.352802)
		(width 0.1)
		(layer "In5.Cu")
		(net 150)
	)
	(segment
		(start 102.311756 128.465151)
		(end 102.332892 128.472547)
		(width 0.1)
		(layer "In5.Cu")
		(net 150)
	)
	(segment
		(start 102.332892 128.472547)
		(end 102.355145 128.475055)
		(width 0.1)
		(layer "In5.Cu")
		(net 150)
	)
	(segment
		(start 102.775055 142.075055)
		(end 103.375 142.675)
		(width 0.1)
		(layer "In5.Cu")
		(net 150)
	)
	(segment
		(start 102.765151 128.218443)
		(end 102.753238 128.237403)
		(width 0.1)
		(layer "In5.Cu")
		(net 150)
	)
	(segment
		(start 102.675055 128.275055)
		(end 102.355145 128.275055)
		(width 0.1)
		(layer "In5.Cu")
		(net 150)
	)
	(segment
		(start 102.355145 128.275055)
		(end 102.332892 128.277562)
		(width 0.1)
		(layer "In5.Cu")
		(net 150)
	)
	(segment
		(start 102.276961 128.437403)
		(end 102.292796 128.453238)
		(width 0.1)
		(layer "In5.Cu")
		(net 150)
	)
	(segment
		(start 102.292796 128.296871)
		(end 102.276961 128.312706)
		(width 0.1)
		(layer "In5.Cu")
		(net 150)
	)
	(segment
		(start 103.035062 128.531666)
		(end 103.042458 128.552802)
		(width 0.1)
		(layer "In5.Cu")
		(net 150)
	)
	(segment
		(start 103.042458 128.552802)
		(end 103.044965 128.575055)
		(width 0.1)
		(layer "In5.Cu")
		(net 150)
	)
	(segment
		(start 102.276961 128.312706)
		(end 102.265048 128.331666)
		(width 0.1)
		(layer "In5.Cu")
		(net 150)
	)
	(segment
		(start 102.255145 128.375055)
		(end 102.257652 128.397307)
		(width 0.1)
		(layer "In5.Cu")
		(net 150)
	)
	(segment
		(start 102.784959 128.731666)
		(end 102.777563 128.752802)
		(width 0.1)
		(layer "In5.Cu")
		(net 150)
	)
	(segment
		(start 103.035062 128.618443)
		(end 103.023149 128.637403)
		(width 0.1)
		(layer "In5.Cu")
		(net 150)
	)
	(segment
		(start 102.988354 128.484958)
		(end 103.007314 128.496871)
		(width 0.1)
		(layer "In5.Cu")
		(net 150)
	)
	(segment
		(start 102.37501 126.675)
		(end 102.775055 127.075045)
		(width 0.1)
		(layer "In5.Cu")
		(net 150)
	)
	(segment
		(start 103.044965 128.575055)
		(end 103.042458 128.597307)
		(width 0.1)
		(layer "In5.Cu")
		(net 150)
	)
	(segment
		(start 102.292796 128.453238)
		(end 102.311756 128.465151)
		(width 0.1)
		(layer "In5.Cu")
		(net 150)
	)
	(segment
		(start 102.852803 128.677562)
		(end 102.831667 128.684958)
		(width 0.1)
		(layer "In5.Cu")
		(net 150)
	)
	(segment
		(start 102.967218 128.477562)
		(end 102.988354 128.484958)
		(width 0.1)
		(layer "In5.Cu")
		(net 150)
	)
	(segment
		(start 102.777563 128.752802)
		(end 102.775055 128.775055)
		(width 0.1)
		(layer "In5.Cu")
		(net 150)
	)
	(segment
		(start 102.697307 128.272547)
		(end 102.675055 128.275055)
		(width 0.1)
		(layer "In5.Cu")
		(net 150)
	)
	(segment
		(start 102.332892 128.277562)
		(end 102.311756 128.284958)
		(width 0.1)
		(layer "In5.Cu")
		(net 150)
	)
	(segment
		(start 102.775055 127.075045)
		(end 102.775055 128.175055)
		(width 0.1)
		(layer "In5.Cu")
		(net 150)
	)
	(segment
		(start 102.875055 128.675055)
		(end 102.852803 128.677562)
		(width 0.1)
		(layer "In5.Cu")
		(net 150)
	)
	(segment
		(start 102.988354 128.665151)
		(end 102.967218 128.672547)
		(width 0.1)
		(layer "In5.Cu")
		(net 150)
	)
	(segment
		(start 102.944965 128.675055)
		(end 102.875055 128.675055)
		(width 0.1)
		(layer "In5.Cu")
		(net 150)
	)
	(segment
		(start 102.311756 128.284958)
		(end 102.292796 128.296871)
		(width 0.1)
		(layer "In5.Cu")
		(net 150)
	)
	(segment
		(start 102.796872 128.712706)
		(end 102.784959 128.731666)
		(width 0.1)
		(layer "In5.Cu")
		(net 150)
	)
	(segment
		(start 102.753238 128.237403)
		(end 102.737403 128.253238)
		(width 0.1)
		(layer "In5.Cu")
		(net 150)
	)
	(segment
		(start 102.944965 128.475055)
		(end 102.967218 128.477562)
		(width 0.1)
		(layer "In5.Cu")
		(net 150)
	)
	(segment
		(start 104.175 148.775)
		(end 104.175 148.175)
		(width 0.1)
		(layer "F.Cu")
		(net 151)
	)
	(segment
		(start 103.775 129.175)
		(end 103.275021 128.675021)
		(width 0.15)
		(layer "F.Cu")
		(net 151)
	)
	(segment
		(start 103.275021 128.675021)
		(end 103.275021 128.675)
		(width 0.15)
		(layer "F.Cu")
		(net 151)
	)
	(via
		(at 104.175 148.175)
		(size 0.5)
		(drill 0.2)
		(layers "F.Cu" "B.Cu")
		(net 151)
	)
	(via blind
		(at 103.275021 128.675)
		(size 0.5)
		(drill 0.2)
		(layers "F.Cu" "In2.Cu")
		(net 151)
	)
	(segment
		(start 105.575 145.955)
		(end 105.575 145.66)
		(width 0.1)
		(layer "B.Cu")
		(net 151)
	)
	(segment
		(start 105.2625 146.2675)
		(end 105.575 145.955)
		(width 0.1)
		(layer "B.Cu")
		(net 151)
	)
	(segment
		(start 104.6675 146.2675)
		(end 105.2625 146.2675)
		(width 0.1)
		(layer "B.Cu")
		(net 151)
	)
	(segment
		(start 104.175 148.175)
		(end 104.175 146.76)
		(width 0.1)
		(layer "B.Cu")
		(net 151)
	)
	(segment
		(start 104.175 146.76)
		(end 104.6675 146.2675)
		(width 0.1)
		(layer "B.Cu")
		(net 151)
	)
	(segment
		(start 104.917565 132.681123)
		(end 104.919374 132.697187)
		(width 0.1)
		(layer "In2.Cu")
		(net 151)
	)
	(segment
		(start 104.679951 132.853305)
		(end 104.676253 132.863873)
		(width 0.1)
		(layer "In2.Cu")
		(net 151)
	)
	(segment
		(start 104.713873 132.623746)
		(end 104.725 132.625)
		(width 0.1)
		(layer "In2.Cu")
		(net 151)
	)
	(segment
		(start 104.693825 133.014091)
		(end 104.703305 133.020048)
		(width 0.1)
		(layer "In2.Cu")
		(net 151)
	)
	(segment
		(start 104.693825 132.614091)
		(end 104.703305 132.620048)
		(width 0.1)
		(layer "In2.Cu")
		(net 151)
	)
	(segment
		(start 104.725 132.825)
		(end 104.713873 132.826253)
		(width 0.1)
		(layer "In2.Cu")
		(net 151)
	)
	(segment
		(start 104.676253 132.463873)
		(end 104.675 132.475)
		(width 0.1)
		(layer "In2.Cu")
		(net 151)
	)
	(segment
		(start 104.775 133.075)
		(end 104.775 147.575)
		(width 0.1)
		(layer "In2.Cu")
		(net 151)
	)
	(segment
		(start 104.675 132.075)
		(end 104.775 132.175)
		(width 0.1)
		(layer "In2.Cu")
		(net 151)
	)
	(segment
		(start 104.685908 132.606174)
		(end 104.693825 132.614091)
		(width 0.1)
		(layer "In2.Cu")
		(net 151)
	)
	(segment
		(start 104.775 147.575)
		(end 104.175 148.175)
		(width 0.1)
		(layer "In2.Cu")
		(net 151)
	)
	(segment
		(start 104.847187 132.625)
		(end 104.863251 132.626809)
		(width 0.1)
		(layer "In2.Cu")
		(net 151)
	)
	(segment
		(start 104.675 129.475)
		(end 104.675 132.075)
		(width 0.1)
		(layer "In2.Cu")
		(net 151)
	)
	(segment
		(start 104.903626 132.79782)
		(end 104.892195 132.809251)
		(width 0.1)
		(layer "In2.Cu")
		(net 151)
	)
	(segment
		(start 104.764091 132.406174)
		(end 104.756174 132.414091)
		(width 0.1)
		(layer "In2.Cu")
		(net 151)
	)
	(segment
		(start 104.675 132.875)
		(end 104.675 132.975)
		(width 0.1)
		(layer "In2.Cu")
		(net 151)
	)
	(segment
		(start 104.736126 133.026253)
		(end 104.746694 133.029951)
		(width 0.1)
		(layer "In2.Cu")
		(net 151)
	)
	(segment
		(start 104.679951 132.596694)
		(end 104.685908 132.606174)
		(width 0.1)
		(layer "In2.Cu")
		(net 151)
	)
	(segment
		(start 104.703305 133.020048)
		(end 104.713873 133.023746)
		(width 0.1)
		(layer "In2.Cu")
		(net 151)
	)
	(segment
		(start 104.736126 132.423746)
		(end 104.713873 132.426253)
		(width 0.1)
		(layer "In2.Cu")
		(net 151)
	)
	(segment
		(start 104.773746 133.063873)
		(end 104.775 133.075)
		(width 0.1)
		(layer "In2.Cu")
		(net 151)
	)
	(segment
		(start 104.756174 132.414091)
		(end 104.746694 132.420048)
		(width 0.1)
		(layer "In2.Cu")
		(net 151)
	)
	(segment
		(start 104.919374 132.697187)
		(end 104.919374 132.752813)
		(width 0.1)
		(layer "In2.Cu")
		(net 151)
	)
	(segment
		(start 104.685908 132.443825)
		(end 104.679951 132.453305)
		(width 0.1)
		(layer "In2.Cu")
		(net 151)
	)
	(segment
		(start 104.675 132.975)
		(end 104.676253 132.986126)
		(width 0.1)
		(layer "In2.Cu")
		(net 151)
	)
	(segment
		(start 104.878508 132.817851)
		(end 104.863251 132.82319)
		(width 0.1)
		(layer "In2.Cu")
		(net 151)
	)
	(segment
		(start 104.863251 132.82319)
		(end 104.847187 132.825)
		(width 0.1)
		(layer "In2.Cu")
		(net 151)
	)
	(segment
		(start 104.746694 133.029951)
		(end 104.756174 133.035908)
		(width 0.1)
		(layer "In2.Cu")
		(net 151)
	)
	(segment
		(start 104.675 132.575)
		(end 104.676253 132.586126)
		(width 0.1)
		(layer "In2.Cu")
		(net 151)
	)
	(segment
		(start 104.912226 132.784133)
		(end 104.903626 132.79782)
		(width 0.1)
		(layer "In2.Cu")
		(net 151)
	)
	(segment
		(start 104.713873 133.023746)
		(end 104.736126 133.026253)
		(width 0.1)
		(layer "In2.Cu")
		(net 151)
	)
	(segment
		(start 104.685908 132.843825)
		(end 104.679951 132.853305)
		(width 0.1)
		(layer "In2.Cu")
		(net 151)
	)
	(segment
		(start 104.770048 132.396694)
		(end 104.764091 132.406174)
		(width 0.1)
		(layer "In2.Cu")
		(net 151)
	)
	(segment
		(start 104.878508 132.632148)
		(end 104.892195 132.640748)
		(width 0.1)
		(layer "In2.Cu")
		(net 151)
	)
	(segment
		(start 104.703305 132.829951)
		(end 104.693825 132.835908)
		(width 0.1)
		(layer "In2.Cu")
		(net 151)
	)
	(segment
		(start 104.773746 132.386126)
		(end 104.770048 132.396694)
		(width 0.1)
		(layer "In2.Cu")
		(net 151)
	)
	(segment
		(start 104.770048 133.053305)
		(end 104.773746 133.063873)
		(width 0.1)
		(layer "In2.Cu")
		(net 151)
	)
	(segment
		(start 104.756174 133.035908)
		(end 104.764091 133.043825)
		(width 0.1)
		(layer "In2.Cu")
		(net 151)
	)
	(segment
		(start 103.875 128.675)
		(end 104.675 129.475)
		(width 0.1)
		(layer "In2.Cu")
		(net 151)
	)
	(segment
		(start 104.676253 132.986126)
		(end 104.679951 132.996694)
		(width 0.1)
		(layer "In2.Cu")
		(net 151)
	)
	(segment
		(start 104.892195 132.640748)
		(end 104.903626 132.652179)
		(width 0.1)
		(layer "In2.Cu")
		(net 151)
	)
	(segment
		(start 104.685908 133.006174)
		(end 104.693825 133.014091)
		(width 0.1)
		(layer "In2.Cu")
		(net 151)
	)
	(segment
		(start 104.703305 132.620048)
		(end 104.713873 132.623746)
		(width 0.1)
		(layer "In2.Cu")
		(net 151)
	)
	(segment
		(start 104.713873 132.826253)
		(end 104.703305 132.829951)
		(width 0.1)
		(layer "In2.Cu")
		(net 151)
	)
	(segment
		(start 104.676253 132.586126)
		(end 104.679951 132.596694)
		(width 0.1)
		(layer "In2.Cu")
		(net 151)
	)
	(segment
		(start 104.679951 132.453305)
		(end 104.676253 132.463873)
		(width 0.1)
		(layer "In2.Cu")
		(net 151)
	)
	(segment
		(start 104.764091 133.043825)
		(end 104.770048 133.053305)
		(width 0.1)
		(layer "In2.Cu")
		(net 151)
	)
	(segment
		(start 104.863251 132.626809)
		(end 104.878508 132.632148)
		(width 0.1)
		(layer "In2.Cu")
		(net 151)
	)
	(segment
		(start 104.713873 132.426253)
		(end 104.703305 132.429951)
		(width 0.1)
		(layer "In2.Cu")
		(net 151)
	)
	(segment
		(start 104.703305 132.429951)
		(end 104.693825 132.435908)
		(width 0.1)
		(layer "In2.Cu")
		(net 151)
	)
	(segment
		(start 104.917565 132.768876)
		(end 104.912226 132.784133)
		(width 0.1)
		(layer "In2.Cu")
		(net 151)
	)
	(segment
		(start 104.679951 132.996694)
		(end 104.685908 133.006174)
		(width 0.1)
		(layer "In2.Cu")
		(net 151)
	)
	(segment
		(start 104.693825 132.835908)
		(end 104.685908 132.843825)
		(width 0.1)
		(layer "In2.Cu")
		(net 151)
	)
	(segment
		(start 104.693825 132.435908)
		(end 104.685908 132.443825)
		(width 0.1)
		(layer "In2.Cu")
		(net 151)
	)
	(segment
		(start 104.676253 132.863873)
		(end 104.675 132.875)
		(width 0.1)
		(layer "In2.Cu")
		(net 151)
	)
	(segment
		(start 104.892195 132.809251)
		(end 104.878508 132.817851)
		(width 0.1)
		(layer "In2.Cu")
		(net 151)
	)
	(segment
		(start 104.775 132.375)
		(end 104.773746 132.386126)
		(width 0.1)
		(layer "In2.Cu")
		(net 151)
	)
	(segment
		(start 104.675 132.475)
		(end 104.675 132.575)
		(width 0.1)
		(layer "In2.Cu")
		(net 151)
	)
	(segment
		(start 104.919374 132.752813)
		(end 104.917565 132.768876)
		(width 0.1)
		(layer "In2.Cu")
		(net 151)
	)
	(segment
		(start 104.847187 132.825)
		(end 104.725 132.825)
		(width 0.1)
		(layer "In2.Cu")
		(net 151)
	)
	(segment
		(start 104.746694 132.420048)
		(end 104.736126 132.423746)
		(width 0.1)
		(layer "In2.Cu")
		(net 151)
	)
	(segment
		(start 104.725 132.625)
		(end 104.847187 132.625)
		(width 0.1)
		(layer "In2.Cu")
		(net 151)
	)
	(segment
		(start 104.903626 132.652179)
		(end 104.912226 132.665866)
		(width 0.1)
		(layer "In2.Cu")
		(net 151)
	)
	(segment
		(start 104.912226 132.665866)
		(end 104.917565 132.681123)
		(width 0.1)
		(layer "In2.Cu")
		(net 151)
	)
	(segment
		(start 104.775 132.175)
		(end 104.775 132.375)
		(width 0.1)
		(layer "In2.Cu")
		(net 151)
	)
	(segment
		(start 103.275021 128.675)
		(end 103.875 128.675)
		(width 0.1)
		(layer "In2.Cu")
		(net 151)
	)
	(segment
		(start 100.975 148.775)
		(end 100.975 148.175)
		(width 0.1)
		(layer "F.Cu")
		(net 152)
	)
	(segment
		(start 100.775 127.175)
		(end 100.275 127.675)
		(width 0.15)
		(layer "F.Cu")
		(net 152)
	)
	(via blind
		(at 100.275 127.675)
		(size 0.5)
		(drill 0.2)
		(layers "F.Cu" "In2.Cu")
		(net 152)
	)
	(via
		(at 100.975 148.175)
		(size 0.5)
		(drill 0.2)
		(layers "F.Cu" "B.Cu")
		(net 152)
	)
	(segment
		(start 100.175 149.175)
		(end 100.975 148.375)
		(width 0.1)
		(layer "B.Cu")
		(net 152)
	)
	(segment
		(start 100.975 148.375)
		(end 100.975 148.175)
		(width 0.1)
		(layer "B.Cu")
		(net 152)
	)
	(segment
		(start 101.028656 132.364968)
		(end 101.044178 132.374721)
		(width 0.1)
		(layer "In2.Cu")
		(net 152)
	)
	(segment
		(start 100.929135 132.32604)
		(end 100.942097 132.339002)
		(width 0.1)
		(layer "In2.Cu")
		(net 152)
	)
	(segment
		(start 100.929135 132.187683)
		(end 100.919382 132.203205)
		(width 0.1)
		(layer "In2.Cu")
		(net 152)
	)
	(segment
		(start 100.942097 132.174721)
		(end 100.929135 132.187683)
		(width 0.1)
		(layer "In2.Cu")
		(net 152)
	)
	(segment
		(start 101.011354 132.154809)
		(end 100.974921 132.158914)
		(width 0.1)
		(layer "In2.Cu")
		(net 152)
	)
	(segment
		(start 101.044178 132.374721)
		(end 101.05714 132.387683)
		(width 0.1)
		(layer "In2.Cu")
		(net 152)
	)
	(segment
		(start 100.942097 132.339002)
		(end 100.957619 132.348755)
		(width 0.1)
		(layer "In2.Cu")
		(net 152)
	)
	(segment
		(start 101.044178 132.139002)
		(end 101.028656 132.148755)
		(width 0.1)
		(layer "In2.Cu")
		(net 152)
	)
	(segment
		(start 100.957619 132.164968)
		(end 100.942097 132.174721)
		(width 0.1)
		(layer "In2.Cu")
		(net 152)
	)
	(segment
		(start 100.974921 132.158914)
		(end 100.957619 132.164968)
		(width 0.1)
		(layer "In2.Cu")
		(net 152)
	)
	(segment
		(start 100.913328 132.220507)
		(end 100.911276 132.238724)
		(width 0.1)
		(layer "In2.Cu")
		(net 152)
	)
	(segment
		(start 100.919382 132.203205)
		(end 100.913328 132.220507)
		(width 0.1)
		(layer "In2.Cu")
		(net 152)
	)
	(segment
		(start 100.874999 128.274999)
		(end 100.874999 130.924999)
		(width 0.1)
		(layer "In2.Cu")
		(net 152)
	)
	(segment
		(start 100.974921 132.354809)
		(end 101.011354 132.358914)
		(width 0.1)
		(layer "In2.Cu")
		(net 152)
	)
	(segment
		(start 101.066893 132.403205)
		(end 101.072947 132.420507)
		(width 0.1)
		(layer "In2.Cu")
		(net 152)
	)
	(segment
		(start 100.919382 132.310518)
		(end 100.929135 132.32604)
		(width 0.1)
		(layer "In2.Cu")
		(net 152)
	)
	(segment
		(start 101.066893 132.110518)
		(end 101.05714 132.12604)
		(width 0.1)
		(layer "In2.Cu")
		(net 152)
	)
	(segment
		(start 100.975 147.398223)
		(end 100.975 148.175)
		(width 0.1)
		(layer "In2.Cu")
		(net 152)
	)
	(segment
		(start 100.275 127.675)
		(end 100.874999 128.274999)
		(width 0.1)
		(layer "In2.Cu")
		(net 152)
	)
	(segment
		(start 101.075 131.125)
		(end 101.075 132.075)
		(width 0.1)
		(layer "In2.Cu")
		(net 152)
	)
	(segment
		(start 101.075 138.275)
		(end 100.775011 138.574989)
		(width 0.1)
		(layer "In2.Cu")
		(net 152)
	)
	(segment
		(start 101.028656 132.148755)
		(end 101.011354 132.154809)
		(width 0.1)
		(layer "In2.Cu")
		(net 152)
	)
	(segment
		(start 101.072947 132.420507)
		(end 101.075 132.438724)
		(width 0.1)
		(layer "In2.Cu")
		(net 152)
	)
	(segment
		(start 100.775011 138.574989)
		(end 100.775011 147.198234)
		(width 0.1)
		(layer "In2.Cu")
		(net 152)
	)
	(segment
		(start 100.911276 132.275)
		(end 100.913328 132.293216)
		(width 0.1)
		(layer "In2.Cu")
		(net 152)
	)
	(segment
		(start 101.075 132.075)
		(end 101.072947 132.093216)
		(width 0.1)
		(layer "In2.Cu")
		(net 152)
	)
	(segment
		(start 100.911276 132.238724)
		(end 100.911276 132.275)
		(width 0.1)
		(layer "In2.Cu")
		(net 152)
	)
	(segment
		(start 100.874999 130.924999)
		(end 101.075 131.125)
		(width 0.1)
		(layer "In2.Cu")
		(net 152)
	)
	(segment
		(start 101.075 132.438724)
		(end 101.075 138.275)
		(width 0.1)
		(layer "In2.Cu")
		(net 152)
	)
	(segment
		(start 101.072947 132.093216)
		(end 101.066893 132.110518)
		(width 0.1)
		(layer "In2.Cu")
		(net 152)
	)
	(segment
		(start 101.05714 132.387683)
		(end 101.066893 132.403205)
		(width 0.1)
		(layer "In2.Cu")
		(net 152)
	)
	(segment
		(start 100.775011 147.198234)
		(end 100.975 147.398223)
		(width 0.1)
		(layer "In2.Cu")
		(net 152)
	)
	(segment
		(start 100.913328 132.293216)
		(end 100.919382 132.310518)
		(width 0.1)
		(layer "In2.Cu")
		(net 152)
	)
	(segment
		(start 101.05714 132.12604)
		(end 101.044178 132.139002)
		(width 0.1)
		(layer "In2.Cu")
		(net 152)
	)
	(segment
		(start 101.011354 132.358914)
		(end 101.028656 132.364968)
		(width 0.1)
		(layer "In2.Cu")
		(net 152)
	)
	(segment
		(start 100.957619 132.348755)
		(end 100.974921 132.354809)
		(width 0.1)
		(layer "In2.Cu")
		(net 152)
	)
	(segment
		(start 100.175 148.775)
		(end 100.175 148.175)
		(width 0.1)
		(layer "F.Cu")
		(net 153)
	)
	(segment
		(start 100.775 131.025)
		(end 100.775 130.175)
		(width 0.1)
		(layer "F.Cu")
		(net 153)
	)
	(segment
		(start 100.325 131.475)
		(end 100.775 131.025)
		(width 0.1)
		(layer "F.Cu")
		(net 153)
	)
	(via
		(at 100.175 148.175)
		(size 0.5)
		(drill 0.2)
		(layers "F.Cu" "B.Cu")
		(net 153)
	)
	(via
		(at 100.325 131.475)
		(size 0.5)
		(drill 0.2)
		(layers "F.Cu" "B.Cu")
		(net 153)
	)
	(segment
		(start 99.775 148.575)
		(end 100.175 148.175)
		(width 0.1)
		(layer "B.Cu")
		(net 153)
	)
	(segment
		(start 99.495 148.575)
		(end 99.775 148.575)
		(width 0.1)
		(layer "B.Cu")
		(net 153)
	)
	(segment
		(start 99.175 149.19)
		(end 99.175 148.895)
		(width 0.1)
		(layer "B.Cu")
		(net 153)
	)
	(segment
		(start 99.175 148.895)
		(end 99.495 148.575)
		(width 0.1)
		(layer "B.Cu")
		(net 153)
	)
	(segment
		(start 100.325 147.125)
		(end 100.325 131.475)
		(width 0.1)
		(layer "In5.Cu")
		(net 153)
	)
	(segment
		(start 100.175 147.275)
		(end 100.325 147.125)
		(width 0.1)
		(layer "In5.Cu")
		(net 153)
	)
	(segment
		(start 100.175 148.175)
		(end 100.175 147.275)
		(width 0.1)
		(layer "In5.Cu")
		(net 153)
	)
	(segment
		(start 100.775 126.175)
		(end 100.275 126.675)
		(width 0.15)
		(layer "F.Cu")
		(net 154)
	)
	(segment
		(start 99.775 145.175)
		(end 99.775 142.875)
		(width 0.1)
		(layer "F.Cu")
		(net 154)
	)
	(segment
		(start 100.175 145.575)
		(end 99.775 145.175)
		(width 0.1)
		(layer "F.Cu")
		(net 154)
	)
	(via
		(at 99.775 142.875)
		(size 0.5)
		(drill 0.2)
		(layers "F.Cu" "B.Cu")
		(net 154)
	)
	(via blind
		(at 100.275 126.675)
		(size 0.5)
		(drill 0.2)
		(layers "F.Cu" "In5.Cu")
		(net 154)
	)
	(segment
		(start 99.775 142.875)
		(end 99.775 141.96)
		(width 0.1)
		(layer "B.Cu")
		(net 154)
	)
	(segment
		(start 99.777508 128.552747)
		(end 99.775 128.575)
		(width 0.1)
		(layer "In5.Cu")
		(net 154)
	)
	(segment
		(start 100.275 126.675)
		(end 99.775 127.175)
		(width 0.1)
		(layer "In5.Cu")
		(net 154)
	)
	(segment
		(start 100.449831 128.331611)
		(end 100.457227 128.352747)
		(width 0.1)
		(layer "In5.Cu")
		(net 154)
	)
	(segment
		(start 100.403123 129.084903)
		(end 100.422083 129.096816)
		(width 0.1)
		(layer "In5.Cu")
		(net 154)
	)
	(segment
		(start 100.459734 128.375)
		(end 100.457227 128.397252)
		(width 0.1)
		(layer "In5.Cu")
		(net 154)
	)
	(segment
		(start 99.796817 128.637348)
		(end 99.812652 128.653183)
		(width 0.1)
		(layer "In5.Cu")
		(net 154)
	)
	(segment
		(start 99.777508 129.752747)
		(end 99.775 129.775)
		(width 0.1)
		(layer "In5.Cu")
		(net 154)
	)
	(segment
		(start 99.777508 128.997252)
		(end 99.784904 129.018388)
		(width 0.1)
		(layer "In5.Cu")
		(net 154)
	)
	(segment
		(start 99.852748 129.677507)
		(end 99.831612 129.684903)
		(width 0.1)
		(layer "In5.Cu")
		(net 154)
	)
	(segment
		(start 100.459734 128.775)
		(end 100.457227 128.797252)
		(width 0.1)
		(layer "In5.Cu")
		(net 154)
	)
	(segment
		(start 99.875 129.675)
		(end 99.852748 129.677507)
		(width 0.1)
		(layer "In5.Cu")
		(net 154)
	)
	(segment
		(start 100.437918 128.837348)
		(end 100.422083 128.853183)
		(width 0.1)
		(layer "In5.Cu")
		(net 154)
	)
	(segment
		(start 99.796817 128.512651)
		(end 99.784904 128.531611)
		(width 0.1)
		(layer "In5.Cu")
		(net 154)
	)
	(segment
		(start 99.775 129.375)
		(end 99.777508 129.397252)
		(width 0.1)
		(layer "In5.Cu")
		(net 154)
	)
	(segment
		(start 99.812652 128.253183)
		(end 99.831612 128.265096)
		(width 0.1)
		(layer "In5.Cu")
		(net 154)
	)
	(segment
		(start 99.777508 129.397252)
		(end 99.784904 129.418388)
		(width 0.1)
		(layer "In5.Cu")
		(net 154)
	)
	(segment
		(start 99.796817 129.712651)
		(end 99.784904 129.731611)
		(width 0.1)
		(layer "In5.Cu")
		(net 154)
	)
	(segment
		(start 99.831612 129.284903)
		(end 99.812652 129.296816)
		(width 0.1)
		(layer "In5.Cu")
		(net 154)
	)
	(segment
		(start 99.812652 129.053183)
		(end 99.831612 129.065096)
		(width 0.1)
		(layer "In5.Cu")
		(net 154)
	)
	(segment
		(start 99.875 128.875)
		(end 99.852748 128.877507)
		(width 0.1)
		(layer "In5.Cu")
		(net 154)
	)
	(segment
		(start 100.457227 128.352747)
		(end 100.459734 128.375)
		(width 0.1)
		(layer "In5.Cu")
		(net 154)
	)
	(segment
		(start 100.437918 129.637348)
		(end 100.422083 129.653183)
		(width 0.1)
		(layer "In5.Cu")
		(net 154)
	)
	(segment
		(start 100.422083 128.696816)
		(end 100.437918 128.712651)
		(width 0.1)
		(layer "In5.Cu")
		(net 154)
	)
	(segment
		(start 100.459734 129.175)
		(end 100.457227 129.197252)
		(width 0.1)
		(layer "In5.Cu")
		(net 154)
	)
	(segment
		(start 100.457227 129.197252)
		(end 100.449831 129.218388)
		(width 0.1)
		(layer "In5.Cu")
		(net 154)
	)
	(segment
		(start 100.381987 128.677507)
		(end 100.403123 128.684903)
		(width 0.1)
		(layer "In5.Cu")
		(net 154)
	)
	(segment
		(start 99.875 129.475)
		(end 100.359734 129.475)
		(width 0.1)
		(layer "In5.Cu")
		(net 154)
	)
	(segment
		(start 100.457227 129.552747)
		(end 100.459734 129.575)
		(width 0.1)
		(layer "In5.Cu")
		(net 154)
	)
	(segment
		(start 99.852748 128.477507)
		(end 99.831612 128.484903)
		(width 0.1)
		(layer "In5.Cu")
		(net 154)
	)
	(segment
		(start 99.875 128.675)
		(end 100.359734 128.675)
		(width 0.1)
		(layer "In5.Cu")
		(net 154)
	)
	(segment
		(start 100.449831 129.531611)
		(end 100.457227 129.552747)
		(width 0.1)
		(layer "In5.Cu")
		(net 154)
	)
	(segment
		(start 100.359734 129.275)
		(end 99.875 129.275)
		(width 0.1)
		(layer "In5.Cu")
		(net 154)
	)
	(segment
		(start 100.381987 128.277507)
		(end 100.403123 128.284903)
		(width 0.1)
		(layer "In5.Cu")
		(net 154)
	)
	(segment
		(start 100.437918 129.112651)
		(end 100.449831 129.131611)
		(width 0.1)
		(layer "In5.Cu")
		(net 154)
	)
	(segment
		(start 100.403123 128.865096)
		(end 100.381987 128.872492)
		(width 0.1)
		(layer "In5.Cu")
		(net 154)
	)
	(segment
		(start 99.796817 128.912651)
		(end 99.784904 128.931611)
		(width 0.1)
		(layer "In5.Cu")
		(net 154)
	)
	(segment
		(start 99.831612 129.684903)
		(end 99.812652 129.696816)
		(width 0.1)
		(layer "In5.Cu")
		(net 154)
	)
	(segment
		(start 100.457227 128.752747)
		(end 100.459734 128.775)
		(width 0.1)
		(layer "In5.Cu")
		(net 154)
	)
	(segment
		(start 99.831612 129.065096)
		(end 99.852748 129.072492)
		(width 0.1)
		(layer "In5.Cu")
		(net 154)
	)
	(segment
		(start 100.359734 128.875)
		(end 99.875 128.875)
		(width 0.1)
		(layer "In5.Cu")
		(net 154)
	)
	(segment
		(start 99.831612 128.265096)
		(end 99.852748 128.272492)
		(width 0.1)
		(layer "In5.Cu")
		(net 154)
	)
	(segment
		(start 99.784904 128.618388)
		(end 99.796817 128.637348)
		(width 0.1)
		(layer "In5.Cu")
		(net 154)
	)
	(segment
		(start 99.831612 128.665096)
		(end 99.852748 128.672492)
		(width 0.1)
		(layer "In5.Cu")
		(net 154)
	)
	(segment
		(start 100.449831 129.131611)
		(end 100.457227 129.152747)
		(width 0.1)
		(layer "In5.Cu")
		(net 154)
	)
	(segment
		(start 100.449831 128.731611)
		(end 100.457227 128.752747)
		(width 0.1)
		(layer "In5.Cu")
		(net 154)
	)
	(segment
		(start 99.784904 128.531611)
		(end 99.777508 128.552747)
		(width 0.1)
		(layer "In5.Cu")
		(net 154)
	)
	(segment
		(start 100.381987 129.672492)
		(end 100.359734 129.675)
		(width 0.1)
		(layer "In5.Cu")
		(net 154)
	)
	(segment
		(start 100.422083 128.296816)
		(end 100.437918 128.312651)
		(width 0.1)
		(layer "In5.Cu")
		(net 154)
	)
	(segment
		(start 99.812652 129.696816)
		(end 99.796817 129.712651)
		(width 0.1)
		(layer "In5.Cu")
		(net 154)
	)
	(segment
		(start 99.775 129.775)
		(end 99.775 142.875)
		(width 0.1)
		(layer "In5.Cu")
		(net 154)
	)
	(segment
		(start 100.449831 129.218388)
		(end 100.437918 129.237348)
		(width 0.1)
		(layer "In5.Cu")
		(net 154)
	)
	(segment
		(start 99.784904 128.931611)
		(end 99.777508 128.952747)
		(width 0.1)
		(layer "In5.Cu")
		(net 154)
	)
	(segment
		(start 100.437918 129.512651)
		(end 100.449831 129.531611)
		(width 0.1)
		(layer "In5.Cu")
		(net 154)
	)
	(segment
		(start 100.457227 129.152747)
		(end 100.459734 129.175)
		(width 0.1)
		(layer "In5.Cu")
		(net 154)
	)
	(segment
		(start 100.381987 128.872492)
		(end 100.359734 128.875)
		(width 0.1)
		(layer "In5.Cu")
		(net 154)
	)
	(segment
		(start 100.457227 128.397252)
		(end 100.449831 128.418388)
		(width 0.1)
		(layer "In5.Cu")
		(net 154)
	)
	(segment
		(start 100.359734 128.675)
		(end 100.381987 128.677507)
		(width 0.1)
		(layer "In5.Cu")
		(net 154)
	)
	(segment
		(start 99.784904 129.018388)
		(end 99.796817 129.037348)
		(width 0.1)
		(layer "In5.Cu")
		(net 154)
	)
	(segment
		(start 99.777508 128.952747)
		(end 99.775 128.975)
		(width 0.1)
		(layer "In5.Cu")
		(net 154)
	)
	(segment
		(start 100.403123 129.484903)
		(end 100.422083 129.496816)
		(width 0.1)
		(layer "In5.Cu")
		(net 154)
	)
	(segment
		(start 100.381987 129.477507)
		(end 100.403123 129.484903)
		(width 0.1)
		(layer "In5.Cu")
		(net 154)
	)
	(segment
		(start 100.449831 129.618388)
		(end 100.437918 129.637348)
		(width 0.1)
		(layer "In5.Cu")
		(net 154)
	)
	(segment
		(start 99.796817 128.237348)
		(end 99.812652 128.253183)
		(width 0.1)
		(layer "In5.Cu")
		(net 154)
	)
	(segment
		(start 99.875 128.275)
		(end 100.359734 128.275)
		(width 0.1)
		(layer "In5.Cu")
		(net 154)
	)
	(segment
		(start 100.459734 129.575)
		(end 100.457227 129.597252)
		(width 0.1)
		(layer "In5.Cu")
		(net 154)
	)
	(segment
		(start 99.784904 129.418388)
		(end 99.796817 129.437348)
		(width 0.1)
		(layer "In5.Cu")
		(net 154)
	)
	(segment
		(start 99.775 128.575)
		(end 99.777508 128.597252)
		(width 0.1)
		(layer "In5.Cu")
		(net 154)
	)
	(segment
		(start 100.437918 128.712651)
		(end 100.449831 128.731611)
		(width 0.1)
		(layer "In5.Cu")
		(net 154)
	)
	(segment
		(start 100.449831 128.418388)
		(end 100.437918 128.437348)
		(width 0.1)
		(layer "In5.Cu")
		(net 154)
	)
	(segment
		(start 100.437918 129.237348)
		(end 100.422083 129.253183)
		(width 0.1)
		(layer "In5.Cu")
		(net 154)
	)
	(segment
		(start 99.831612 128.884903)
		(end 99.812652 128.896816)
		(width 0.1)
		(layer "In5.Cu")
		(net 154)
	)
	(segment
		(start 100.403123 129.265096)
		(end 100.381987 129.272492)
		(width 0.1)
		(layer "In5.Cu")
		(net 154)
	)
	(segment
		(start 99.796817 129.437348)
		(end 99.812652 129.453183)
		(width 0.1)
		(layer "In5.Cu")
		(net 154)
	)
	(segment
		(start 100.403123 128.284903)
		(end 100.422083 128.296816)
		(width 0.1)
		(layer "In5.Cu")
		(net 154)
	)
	(segment
		(start 99.852748 129.472492)
		(end 99.875 129.475)
		(width 0.1)
		(layer "In5.Cu")
		(net 154)
	)
	(segment
		(start 100.457227 129.597252)
		(end 100.449831 129.618388)
		(width 0.1)
		(layer "In5.Cu")
		(net 154)
	)
	(segment
		(start 100.403123 128.684903)
		(end 100.422083 128.696816)
		(width 0.1)
		(layer "In5.Cu")
		(net 154)
	)
	(segment
		(start 99.812652 128.653183)
		(end 99.831612 128.665096)
		(width 0.1)
		(layer "In5.Cu")
		(net 154)
	)
	(segment
		(start 99.852748 129.277507)
		(end 99.831612 129.284903)
		(width 0.1)
		(layer "In5.Cu")
		(net 154)
	)
	(segment
		(start 99.812652 129.453183)
		(end 99.831612 129.465096)
		(width 0.1)
		(layer "In5.Cu")
		(net 154)
	)
	(segment
		(start 100.359734 129.675)
		(end 99.875 129.675)
		(width 0.1)
		(layer "In5.Cu")
		(net 154)
	)
	(segment
		(start 99.775 127.175)
		(end 99.775 128.175)
		(width 0.1)
		(layer "In5.Cu")
		(net 154)
	)
	(segment
		(start 99.775 128.975)
		(end 99.777508 128.997252)
		(width 0.1)
		(layer "In5.Cu")
		(net 154)
	)
	(segment
		(start 99.796817 129.312651)
		(end 99.784904 129.331611)
		(width 0.1)
		(layer "In5.Cu")
		(net 154)
	)
	(segment
		(start 99.875 129.275)
		(end 99.852748 129.277507)
		(width 0.1)
		(layer "In5.Cu")
		(net 154)
	)
	(segment
		(start 100.422083 129.253183)
		(end 100.403123 129.265096)
		(width 0.1)
		(layer "In5.Cu")
		(net 154)
	)
	(segment
		(start 99.831612 129.465096)
		(end 99.852748 129.472492)
		(width 0.1)
		(layer "In5.Cu")
		(net 154)
	)
	(segment
		(start 99.875 128.475)
		(end 99.852748 128.477507)
		(width 0.1)
		(layer "In5.Cu")
		(net 154)
	)
	(segment
		(start 99.777508 128.597252)
		(end 99.784904 128.618388)
		(width 0.1)
		(layer "In5.Cu")
		(net 154)
	)
	(segment
		(start 99.775 128.175)
		(end 99.777508 128.197252)
		(width 0.1)
		(layer "In5.Cu")
		(net 154)
	)
	(segment
		(start 99.831612 128.484903)
		(end 99.812652 128.496816)
		(width 0.1)
		(layer "In5.Cu")
		(net 154)
	)
	(segment
		(start 100.403123 129.665096)
		(end 100.381987 129.672492)
		(width 0.1)
		(layer "In5.Cu")
		(net 154)
	)
	(segment
		(start 100.422083 128.853183)
		(end 100.403123 128.865096)
		(width 0.1)
		(layer "In5.Cu")
		(net 154)
	)
	(segment
		(start 99.784904 128.218388)
		(end 99.796817 128.237348)
		(width 0.1)
		(layer "In5.Cu")
		(net 154)
	)
	(segment
		(start 99.796817 129.037348)
		(end 99.812652 129.053183)
		(width 0.1)
		(layer "In5.Cu")
		(net 154)
	)
	(segment
		(start 100.422083 129.096816)
		(end 100.437918 129.112651)
		(width 0.1)
		(layer "In5.Cu")
		(net 154)
	)
	(segment
		(start 99.784904 129.331611)
		(end 99.777508 129.352747)
		(width 0.1)
		(layer "In5.Cu")
		(net 154)
	)
	(segment
		(start 100.457227 128.797252)
		(end 100.449831 128.818388)
		(width 0.1)
		(layer "In5.Cu")
		(net 154)
	)
	(segment
		(start 100.437918 128.437348)
		(end 100.422083 128.453183)
		(width 0.1)
		(layer "In5.Cu")
		(net 154)
	)
	(segment
		(start 100.359734 129.075)
		(end 100.381987 129.077507)
		(width 0.1)
		(layer "In5.Cu")
		(net 154)
	)
	(segment
		(start 99.875 129.075)
		(end 100.359734 129.075)
		(width 0.1)
		(layer "In5.Cu")
		(net 154)
	)
	(segment
		(start 100.422083 129.653183)
		(end 100.403123 129.665096)
		(width 0.1)
		(layer "In5.Cu")
		(net 154)
	)
	(segment
		(start 100.403123 128.465096)
		(end 100.381987 128.472492)
		(width 0.1)
		(layer "In5.Cu")
		(net 154)
	)
	(segment
		(start 99.777508 129.352747)
		(end 99.775 129.375)
		(width 0.1)
		(layer "In5.Cu")
		(net 154)
	)
	(segment
		(start 99.852748 129.072492)
		(end 99.875 129.075)
		(width 0.1)
		(layer "In5.Cu")
		(net 154)
	)
	(segment
		(start 100.359734 129.475)
		(end 100.381987 129.477507)
		(width 0.1)
		(layer "In5.Cu")
		(net 154)
	)
	(segment
		(start 99.852748 128.672492)
		(end 99.875 128.675)
		(width 0.1)
		(layer "In5.Cu")
		(net 154)
	)
	(segment
		(start 100.381987 128.472492)
		(end 100.359734 128.475)
		(width 0.1)
		(layer "In5.Cu")
		(net 154)
	)
	(segment
		(start 99.812652 128.496816)
		(end 99.796817 128.512651)
		(width 0.1)
		(layer "In5.Cu")
		(net 154)
	)
	(segment
		(start 100.381987 129.077507)
		(end 100.403123 129.084903)
		(width 0.1)
		(layer "In5.Cu")
		(net 154)
	)
	(segment
		(start 99.852748 128.272492)
		(end 99.875 128.275)
		(width 0.1)
		(layer "In5.Cu")
		(net 154)
	)
	(segment
		(start 99.852748 128.877507)
		(end 99.831612 128.884903)
		(width 0.1)
		(layer "In5.Cu")
		(net 154)
	)
	(segment
		(start 100.359734 128.275)
		(end 100.381987 128.277507)
		(width 0.1)
		(layer "In5.Cu")
		(net 154)
	)
	(segment
		(start 100.422083 128.453183)
		(end 100.403123 128.465096)
		(width 0.1)
		(layer "In5.Cu")
		(net 154)
	)
	(segment
		(start 99.812652 129.296816)
		(end 99.796817 129.312651)
		(width 0.1)
		(layer "In5.Cu")
		(net 154)
	)
	(segment
		(start 100.449831 128.818388)
		(end 100.437918 128.837348)
		(width 0.1)
		(layer "In5.Cu")
		(net 154)
	)
	(segment
		(start 100.359734 128.475)
		(end 99.875 128.475)
		(width 0.1)
		(layer "In5.Cu")
		(net 154)
	)
	(segment
		(start 99.812652 128.896816)
		(end 99.796817 128.912651)
		(width 0.1)
		(layer "In5.Cu")
		(net 154)
	)
	(segment
		(start 100.422083 129.496816)
		(end 100.437918 129.512651)
		(width 0.1)
		(layer "In5.Cu")
		(net 154)
	)
	(segment
		(start 100.437918 128.312651)
		(end 100.449831 128.331611)
		(width 0.1)
		(layer "In5.Cu")
		(net 154)
	)
	(segment
		(start 99.777508 128.197252)
		(end 99.784904 128.218388)
		(width 0.1)
		(layer "In5.Cu")
		(net 154)
	)
	(segment
		(start 99.784904 129.731611)
		(end 99.777508 129.752747)
		(width 0.1)
		(layer "In5.Cu")
		(net 154)
	)
	(segment
		(start 100.381987 129.272492)
		(end 100.359734 129.275)
		(width 0.1)
		(layer "In5.Cu")
		(net 154)
	)
	(segment
		(start 101.375032 144.375032)
		(end 101.375032 142.255285)
		(width 0.1)
		(layer "F.Cu")
		(net 155)
	)
	(segment
		(start 101.775 144.775)
		(end 101.375032 144.375032)
		(width 0.1)
		(layer "F.Cu")
		(net 155)
	)
	(segment
		(start 99.775 125.175)
		(end 100.275 125.675)
		(width 0.15)
		(layer "F.Cu")
		(net 155)
	)
	(via
		(at 101.375032 142.255285)
		(size 0.5)
		(drill 0.2)
		(layers "F.Cu" "B.Cu")
		(net 155)
	)
	(via blind
		(at 100.275 125.675)
		(size 0.5)
		(drill 0.2)
		(layers "F.Cu" "In5.Cu")
		(net 155)
	)
	(segment
		(start 101.175 141.56)
		(end 101.175 142.055253)
		(width 0.2)
		(layer "B.Cu")
		(net 155)
	)
	(segment
		(start 101.175 142.055253)
		(end 101.375032 142.255285)
		(width 0.2)
		(layer "B.Cu")
		(net 155)
	)
	(segment
		(start 100.013758 127.500011)
		(end 100.016265 127.522263)
		(width 0.1)
		(layer "In5.Cu")
		(net 155)
	)
	(segment
		(start 100.722263 126.997503)
		(end 100.700011 127.000011)
		(width 0.1)
		(layer "In5.Cu")
		(net 155)
	)
	(segment
		(start 100.778194 126.962359)
		(end 100.762359 126.978194)
		(width 0.1)
		(layer "In5.Cu")
		(net 155)
	)
	(segment
		(start 100.986264 128.200011)
		(end 100.900011 128.200011)
		(width 0.1)
		(layer "In5.Cu")
		(net 155)
	)
	(segment
		(start 100.778194 127.637662)
		(end 100.790107 127.656622)
		(width 0.1)
		(layer "In5.Cu")
		(net 155)
	)
	(segment
		(start 100.800011 128.300011)
		(end 100.800011 130.600011)
		(width 0.1)
		(layer "In5.Cu")
		(net 155)
	)
	(segment
		(start 100.986264 127.306885)
		(end 100.98393 127.327607)
		(width 0.1)
		(layer "In5.Cu")
		(net 155)
	)
	(segment
		(start 100.700011 127.600011)
		(end 100.722263 127.602518)
		(width 0.1)
		(layer "In5.Cu")
		(net 155)
	)
	(segment
		(start 100.778194 127.762359)
		(end 100.762359 127.778194)
		(width 0.1)
		(layer "In5.Cu")
		(net 155)
	)
	(segment
		(start 101.083757 128.077758)
		(end 101.086264 128.100011)
		(width 0.1)
		(layer "In5.Cu")
		(net 155)
	)
	(segment
		(start 100.797503 126.922263)
		(end 100.790107 126.943399)
		(width 0.1)
		(layer "In5.Cu")
		(net 155)
	)
	(segment
		(start 100.98393 127.327607)
		(end 100.977042 127.34729)
		(width 0.1)
		(layer "In5.Cu")
		(net 155)
	)
	(segment
		(start 100.797503 127.677758)
		(end 100.800011 127.700011)
		(width 0.1)
		(layer "In5.Cu")
		(net 155)
	)
	(segment
		(start 100.466265 127.122263)
		(end 100.473661 127.143399)
		(width 0.1)
		(layer "In5.Cu")
		(net 155)
	)
	(segment
		(start 100.893138 127.400011)
		(end 100.113758 127.400011)
		(width 0.1)
		(layer "In5.Cu")
		(net 155)
	)
	(segment
		(start 100.485574 127.162359)
		(end 100.501409 127.178194)
		(width 0.1)
		(layer "In5.Cu")
		(net 155)
	)
	(segment
		(start 101.075 141.955253)
		(end 101.375032 142.255285)
		(width 0.1)
		(layer "In5.Cu")
		(net 155)
	)
	(segment
		(start 100.790107 127.743399)
		(end 100.778194 127.762359)
		(width 0.1)
		(layer "In5.Cu")
		(net 155)
	)
	(segment
		(start 100.913861 127.202345)
		(end 100.933544 127.209233)
		(width 0.1)
		(layer "In5.Cu")
		(net 155)
	)
	(segment
		(start 101.076361 128.143399)
		(end 101.064448 128.162359)
		(width 0.1)
		(layer "In5.Cu")
		(net 155)
	)
	(segment
		(start 100.977042 127.34729)
		(end 100.965947 127.364948)
		(width 0.1)
		(layer "In5.Cu")
		(net 155)
	)
	(segment
		(start 100.722263 127.602518)
		(end 100.743399 127.609914)
		(width 0.1)
		(layer "In5.Cu")
		(net 155)
	)
	(segment
		(start 100.035574 127.962359)
		(end 100.051409 127.978194)
		(width 0.1)
		(layer "In5.Cu")
		(net 155)
	)
	(segment
		(start 100.016265 127.477758)
		(end 100.013758 127.500011)
		(width 0.1)
		(layer "In5.Cu")
		(net 155)
	)
	(segment
		(start 100.091505 127.597503)
		(end 100.113758 127.600011)
		(width 0.1)
		(layer "In5.Cu")
		(net 155)
	)
	(segment
		(start 100.743399 126.990107)
		(end 100.722263 126.997503)
		(width 0.1)
		(layer "In5.Cu")
		(net 155)
	)
	(segment
		(start 101.064448 128.162359)
		(end 101.048613 128.178194)
		(width 0.1)
		(layer "In5.Cu")
		(net 155)
	)
	(segment
		(start 100.965947 127.364948)
		(end 100.951202 127.379693)
		(width 0.1)
		(layer "In5.Cu")
		(net 155)
	)
	(segment
		(start 100.986264 128.000011)
		(end 101.008517 128.002518)
		(width 0.1)
		(layer "In5.Cu")
		(net 155)
	)
	(segment
		(start 100.023661 127.943399)
		(end 100.035574 127.962359)
		(width 0.1)
		(layer "In5.Cu")
		(net 155)
	)
	(segment
		(start 100.800011 130.600011)
		(end 101.075 130.875)
		(width 0.1)
		(layer "In5.Cu")
		(net 155)
	)
	(segment
		(start 100.541505 127.002518)
		(end 100.520369 127.009914)
		(width 0.1)
		(layer "In5.Cu")
		(net 155)
	)
	(segment
		(start 100.965947 127.235073)
		(end 100.977042 127.252731)
		(width 0.1)
		(layer "In5.Cu")
		(net 155)
	)
	(segment
		(start 100.856623 128.209914)
		(end 100.837663 128.221827)
		(width 0.1)
		(layer "In5.Cu")
		(net 155)
	)
	(segment
		(start 100.070369 127.990107)
		(end 100.091505 127.997503)
		(width 0.1)
		(layer "In5.Cu")
		(net 155)
	)
	(segment
		(start 100.563758 127.000011)
		(end 100.541505 127.002518)
		(width 0.1)
		(layer "In5.Cu")
		(net 155)
	)
	(segment
		(start 100.977042 127.252731)
		(end 100.98393 127.272414)
		(width 0.1)
		(layer "In5.Cu")
		(net 155)
	)
	(segment
		(start 101.029653 128.009914)
		(end 101.048613 128.021827)
		(width 0.1)
		(layer "In5.Cu")
		(net 155)
	)
	(segment
		(start 100.023661 127.543399)
		(end 100.035574 127.562359)
		(width 0.1)
		(layer "In5.Cu")
		(net 155)
	)
	(segment
		(start 100.113758 127.800011)
		(end 100.091505 127.802518)
		(width 0.1)
		(layer "In5.Cu")
		(net 155)
	)
	(segment
		(start 100.070369 127.590107)
		(end 100.091505 127.597503)
		(width 0.1)
		(layer "In5.Cu")
		(net 155)
	)
	(segment
		(start 100.700011 127.000011)
		(end 100.563758 127.000011)
		(width 0.1)
		(layer "In5.Cu")
		(net 155)
	)
	(segment
		(start 100.466265 127.077758)
		(end 100.463758 127.100011)
		(width 0.1)
		(layer "In5.Cu")
		(net 155)
	)
	(segment
		(start 100.035574 127.437662)
		(end 100.023661 127.456622)
		(width 0.1)
		(layer "In5.Cu")
		(net 155)
	)
	(segment
		(start 100.790107 127.656622)
		(end 100.797503 127.677758)
		(width 0.1)
		(layer "In5.Cu")
		(net 155)
	)
	(segment
		(start 100.473661 127.143399)
		(end 100.485574 127.162359)
		(width 0.1)
		(layer "In5.Cu")
		(net 155)
	)
	(segment
		(start 100.113758 128.000011)
		(end 100.986264 128.000011)
		(width 0.1)
		(layer "In5.Cu")
		(net 155)
	)
	(segment
		(start 100.051409 127.421827)
		(end 100.035574 127.437662)
		(width 0.1)
		(layer "In5.Cu")
		(net 155)
	)
	(segment
		(start 100.541505 127.197503)
		(end 100.563758 127.200011)
		(width 0.1)
		(layer "In5.Cu")
		(net 155)
	)
	(segment
		(start 101.083757 128.122263)
		(end 101.076361 128.143399)
		(width 0.1)
		(layer "In5.Cu")
		(net 155)
	)
	(segment
		(start 100.809915 128.256622)
		(end 100.802519 128.277758)
		(width 0.1)
		(layer "In5.Cu")
		(net 155)
	)
	(segment
		(start 100.951202 127.220328)
		(end 100.965947 127.235073)
		(width 0.1)
		(layer "In5.Cu")
		(net 155)
	)
	(segment
		(start 100.837663 128.221827)
		(end 100.821828 128.237662)
		(width 0.1)
		(layer "In5.Cu")
		(net 155)
	)
	(segment
		(start 101.076361 128.056622)
		(end 101.083757 128.077758)
		(width 0.1)
		(layer "In5.Cu")
		(net 155)
	)
	(segment
		(start 101.008517 128.002518)
		(end 101.029653 128.009914)
		(width 0.1)
		(layer "In5.Cu")
		(net 155)
	)
	(segment
		(start 100.501409 127.178194)
		(end 100.520369 127.190107)
		(width 0.1)
		(layer "In5.Cu")
		(net 155)
	)
	(segment
		(start 100.802519 128.277758)
		(end 100.800011 128.300011)
		(width 0.1)
		(layer "In5.Cu")
		(net 155)
	)
	(segment
		(start 100.091505 127.802518)
		(end 100.070369 127.809914)
		(width 0.1)
		(layer "In5.Cu")
		(net 155)
	)
	(segment
		(start 100.563758 127.200011)
		(end 100.893138 127.200011)
		(width 0.1)
		(layer "In5.Cu")
		(net 155)
	)
	(segment
		(start 100.016265 127.877758)
		(end 100.013758 127.900011)
		(width 0.1)
		(layer "In5.Cu")
		(net 155)
	)
	(segment
		(start 100.700011 127.800011)
		(end 100.113758 127.800011)
		(width 0.1)
		(layer "In5.Cu")
		(net 155)
	)
	(segment
		(start 100.800011 126.900011)
		(end 100.797503 126.922263)
		(width 0.1)
		(layer "In5.Cu")
		(net 155)
	)
	(segment
		(start 100.743399 127.790107)
		(end 100.722263 127.797503)
		(width 0.1)
		(layer "In5.Cu")
		(net 155)
	)
	(segment
		(start 100.893138 127.200011)
		(end 100.913861 127.202345)
		(width 0.1)
		(layer "In5.Cu")
		(net 155)
	)
	(segment
		(start 100.520369 127.009914)
		(end 100.501409 127.021827)
		(width 0.1)
		(layer "In5.Cu")
		(net 155)
	)
	(segment
		(start 100.016265 127.922263)
		(end 100.023661 127.943399)
		(width 0.1)
		(layer "In5.Cu")
		(net 155)
	)
	(segment
		(start 101.048613 128.178194)
		(end 101.029653 128.190107)
		(width 0.1)
		(layer "In5.Cu")
		(net 155)
	)
	(segment
		(start 101.008517 128.197503)
		(end 100.986264 128.200011)
		(width 0.1)
		(layer "In5.Cu")
		(net 155)
	)
	(segment
		(start 100.113758 127.400011)
		(end 100.091505 127.402518)
		(width 0.1)
		(layer "In5.Cu")
		(net 155)
	)
	(segment
		(start 100.023661 127.856622)
		(end 100.016265 127.877758)
		(width 0.1)
		(layer "In5.Cu")
		(net 155)
	)
	(segment
		(start 100.743399 127.609914)
		(end 100.762359 127.621827)
		(width 0.1)
		(layer "In5.Cu")
		(net 155)
	)
	(segment
		(start 100.722263 127.797503)
		(end 100.700011 127.800011)
		(width 0.1)
		(layer "In5.Cu")
		(net 155)
	)
	(segment
		(start 100.070369 127.809914)
		(end 100.051409 127.821827)
		(width 0.1)
		(layer "In5.Cu")
		(net 155)
	)
	(segment
		(start 100.485574 127.037662)
		(end 100.473661 127.056622)
		(width 0.1)
		(layer "In5.Cu")
		(net 155)
	)
	(segment
		(start 100.821828 128.237662)
		(end 100.809915 128.256622)
		(width 0.1)
		(layer "In5.Cu")
		(net 155)
	)
	(segment
		(start 100.933544 127.209233)
		(end 100.951202 127.220328)
		(width 0.1)
		(layer "In5.Cu")
		(net 155)
	)
	(segment
		(start 100.275 125.675)
		(end 100.800011 126.200011)
		(width 0.1)
		(layer "In5.Cu")
		(net 155)
	)
	(segment
		(start 100.797503 127.722263)
		(end 100.790107 127.743399)
		(width 0.1)
		(layer "In5.Cu")
		(net 155)
	)
	(segment
		(start 100.900011 128.200011)
		(end 100.877759 128.202518)
		(width 0.1)
		(layer "In5.Cu")
		(net 155)
	)
	(segment
		(start 101.048613 128.021827)
		(end 101.064448 128.037662)
		(width 0.1)
		(layer "In5.Cu")
		(net 155)
	)
	(segment
		(start 100.463758 127.100011)
		(end 100.466265 127.122263)
		(width 0.1)
		(layer "In5.Cu")
		(net 155)
	)
	(segment
		(start 100.035574 127.837662)
		(end 100.023661 127.856622)
		(width 0.1)
		(layer "In5.Cu")
		(net 155)
	)
	(segment
		(start 100.070369 127.409914)
		(end 100.051409 127.421827)
		(width 0.1)
		(layer "In5.Cu")
		(net 155)
	)
	(segment
		(start 100.091505 127.402518)
		(end 100.070369 127.409914)
		(width 0.1)
		(layer "In5.Cu")
		(net 155)
	)
	(segment
		(start 101.086264 128.100011)
		(end 101.083757 128.122263)
		(width 0.1)
		(layer "In5.Cu")
		(net 155)
	)
	(segment
		(start 100.520369 127.190107)
		(end 100.541505 127.197503)
		(width 0.1)
		(layer "In5.Cu")
		(net 155)
	)
	(segment
		(start 100.913861 127.397676)
		(end 100.893138 127.400011)
		(width 0.1)
		(layer "In5.Cu")
		(net 155)
	)
	(segment
		(start 100.473661 127.056622)
		(end 100.466265 127.077758)
		(width 0.1)
		(layer "In5.Cu")
		(net 155)
	)
	(segment
		(start 100.501409 127.021827)
		(end 100.485574 127.037662)
		(width 0.1)
		(layer "In5.Cu")
		(net 155)
	)
	(segment
		(start 101.064448 128.037662)
		(end 101.076361 128.056622)
		(width 0.1)
		(layer "In5.Cu")
		(net 155)
	)
	(segment
		(start 100.051409 127.578194)
		(end 100.070369 127.590107)
		(width 0.1)
		(layer "In5.Cu")
		(net 155)
	)
	(segment
		(start 100.986264 127.293137)
		(end 100.986264 127.306885)
		(width 0.1)
		(layer "In5.Cu")
		(net 155)
	)
	(segment
		(start 100.951202 127.379693)
		(end 100.933544 127.390788)
		(width 0.1)
		(layer "In5.Cu")
		(net 155)
	)
	(segment
		(start 100.023661 127.456622)
		(end 100.016265 127.477758)
		(width 0.1)
		(layer "In5.Cu")
		(net 155)
	)
	(segment
		(start 100.113758 127.600011)
		(end 100.700011 127.600011)
		(width 0.1)
		(layer "In5.Cu")
		(net 155)
	)
	(segment
		(start 100.051409 127.821827)
		(end 100.035574 127.837662)
		(width 0.1)
		(layer "In5.Cu")
		(net 155)
	)
	(segment
		(start 100.091505 127.997503)
		(end 100.113758 128.000011)
		(width 0.1)
		(layer "In5.Cu")
		(net 155)
	)
	(segment
		(start 100.790107 126.943399)
		(end 100.778194 126.962359)
		(width 0.1)
		(layer "In5.Cu")
		(net 155)
	)
	(segment
		(start 100.013758 127.900011)
		(end 100.016265 127.922263)
		(width 0.1)
		(layer "In5.Cu")
		(net 155)
	)
	(segment
		(start 101.029653 128.190107)
		(end 101.008517 128.197503)
		(width 0.1)
		(layer "In5.Cu")
		(net 155)
	)
	(segment
		(start 100.016265 127.522263)
		(end 100.023661 127.543399)
		(width 0.1)
		(layer "In5.Cu")
		(net 155)
	)
	(segment
		(start 100.800011 126.200011)
		(end 100.800011 126.900011)
		(width 0.1)
		(layer "In5.Cu")
		(net 155)
	)
	(segment
		(start 100.035574 127.562359)
		(end 100.051409 127.578194)
		(width 0.1)
		(layer "In5.Cu")
		(net 155)
	)
	(segment
		(start 100.762359 126.978194)
		(end 100.743399 126.990107)
		(width 0.1)
		(layer "In5.Cu")
		(net 155)
	)
	(segment
		(start 100.800011 127.700011)
		(end 100.797503 127.722263)
		(width 0.1)
		(layer "In5.Cu")
		(net 155)
	)
	(segment
		(start 100.762359 127.621827)
		(end 100.778194 127.637662)
		(width 0.1)
		(layer "In5.Cu")
		(net 155)
	)
	(segment
		(start 100.051409 127.978194)
		(end 100.070369 127.990107)
		(width 0.1)
		(layer "In5.Cu")
		(net 155)
	)
	(segment
		(start 100.877759 128.202518)
		(end 100.856623 128.209914)
		(width 0.1)
		(layer "In5.Cu")
		(net 155)
	)
	(segment
		(start 100.762359 127.778194)
		(end 100.743399 127.790107)
		(width 0.1)
		(layer "In5.Cu")
		(net 155)
	)
	(segment
		(start 101.075 130.875)
		(end 101.075 141.955253)
		(width 0.1)
		(layer "In5.Cu")
		(net 155)
	)
	(segment
		(start 100.98393 127.272414)
		(end 100.986264 127.293137)
		(width 0.1)
		(layer "In5.Cu")
		(net 155)
	)
	(segment
		(start 100.933544 127.390788)
		(end 100.913861 127.397676)
		(width 0.1)
		(layer "In5.Cu")
		(net 155)
	)
	(segment
		(start 102.775 127.175)
		(end 102.275 127.675)
		(width 0.15)
		(layer "F.Cu")
		(net 156)
	)
	(segment
		(start 101.775 145.575)
		(end 101.775 146.174946)
		(width 0.1)
		(layer "F.Cu")
		(net 156)
	)
	(segment
		(start 101.775 146.174946)
		(end 101.775054 146.175)
		(width 0.1)
		(layer "F.Cu")
		(net 156)
	)
	(via blind
		(at 102.275 127.675)
		(size 0.5)
		(drill 0.2)
		(layers "F.Cu" "In2.Cu")
		(net 156)
	)
	(via
		(at 101.775054 146.175)
		(size 0.5)
		(drill 0.2)
		(layers "F.Cu" "B.Cu")
		(net 156)
	)
	(segment
		(start 101.56 145.959946)
		(end 101.775054 146.175)
		(width 0.1)
		(layer "B.Cu")
		(net 156)
	)
	(segment
		(start 101.56 144.775)
		(end 101.56 145.959946)
		(width 0.1)
		(layer "B.Cu")
		(net 156)
	)
	(segment
		(start 102.3892 134.819667)
		(end 102.381971 134.799009)
		(width 0.1)
		(layer "In2.Cu")
		(net 156)
	)
	(segment
		(start 102.455511 134.27745)
		(end 102.49901 134.272549)
		(width 0.1)
		(layer "In2.Cu")
		(net 156)
	)
	(segment
		(start 102.575 145.375054)
		(end 102.575 142.775)
		(width 0.1)
		(layer "In2.Cu")
		(net 156)
	)
	(segment
		(start 102.715147 134.484679)
		(end 102.694489 134.47745)
		(width 0.1)
		(layer "In2.Cu")
		(net 156)
	)
	(segment
		(start 102.768029 135.35325)
		(end 102.7608 135.332592)
		(width 0.1)
		(layer "In2.Cu")
		(net 156)
	)
	(segment
		(start 102.416321 134.853676)
		(end 102.400844 134.838199)
		(width 0.1)
		(layer "In2.Cu")
		(net 156)
	)
	(segment
		(start 102.47726 134.675)
		(end 102.67274 134.675)
		(width 0.1)
		(layer "In2.Cu")
		(net 156)
	)
	(segment
		(start 102.400844 135.238199)
		(end 102.3892 135.219667)
		(width 0.1)
		(layer "In2.Cu")
		(net 156)
	)
	(segment
		(start 102.77048 134.57726)
		(end 102.77048 134.57274)
		(width 0.1)
		(layer "In2.Cu")
		(net 156)
	)
	(segment
		(start 102.400844 134.3118)
		(end 102.416321 134.296323)
		(width 0.1)
		(layer "In2.Cu")
		(net 156)
	)
	(segment
		(start 102.434853 134.46532)
		(end 102.416321 134.453676)
		(width 0.1)
		(layer "In2.Cu")
		(net 156)
	)
	(segment
		(start 102.733679 135.455936)
		(end 102.749156 135.440459)
		(width 0.1)
		(layer "In2.Cu")
		(net 156)
	)
	(segment
		(start 102.37952 134.37274)
		(end 102.381971 134.35099)
		(width 0.1)
		(layer "In2.Cu")
		(net 156)
	)
	(segment
		(start 102.67274 134.675)
		(end 102.694489 134.672549)
		(width 0.1)
		(layer "In2.Cu")
		(net 156)
	)
	(segment
		(start 102.575 135.27726)
		(end 102.575 135.275)
		(width 0.1)
		(layer "In2.Cu")
		(net 156)
	)
	(segment
		(start 102.77048 135.375)
		(end 102.768029 135.35325)
		(width 0.1)
		(layer "In2.Cu")
		(net 156)
	)
	(segment
		(start 102.733679 134.896323)
		(end 102.715147 134.884679)
		(width 0.1)
		(layer "In2.Cu")
		(net 156)
	)
	(segment
		(start 102.715147 134.884679)
		(end 102.694489 134.87745)
		(width 0.1)
		(layer "In2.Cu")
		(net 156)
	)
	(segment
		(start 102.77048 134.97726)
		(end 102.77048 134.97274)
		(width 0.1)
		(layer "In2.Cu")
		(net 156)
	)
	(segment
		(start 102.7608 135.421927)
		(end 102.768029 135.401269)
		(width 0.1)
		(layer "In2.Cu")
		(net 156)
	)
	(segment
		(start 102.694489 135.27971)
		(end 102.67274 135.27726)
		(width 0.1)
		(layer "In2.Cu")
		(net 156)
	)
	(segment
		(start 102.77048 134.97274)
		(end 102.768029 134.95099)
		(width 0.1)
		(layer "In2.Cu")
		(net 156)
	)
	(segment
		(start 102.47726 135.275)
		(end 102.455511 135.272549)
		(width 0.1)
		(layer "In2.Cu")
		(net 156)
	)
	(segment
		(start 102.3892 134.330332)
		(end 102.400844 134.3118)
		(width 0.1)
		(layer "In2.Cu")
		(net 156)
	)
	(segment
		(start 102.584679 135.532592)
		(end 102.596323 135.51406)
		(width 0.1)
		(layer "In2.Cu")
		(net 156)
	)
	(segment
		(start 102.47726 134.475)
		(end 102.455511 134.472549)
		(width 0.1)
		(layer "In2.Cu")
		(net 156)
	)
	(segment
		(start 102.694489 134.87745)
		(end 102.67274 134.875)
		(width 0.1)
		(layer "In2.Cu")
		(net 156)
	)
	(segment
		(start 102.400844 134.7118)
		(end 102.416321 134.696323)
		(width 0.1)
		(layer "In2.Cu")
		(net 156)
	)
	(segment
		(start 102.975011 142.374989)
		(end 102.975011 140.937998)
		(width 0.1)
		(layer "In2.Cu")
		(net 156)
	)
	(segment
		(start 102.694489 134.672549)
		(end 102.715147 134.66532)
		(width 0.1)
		(layer "In2.Cu")
		(net 156)
	)
	(segment
		(start 102.77048 134.57274)
		(end 102.768029 134.55099)
		(width 0.1)
		(layer "In2.Cu")
		(net 156)
	)
	(segment
		(start 102.519668 134.26532)
		(end 102.5382 134.253676)
		(width 0.1)
		(layer "In2.Cu")
		(net 156)
	)
	(segment
		(start 102.49901 134.272549)
		(end 102.519668 134.26532)
		(width 0.1)
		(layer "In2.Cu")
		(net 156)
	)
	(segment
		(start 102.565321 134.219667)
		(end 102.57255 134.199009)
		(width 0.1)
		(layer "In2.Cu")
		(net 156)
	)
	(segment
		(start 102.47726 134.875)
		(end 102.455511 134.872549)
		(width 0.1)
		(layer "In2.Cu")
		(net 156)
	)
	(segment
		(start 102.7608 135.332592)
		(end 102.749156 135.31406)
		(width 0.1)
		(layer "In2.Cu")
		(net 156)
	)
	(segment
		(start 102.3892 134.730332)
		(end 102.400844 134.7118)
		(width 0.1)
		(layer "In2.Cu")
		(net 156)
	)
	(segment
		(start 102.768029 135.401269)
		(end 102.77048 135.37952)
		(width 0.1)
		(layer "In2.Cu")
		(net 156)
	)
	(segment
		(start 102.37952 134.77726)
		(end 102.37952 134.77274)
		(width 0.1)
		(layer "In2.Cu")
		(net 156)
	)
	(segment
		(start 102.416321 135.253676)
		(end 102.400844 135.238199)
		(width 0.1)
		(layer "In2.Cu")
		(net 156)
	)
	(segment
		(start 102.455511 135.07745)
		(end 102.47726 135.075)
		(width 0.1)
		(layer "In2.Cu")
		(net 156)
	)
	(segment
		(start 102.749156 135.440459)
		(end 102.7608 135.421927)
		(width 0.1)
		(layer "In2.Cu")
		(net 156)
	)
	(segment
		(start 102.57745 135.55325)
		(end 102.584679 135.532592)
		(width 0.1)
		(layer "In2.Cu")
		(net 156)
	)
	(segment
		(start 102.749156 135.038199)
		(end 102.7608 135.019667)
		(width 0.1)
		(layer "In2.Cu")
		(net 156)
	)
	(segment
		(start 102.733679 134.653676)
		(end 102.749156 134.638199)
		(width 0.1)
		(layer "In2.Cu")
		(net 156)
	)
	(segment
		(start 102.575 140.537987)
		(end 102.575 135.575)
		(width 0.1)
		(layer "In2.Cu")
		(net 156)
	)
	(segment
		(start 102.455511 134.872549)
		(end 102.434853 134.86532)
		(width 0.1)
		(layer "In2.Cu")
		(net 156)
	)
	(segment
		(start 102.381971 134.35099)
		(end 102.3892 134.330332)
		(width 0.1)
		(layer "In2.Cu")
		(net 156)
	)
	(segment
		(start 102.434853 134.86532)
		(end 102.416321 134.853676)
		(width 0.1)
		(layer "In2.Cu")
		(net 156)
	)
	(segment
		(start 102.575 135.575)
		(end 102.57745 135.55325)
		(width 0.1)
		(layer "In2.Cu")
		(net 156)
	)
	(segment
		(start 102.768029 134.999009)
		(end 102.77048 134.97726)
		(width 0.1)
		(layer "In2.Cu")
		(net 156)
	)
	(segment
		(start 102.733679 134.496323)
		(end 102.715147 134.484679)
		(width 0.1)
		(layer "In2.Cu")
		(net 156)
	)
	(segment
		(start 102.675001 129.382945)
		(end 102.675 128.075)
		(width 0.1)
		(layer "In2.Cu")
		(net 156)
	)
	(segment
		(start 102.768029 134.599009)
		(end 102.77048 134.57726)
		(width 0.1)
		(layer "In2.Cu")
		(net 156)
	)
	(segment
		(start 102.381971 134.399009)
		(end 102.37952 134.37726)
		(width 0.1)
		(layer "In2.Cu")
		(net 156)
	)
	(segment
		(start 102.67274 135.27726)
		(end 102.575 135.27726)
		(width 0.1)
		(layer "In2.Cu")
		(net 156)
	)
	(segment
		(start 102.596323 135.51406)
		(end 102.6118 135.498583)
		(width 0.1)
		(layer "In2.Cu")
		(net 156)
	)
	(segment
		(start 101.775054 146.175)
		(end 102.575 145.375054)
		(width 0.1)
		(layer "In2.Cu")
		(net 156)
	)
	(segment
		(start 102.67274 135.075)
		(end 102.694489 135.072549)
		(width 0.1)
		(layer "In2.Cu")
		(net 156)
	)
	(segment
		(start 102.553677 134.238199)
		(end 102.565321 134.219667)
		(width 0.1)
		(layer "In2.Cu")
		(net 156)
	)
	(segment
		(start 102.7608 134.530332)
		(end 102.749156 134.5118)
		(width 0.1)
		(layer "In2.Cu")
		(net 156)
	)
	(segment
		(start 102.575 142.775)
		(end 102.975011 142.374989)
		(width 0.1)
		(layer "In2.Cu")
		(net 156)
	)
	(segment
		(start 102.733679 135.298583)
		(end 102.715147 135.286939)
		(width 0.1)
		(layer "In2.Cu")
		(net 156)
	)
	(segment
		(start 102.768029 134.55099)
		(end 102.7608 134.530332)
		(width 0.1)
		(layer "In2.Cu")
		(net 156)
	)
	(segment
		(start 102.416321 135.096323)
		(end 102.434853 135.084679)
		(width 0.1)
		(layer "In2.Cu")
		(net 156)
	)
	(segment
		(start 102.715147 135.286939)
		(end 102.694489 135.27971)
		(width 0.1)
		(layer "In2.Cu")
		(net 156)
	)
	(segment
		(start 102.455511 135.272549)
		(end 102.434853 135.26532)
		(width 0.1)
		(layer "In2.Cu")
		(net 156)
	)
	(segment
		(start 102.975011 140.937998)
		(end 102.575 140.537987)
		(width 0.1)
		(layer "In2.Cu")
		(net 156)
	)
	(segment
		(start 102.775055 129.482999)
		(end 102.675001 129.382945)
		(width 0.1)
		(layer "In2.Cu")
		(net 156)
	)
	(segment
		(start 102.381971 134.799009)
		(end 102.37952 134.77726)
		(width 0.1)
		(layer "In2.Cu")
		(net 156)
	)
	(segment
		(start 102.749156 135.31406)
		(end 102.733679 135.298583)
		(width 0.1)
		(layer "In2.Cu")
		(net 156)
	)
	(segment
		(start 102.416321 134.696323)
		(end 102.434853 134.684679)
		(width 0.1)
		(layer "In2.Cu")
		(net 156)
	)
	(segment
		(start 102.434853 134.684679)
		(end 102.455511 134.67745)
		(width 0.1)
		(layer "In2.Cu")
		(net 156)
	)
	(segment
		(start 102.65099 135.47971)
		(end 102.694489 135.474809)
		(width 0.1)
		(layer "In2.Cu")
		(net 156)
	)
	(segment
		(start 102.400844 135.1118)
		(end 102.416321 135.096323)
		(width 0.1)
		(layer "In2.Cu")
		(net 156)
	)
	(segment
		(start 102.5382 134.253676)
		(end 102.553677 134.238199)
		(width 0.1)
		(layer "In2.Cu")
		(net 156)
	)
	(segment
		(start 102.77048 135.37952)
		(end 102.77048 135.375)
		(width 0.1)
		(layer "In2.Cu")
		(net 156)
	)
	(segment
		(start 102.6118 135.498583)
		(end 102.630332 135.486939)
		(width 0.1)
		(layer "In2.Cu")
		(net 156)
	)
	(segment
		(start 102.715147 135.06532)
		(end 102.733679 135.053676)
		(width 0.1)
		(layer "In2.Cu")
		(net 156)
	)
	(segment
		(start 102.768029 134.95099)
		(end 102.7608 134.930332)
		(width 0.1)
		(layer "In2.Cu")
		(net 156)
	)
	(segment
		(start 102.575 130.875)
		(end 102.775055 130.674945)
		(width 0.1)
		(layer "In2.Cu")
		(net 156)
	)
	(segment
		(start 102.37952 134.37726)
		(end 102.37952 134.37274)
		(width 0.1)
		(layer "In2.Cu")
		(net 156)
	)
	(segment
		(start 102.434853 134.284679)
		(end 102.455511 134.27745)
		(width 0.1)
		(layer "In2.Cu")
		(net 156)
	)
	(segment
		(start 102.694489 135.072549)
		(end 102.715147 135.06532)
		(width 0.1)
		(layer "In2.Cu")
		(net 156)
	)
	(segment
		(start 102.416321 134.296323)
		(end 102.434853 134.284679)
		(width 0.1)
		(layer "In2.Cu")
		(net 156)
	)
	(segment
		(start 102.37952 135.17726)
		(end 102.37952 135.17274)
		(width 0.1)
		(layer "In2.Cu")
		(net 156)
	)
	(segment
		(start 102.775055 130.674945)
		(end 102.775055 129.482999)
		(width 0.1)
		(layer "In2.Cu")
		(net 156)
	)
	(segment
		(start 102.37952 135.17274)
		(end 102.381971 135.15099)
		(width 0.1)
		(layer "In2.Cu")
		(net 156)
	)
	(segment
		(start 102.67274 134.475)
		(end 102.47726 134.475)
		(width 0.1)
		(layer "In2.Cu")
		(net 156)
	)
	(segment
		(start 102.749156 134.5118)
		(end 102.733679 134.496323)
		(width 0.1)
		(layer "In2.Cu")
		(net 156)
	)
	(segment
		(start 102.749156 134.638199)
		(end 102.7608 134.619667)
		(width 0.1)
		(layer "In2.Cu")
		(net 156)
	)
	(segment
		(start 102.400844 134.838199)
		(end 102.3892 134.819667)
		(width 0.1)
		(layer "In2.Cu")
		(net 156)
	)
	(segment
		(start 102.575 134.17726)
		(end 102.575 130.875)
		(width 0.1)
		(layer "In2.Cu")
		(net 156)
	)
	(segment
		(start 102.434853 135.26532)
		(end 102.416321 135.253676)
		(width 0.1)
		(layer "In2.Cu")
		(net 156)
	)
	(segment
		(start 102.381971 135.199009)
		(end 102.37952 135.17726)
		(width 0.1)
		(layer "In2.Cu")
		(net 156)
	)
	(segment
		(start 102.7608 134.930332)
		(end 102.749156 134.9118)
		(width 0.1)
		(layer "In2.Cu")
		(net 156)
	)
	(segment
		(start 102.3892 135.130332)
		(end 102.400844 135.1118)
		(width 0.1)
		(layer "In2.Cu")
		(net 156)
	)
	(segment
		(start 102.694489 134.47745)
		(end 102.67274 134.475)
		(width 0.1)
		(layer "In2.Cu")
		(net 156)
	)
	(segment
		(start 102.749156 134.9118)
		(end 102.733679 134.896323)
		(width 0.1)
		(layer "In2.Cu")
		(net 156)
	)
	(segment
		(start 102.715147 135.46758)
		(end 102.733679 135.455936)
		(width 0.1)
		(layer "In2.Cu")
		(net 156)
	)
	(segment
		(start 102.416321 134.453676)
		(end 102.400844 134.438199)
		(width 0.1)
		(layer "In2.Cu")
		(net 156)
	)
	(segment
		(start 102.675 128.075)
		(end 102.275 127.675)
		(width 0.1)
		(layer "In2.Cu")
		(net 156)
	)
	(segment
		(start 102.381971 134.75099)
		(end 102.3892 134.730332)
		(width 0.1)
		(layer "In2.Cu")
		(net 156)
	)
	(segment
		(start 102.67274 134.875)
		(end 102.47726 134.875)
		(width 0.1)
		(layer "In2.Cu")
		(net 156)
	)
	(segment
		(start 102.434853 135.084679)
		(end 102.455511 135.07745)
		(width 0.1)
		(layer "In2.Cu")
		(net 156)
	)
	(segment
		(start 102.455511 134.67745)
		(end 102.47726 134.675)
		(width 0.1)
		(layer "In2.Cu")
		(net 156)
	)
	(segment
		(start 102.3892 134.419667)
		(end 102.381971 134.399009)
		(width 0.1)
		(layer "In2.Cu")
		(net 156)
	)
	(segment
		(start 102.733679 135.053676)
		(end 102.749156 135.038199)
		(width 0.1)
		(layer "In2.Cu")
		(net 156)
	)
	(segment
		(start 102.7608 135.019667)
		(end 102.768029 134.999009)
		(width 0.1)
		(layer "In2.Cu")
		(net 156)
	)
	(segment
		(start 102.47726 135.075)
		(end 102.67274 135.075)
		(width 0.1)
		(layer "In2.Cu")
		(net 156)
	)
	(segment
		(start 102.694489 135.474809)
		(end 102.715147 135.46758)
		(width 0.1)
		(layer "In2.Cu")
		(net 156)
	)
	(segment
		(start 102.7608 134.619667)
		(end 102.768029 134.599009)
		(width 0.1)
		(layer "In2.Cu")
		(net 156)
	)
	(segment
		(start 102.575 135.275)
		(end 102.47726 135.275)
		(width 0.1)
		(layer "In2.Cu")
		(net 156)
	)
	(segment
		(start 102.630332 135.486939)
		(end 102.65099 135.47971)
		(width 0.1)
		(layer "In2.Cu")
		(net 156)
	)
	(segment
		(start 102.3892 135.219667)
		(end 102.381971 135.199009)
		(width 0.1)
		(layer "In2.Cu")
		(net 156)
	)
	(segment
		(start 102.57255 134.199009)
		(end 102.575 134.17726)
		(width 0.1)
		(layer "In2.Cu")
		(net 156)
	)
	(segment
		(start 102.400844 134.438199)
		(end 102.3892 134.419667)
		(width 0.1)
		(layer "In2.Cu")
		(net 156)
	)
	(segment
		(start 102.381971 135.15099)
		(end 102.3892 135.130332)
		(width 0.1)
		(layer "In2.Cu")
		(net 156)
	)
	(segment
		(start 102.455511 134.472549)
		(end 102.434853 134.46532)
		(width 0.1)
		(layer "In2.Cu")
		(net 156)
	)
	(segment
		(start 102.715147 134.66532)
		(end 102.733679 134.653676)
		(width 0.1)
		(layer "In2.Cu")
		(net 156)
	)
	(segment
		(start 102.37952 134.77274)
		(end 102.381971 134.75099)
		(width 0.1)
		(layer "In2.Cu")
		(net 156)
	)
	(segment
		(start 101.775 126.175)
		(end 101.275 126.675)
		(width 0.15)
		(layer "F.Cu")
		(net 157)
	)
	(segment
		(start 102.575 145.575)
		(end 102.575 146.175)
		(width 0.1)
		(layer "F.Cu")
		(net 157)
	)
	(via blind
		(at 101.275 126.675)
		(size 0.5)
		(drill 0.2)
		(layers "F.Cu" "In5.Cu")
		(net 157)
	)
	(via
		(at 102.575 146.175)
		(size 0.5)
		(drill 0.2)
		(layers "F.Cu" "B.Cu")
		(net 157)
	)
	(segment
		(start 102.575 145.16)
		(end 102.575 146.175)
		(width 0.15)
		(layer "B.Cu")
		(net 157)
	)
	(segment
		(start 101.70293 127.830231)
		(end 101.693395 127.836222)
		(width 0.1)
		(layer "In5.Cu")
		(net 157)
	)
	(segment
		(start 101.775033 128.274967)
		(end 101.771898 128.302782)
		(width 0.1)
		(layer "In5.Cu")
		(net 157)
	)
	(segment
		(start 101.771898 128.302782)
		(end 101.762654 128.329202)
		(width 0.1)
		(layer "In5.Cu")
		(net 157)
	)
	(segment
		(start 101.136841 128.579202)
		(end 101.151734 128.602903)
		(width 0.1)
		(layer "In5.Cu")
		(net 157)
	)
	(segment
		(start 101.677848 128.653101)
		(end 101.704268 128.662345)
		(width 0.1)
		(layer "In5.Cu")
		(net 157)
	)
	(segment
		(start 101.735937 127.823991)
		(end 101.713558 127.826512)
		(width 0.1)
		(layer "In5.Cu")
		(net 157)
	)
	(segment
		(start 101.775033 142.447286)
		(end 101.725033 142.497286)
		(width 0.1)
		(layer "In5.Cu")
		(net 157)
	)
	(segment
		(start 101.704268 128.387588)
		(end 101.677848 128.396832)
		(width 0.1)
		(layer "In5.Cu")
		(net 157)
	)
	(segment
		(start 101.735937 128.076512)
		(end 101.746565 128.080231)
		(width 0.1)
		(layer "In5.Cu")
		(net 157)
	)
	(segment
		(start 101.674463 127.875537)
		(end 101.674463 128.024967)
		(width 0.1)
		(layer "In5.Cu")
		(net 157)
	)
	(segment
		(start 101.775033 127.774967)
		(end 101.773772 127.786156)
		(width 0.1)
		(layer "In5.Cu")
		(net 157)
	)
	(segment
		(start 101.674463 128.024967)
		(end 101.675723 128.036156)
		(width 0.1)
		(layer "In5.Cu")
		(net 157)
	)
	(segment
		(start 101.675723 127.864347)
		(end 101.674463 127.875537)
		(width 0.1)
		(layer "In5.Cu")
		(net 157)
	)
	(segment
		(start 101.171526 128.622695)
		(end 101.195227 128.637588)
		(width 0.1)
		(layer "In5.Cu")
		(net 157)
	)
	(segment
		(start 101.727969 128.372695)
		(end 101.704268 128.387588)
		(width 0.1)
		(layer "In5.Cu")
		(net 157)
	)
	(segment
		(start 101.650033 128.649967)
		(end 101.677848 128.653101)
		(width 0.1)
		(layer "In5.Cu")
		(net 157)
	)
	(segment
		(start 101.70293 128.070272)
		(end 101.713558 128.073991)
		(width 0.1)
		(layer "In5.Cu")
		(net 157)
	)
	(segment
		(start 101.679442 128.046784)
		(end 101.685433 128.056319)
		(width 0.1)
		(layer "In5.Cu")
		(net 157)
	)
	(segment
		(start 101.127597 128.552782)
		(end 101.136841 128.579202)
		(width 0.1)
		(layer "In5.Cu")
		(net 157)
	)
	(segment
		(start 101.7561 127.814281)
		(end 101.746565 127.820272)
		(width 0.1)
		(layer "In5.Cu")
		(net 157)
	)
	(segment
		(start 101.775033 128.774967)
		(end 101.775033 142.447286)
		(width 0.1)
		(layer "In5.Cu")
		(net 157)
	)
	(segment
		(start 101.773772 128.114347)
		(end 101.775033 128.125537)
		(width 0.1)
		(layer "In5.Cu")
		(net 157)
	)
	(segment
		(start 101.746565 127.820272)
		(end 101.735937 127.823991)
		(width 0.1)
		(layer "In5.Cu")
		(net 157)
	)
	(segment
		(start 101.650033 128.399967)
		(end 101.249463 128.399967)
		(width 0.1)
		(layer "In5.Cu")
		(net 157)
	)
	(segment
		(start 101.171526 128.427238)
		(end 101.151734 128.44703)
		(width 0.1)
		(layer "In5.Cu")
		(net 157)
	)
	(segment
		(start 101.775033 128.125537)
		(end 101.775033 128.274967)
		(width 0.1)
		(layer "In5.Cu")
		(net 157)
	)
	(segment
		(start 101.713558 127.826512)
		(end 101.70293 127.830231)
		(width 0.1)
		(layer "In5.Cu")
		(net 157)
	)
	(segment
		(start 101.675723 128.036156)
		(end 101.679442 128.046784)
		(width 0.1)
		(layer "In5.Cu")
		(net 157)
	)
	(segment
		(start 101.221647 128.646832)
		(end 101.249463 128.649967)
		(width 0.1)
		(layer "In5.Cu")
		(net 157)
	)
	(segment
		(start 101.747761 128.352903)
		(end 101.727969 128.372695)
		(width 0.1)
		(layer "In5.Cu")
		(net 157)
	)
	(segment
		(start 101.151734 128.44703)
		(end 101.136841 128.470731)
		(width 0.1)
		(layer "In5.Cu")
		(net 157)
	)
	(segment
		(start 101.195227 128.412345)
		(end 101.171526 128.427238)
		(width 0.1)
		(layer "In5.Cu")
		(net 157)
	)
	(segment
		(start 101.773772 127.786156)
		(end 101.770053 127.796784)
		(width 0.1)
		(layer "In5.Cu")
		(net 157)
	)
	(segment
		(start 101.151734 128.602903)
		(end 101.171526 128.622695)
		(width 0.1)
		(layer "In5.Cu")
		(net 157)
	)
	(segment
		(start 101.685433 128.056319)
		(end 101.693395 128.064281)
		(width 0.1)
		(layer "In5.Cu")
		(net 157)
	)
	(segment
		(start 101.221647 128.403101)
		(end 101.195227 128.412345)
		(width 0.1)
		(layer "In5.Cu")
		(net 157)
	)
	(segment
		(start 101.770053 128.103719)
		(end 101.773772 128.114347)
		(width 0.1)
		(layer "In5.Cu")
		(net 157)
	)
	(segment
		(start 101.679442 127.853719)
		(end 101.675723 127.864347)
		(width 0.1)
		(layer "In5.Cu")
		(net 157)
	)
	(segment
		(start 101.195227 128.637588)
		(end 101.221647 128.646832)
		(width 0.1)
		(layer "In5.Cu")
		(net 157)
	)
	(segment
		(start 101.762654 128.329202)
		(end 101.747761 128.352903)
		(width 0.1)
		(layer "In5.Cu")
		(net 157)
	)
	(segment
		(start 101.725033 142.497286)
		(end 101.725033 145.325033)
		(width 0.1)
		(layer "In5.Cu")
		(net 157)
	)
	(segment
		(start 101.747761 128.69703)
		(end 101.762654 128.720731)
		(width 0.1)
		(layer "In5.Cu")
		(net 157)
	)
	(segment
		(start 101.704268 128.662345)
		(end 101.727969 128.677238)
		(width 0.1)
		(layer "In5.Cu")
		(net 157)
	)
	(segment
		(start 101.764062 127.806319)
		(end 101.7561 127.814281)
		(width 0.1)
		(layer "In5.Cu")
		(net 157)
	)
	(segment
		(start 101.771898 128.747151)
		(end 101.775033 128.774967)
		(width 0.1)
		(layer "In5.Cu")
		(net 157)
	)
	(segment
		(start 101.775033 127.175033)
		(end 101.775033 127.774967)
		(width 0.1)
		(layer "In5.Cu")
		(net 157)
	)
	(segment
		(start 101.764062 128.094184)
		(end 101.770053 128.103719)
		(width 0.1)
		(layer "In5.Cu")
		(net 157)
	)
	(segment
		(start 101.713558 128.073991)
		(end 101.735937 128.076512)
		(width 0.1)
		(layer "In5.Cu")
		(net 157)
	)
	(segment
		(start 101.677848 128.396832)
		(end 101.650033 128.399967)
		(width 0.1)
		(layer "In5.Cu")
		(net 157)
	)
	(segment
		(start 101.693395 127.836222)
		(end 101.685433 127.844184)
		(width 0.1)
		(layer "In5.Cu")
		(net 157)
	)
	(segment
		(start 101.762654 128.720731)
		(end 101.771898 128.747151)
		(width 0.1)
		(layer "In5.Cu")
		(net 157)
	)
	(segment
		(start 101.249463 128.649967)
		(end 101.650033 128.649967)
		(width 0.1)
		(layer "In5.Cu")
		(net 157)
	)
	(segment
		(start 101.127597 128.497151)
		(end 101.124463 128.524967)
		(width 0.1)
		(layer "In5.Cu")
		(net 157)
	)
	(segment
		(start 101.249463 128.399967)
		(end 101.221647 128.403101)
		(width 0.1)
		(layer "In5.Cu")
		(net 157)
	)
	(segment
		(start 101.725033 145.325033)
		(end 102.575 146.175)
		(width 0.1)
		(layer "In5.Cu")
		(net 157)
	)
	(segment
		(start 101.693395 128.064281)
		(end 101.70293 128.070272)
		(width 0.1)
		(layer "In5.Cu")
		(net 157)
	)
	(segment
		(start 101.746565 128.080231)
		(end 101.7561 128.086222)
		(width 0.1)
		(layer "In5.Cu")
		(net 157)
	)
	(segment
		(start 101.7561 128.086222)
		(end 101.764062 128.094184)
		(width 0.1)
		(layer "In5.Cu")
		(net 157)
	)
	(segment
		(start 101.727969 128.677238)
		(end 101.747761 128.69703)
		(width 0.1)
		(layer "In5.Cu")
		(net 157)
	)
	(segment
		(start 101.770053 127.796784)
		(end 101.764062 127.806319)
		(width 0.1)
		(layer "In5.Cu")
		(net 157)
	)
	(segment
		(start 101.275 126.675)
		(end 101.775033 127.175033)
		(width 0.1)
		(layer "In5.Cu")
		(net 157)
	)
	(segment
		(start 101.685433 127.844184)
		(end 101.679442 127.853719)
		(width 0.1)
		(layer "In5.Cu")
		(net 157)
	)
	(segment
		(start 101.124463 128.524967)
		(end 101.127597 128.552782)
		(width 0.1)
		(layer "In5.Cu")
		(net 157)
	)
	(segment
		(start 101.136841 128.470731)
		(end 101.127597 128.497151)
		(width 0.1)
		(layer "In5.Cu")
		(net 157)
	)
	(segment
		(start 101.775 129.175)
		(end 101.275 128.675)
		(width 0.15)
		(layer "F.Cu")
		(net 158)
	)
	(segment
		(start 101.775 148.775)
		(end 101.775 148.175)
		(width 0.1)
		(layer "F.Cu")
		(net 158)
	)
	(via blind
		(at 101.275 128.675)
		(size 0.5)
		(drill 0.2)
		(layers "F.Cu" "In2.Cu")
		(net 158)
	)
	(via
		(at 101.775 148.175)
		(size 0.5)
		(drill 0.2)
		(layers "F.Cu" "B.Cu")
		(net 158)
	)
	(segment
		(start 101.375 148.675)
		(end 101.375 149.19)
		(width 0.1)
		(layer "B.Cu")
		(net 158)
	)
	(segment
		(start 101.775 148.275)
		(end 101.375 148.675)
		(width 0.1)
		(layer "B.Cu")
		(net 158)
	)
	(segment
		(start 101.775 148.175)
		(end 101.775 148.275)
		(width 0.1)
		(layer "B.Cu")
		(net 158)
	)
	(segment
		(start 101.879636 132.182257)
		(end 101.893468 132.190948)
		(width 0.1)
		(layer "In2.Cu")
		(net 158)
	)
	(segment
		(start 101.753663 131.936103)
		(end 101.738153 131.951613)
		(width 0.1)
		(layer "In2.Cu")
		(net 158)
	)
	(segment
		(start 101.775033 131.875033)
		(end 101.772577 131.896828)
		(width 0.1)
		(layer "In2.Cu")
		(net 158)
	)
	(segment
		(start 101.8025 132.790948)
		(end 101.790949 132.802499)
		(width 0.1)
		(layer "In2.Cu")
		(net 158)
	)
	(segment
		(start 101.905019 132.747566)
		(end 101.893468 132.759117)
		(width 0.1)
		(layer "In2.Cu")
		(net 158)
	)
	(segment
		(start 101.616011 132.396402)
		(end 101.600501 132.411912)
		(width 0.1)
		(layer "In2.Cu")
		(net 158)
	)
	(segment
		(start 101.847984 132.375033)
		(end 101.677082 132.375033)
		(width 0.1)
		(layer "In2.Cu")
		(net 158)
	)
	(segment
		(start 101.765332 131.917531)
		(end 101.753663 131.936103)
		(width 0.1)
		(layer "In2.Cu")
		(net 158)
	)
	(segment
		(start 101.879636 132.767808)
		(end 101.864217 132.773203)
		(width 0.1)
		(layer "In2.Cu")
		(net 158)
	)
	(segment
		(start 101.905019 132.602499)
		(end 101.91371 132.616331)
		(width 0.1)
		(layer "In2.Cu")
		(net 158)
	)
	(segment
		(start 101.698878 131.970527)
		(end 101.655286 131.975438)
		(width 0.1)
		(layer "In2.Cu")
		(net 158)
	)
	(segment
		(start 101.616011 131.994352)
		(end 101.600501 132.009862)
		(width 0.1)
		(layer "In2.Cu")
		(net 158)
	)
	(segment
		(start 101.864217 132.773203)
		(end 101.831751 132.776862)
		(width 0.1)
		(layer "In2.Cu")
		(net 158)
	)
	(segment
		(start 101.634583 132.163282)
		(end 101.655286 132.170527)
		(width 0.1)
		(layer "In2.Cu")
		(net 158)
	)
	(segment
		(start 101.776863 132.83175)
		(end 101.775033 132.847983)
		(width 0.1)
		(layer "In2.Cu")
		(net 158)
	)
	(segment
		(start 101.655286 132.572577)
		(end 101.677082 132.575033)
		(width 0.1)
		(layer "In2.Cu")
		(net 158)
	)
	(segment
		(start 101.738153 131.951613)
		(end 101.719581 131.963282)
		(width 0.1)
		(layer "In2.Cu")
		(net 158)
	)
	(segment
		(start 101.616011 132.151613)
		(end 101.634583 132.163282)
		(width 0.1)
		(layer "In2.Cu")
		(net 158)
	)
	(segment
		(start 101.772577 131.896828)
		(end 101.765332 131.917531)
		(width 0.1)
		(layer "In2.Cu")
		(net 158)
	)
	(segment
		(start 101.579132 132.075033)
		(end 101.581587 132.096828)
		(width 0.1)
		(layer "In2.Cu")
		(net 158)
	)
	(segment
		(start 101.919105 132.63175)
		(end 101.920934 132.647983)
		(width 0.1)
		(layer "In2.Cu")
		(net 158)
	)
	(segment
		(start 101.579132 132.477083)
		(end 101.581587 132.498878)
		(width 0.1)
		(layer "In2.Cu")
		(net 158)
	)
	(segment
		(start 101.790949 132.802499)
		(end 101.782258 132.816331)
		(width 0.1)
		(layer "In2.Cu")
		(net 158)
	)
	(segment
		(start 101.775033 132.175033)
		(end 101.847984 132.175033)
		(width 0.1)
		(layer "In2.Cu")
		(net 158)
	)
	(segment
		(start 101.655286 132.170527)
		(end 101.677083 132.172983)
		(width 0.1)
		(layer "In2.Cu")
		(net 158)
	)
	(segment
		(start 101.677082 132.575033)
		(end 101.847984 132.575033)
		(width 0.1)
		(layer "In2.Cu")
		(net 158)
	)
	(segment
		(start 101.655286 131.975438)
		(end 101.634583 131.982683)
		(width 0.1)
		(layer "In2.Cu")
		(net 158)
	)
	(segment
		(start 101.634583 132.565332)
		(end 101.655286 132.572577)
		(width 0.1)
		(layer "In2.Cu")
		(net 158)
	)
	(segment
		(start 101.579132 132.070933)
		(end 101.579132 132.075033)
		(width 0.1)
		(layer "In2.Cu")
		(net 158)
	)
	(segment
		(start 101.581587 132.451187)
		(end 101.579132 132.472983)
		(width 0.1)
		(layer "In2.Cu")
		(net 158)
	)
	(segment
		(start 101.775033 132.847983)
		(end 101.775033 142.447286)
		(width 0.1)
		(layer "In2.Cu")
		(net 158)
	)
	(segment
		(start 101.600501 132.411912)
		(end 101.588832 132.430484)
		(width 0.1)
		(layer "In2.Cu")
		(net 158)
	)
	(segment
		(start 101.775033 142.447286)
		(end 101.175033 143.047286)
		(width 0.1)
		(layer "In2.Cu")
		(net 158)
	)
	(segment
		(start 101.816332 132.782257)
		(end 101.8025 132.790948)
		(width 0.1)
		(layer "In2.Cu")
		(net 158)
	)
	(segment
		(start 101.677082 132.375033)
		(end 101.655286 132.377488)
		(width 0.1)
		(layer "In2.Cu")
		(net 158)
	)
	(segment
		(start 101.920934 132.702083)
		(end 101.919105 132.718315)
		(width 0.1)
		(layer "In2.Cu")
		(net 158)
	)
	(segment
		(start 101.600501 132.538153)
		(end 101.616011 132.553663)
		(width 0.1)
		(layer "In2.Cu")
		(net 158)
	)
	(segment
		(start 101.655286 132.377488)
		(end 101.634583 132.384733)
		(width 0.1)
		(layer "In2.Cu")
		(net 158)
	)
	(segment
		(start 101.919105 132.718315)
		(end 101.91371 132.733734)
		(width 0.1)
		(layer "In2.Cu")
		(net 158)
	)
	(segment
		(start 101.919105 132.23175)
		(end 101.920934 132.247983)
		(width 0.1)
		(layer "In2.Cu")
		(net 158)
	)
	(segment
		(start 101.677083 132.172983)
		(end 101.775033 132.172983)
		(width 0.1)
		(layer "In2.Cu")
		(net 158)
	)
	(segment
		(start 101.775033 129.175033)
		(end 101.775033 131.875033)
		(width 0.1)
		(layer "In2.Cu")
		(net 158)
	)
	(segment
		(start 101.581587 132.096828)
		(end 101.588832 132.117531)
		(width 0.1)
		(layer "In2.Cu")
		(net 158)
	)
	(segment
		(start 101.905019 132.347566)
		(end 101.893468 132.359117)
		(width 0.1)
		(layer "In2.Cu")
		(net 158)
	)
	(segment
		(start 101.588832 132.117531)
		(end 101.600501 132.136103)
		(width 0.1)
		(layer "In2.Cu")
		(net 158)
	)
	(segment
		(start 101.893468 132.759117)
		(end 101.879636 132.767808)
		(width 0.1)
		(layer "In2.Cu")
		(net 158)
	)
	(segment
		(start 101.920934 132.302083)
		(end 101.919105 132.318315)
		(width 0.1)
		(layer "In2.Cu")
		(net 158)
	)
	(segment
		(start 101.616011 132.553663)
		(end 101.634583 132.565332)
		(width 0.1)
		(layer "In2.Cu")
		(net 158)
	)
	(segment
		(start 101.581587 132.498878)
		(end 101.588832 132.519581)
		(width 0.1)
		(layer "In2.Cu")
		(net 158)
	)
	(segment
		(start 101.175033 146.457891)
		(end 101.775 147.057858)
		(width 0.1)
		(layer "In2.Cu")
		(net 158)
	)
	(segment
		(start 101.600501 132.009862)
		(end 101.588832 132.028434)
		(width 0.1)
		(layer "In2.Cu")
		(net 158)
	)
	(segment
		(start 101.905019 132.202499)
		(end 101.91371 132.216331)
		(width 0.1)
		(layer "In2.Cu")
		(net 158)
	)
	(segment
		(start 101.893468 132.190948)
		(end 101.905019 132.202499)
		(width 0.1)
		(layer "In2.Cu")
		(net 158)
	)
	(segment
		(start 101.91371 132.616331)
		(end 101.919105 132.63175)
		(width 0.1)
		(layer "In2.Cu")
		(net 158)
	)
	(segment
		(start 101.91371 132.216331)
		(end 101.919105 132.23175)
		(width 0.1)
		(layer "In2.Cu")
		(net 158)
	)
	(segment
		(start 101.600501 132.136103)
		(end 101.616011 132.151613)
		(width 0.1)
		(layer "In2.Cu")
		(net 158)
	)
	(segment
		(start 101.847984 132.175033)
		(end 101.864217 132.176862)
		(width 0.1)
		(layer "In2.Cu")
		(net 158)
	)
	(segment
		(start 101.634583 132.384733)
		(end 101.616011 132.396402)
		(width 0.1)
		(layer "In2.Cu")
		(net 158)
	)
	(segment
		(start 101.588832 132.028434)
		(end 101.581587 132.049137)
		(width 0.1)
		(layer "In2.Cu")
		(net 158)
	)
	(segment
		(start 101.847984 132.575033)
		(end 101.864217 132.576862)
		(width 0.1)
		(layer "In2.Cu")
		(net 158)
	)
	(segment
		(start 101.864217 132.373203)
		(end 101.847984 132.375033)
		(width 0.1)
		(layer "In2.Cu")
		(net 158)
	)
	(segment
		(start 101.275 128.675)
		(end 101.775033 129.175033)
		(width 0.1)
		(layer "In2.Cu")
		(net 158)
	)
	(segment
		(start 101.588832 132.519581)
		(end 101.600501 132.538153)
		(width 0.1)
		(layer "In2.Cu")
		(net 158)
	)
	(segment
		(start 101.579132 132.472983)
		(end 101.579132 132.477083)
		(width 0.1)
		(layer "In2.Cu")
		(net 158)
	)
	(segment
		(start 101.879636 132.367808)
		(end 101.864217 132.373203)
		(width 0.1)
		(layer "In2.Cu")
		(net 158)
	)
	(segment
		(start 101.775 147.057858)
		(end 101.775 148.175)
		(width 0.1)
		(layer "In2.Cu")
		(net 158)
	)
	(segment
		(start 101.879636 132.582257)
		(end 101.893468 132.590948)
		(width 0.1)
		(layer "In2.Cu")
		(net 158)
	)
	(segment
		(start 101.782258 132.816331)
		(end 101.776863 132.83175)
		(width 0.1)
		(layer "In2.Cu")
		(net 158)
	)
	(segment
		(start 101.919105 132.318315)
		(end 101.91371 132.333734)
		(width 0.1)
		(layer "In2.Cu")
		(net 158)
	)
	(segment
		(start 101.864217 132.576862)
		(end 101.879636 132.582257)
		(width 0.1)
		(layer "In2.Cu")
		(net 158)
	)
	(segment
		(start 101.634583 131.982683)
		(end 101.616011 131.994352)
		(width 0.1)
		(layer "In2.Cu")
		(net 158)
	)
	(segment
		(start 101.91371 132.333734)
		(end 101.905019 132.347566)
		(width 0.1)
		(layer "In2.Cu")
		(net 158)
	)
	(segment
		(start 101.893468 132.590948)
		(end 101.905019 132.602499)
		(width 0.1)
		(layer "In2.Cu")
		(net 158)
	)
	(segment
		(start 101.831751 132.776862)
		(end 101.816332 132.782257)
		(width 0.1)
		(layer "In2.Cu")
		(net 158)
	)
	(segment
		(start 101.893468 132.359117)
		(end 101.879636 132.367808)
		(width 0.1)
		(layer "In2.Cu")
		(net 158)
	)
	(segment
		(start 101.175033 143.047286)
		(end 101.175033 146.457891)
		(width 0.1)
		(layer "In2.Cu")
		(net 158)
	)
	(segment
		(start 101.719581 131.963282)
		(end 101.698878 131.970527)
		(width 0.1)
		(layer "In2.Cu")
		(net 158)
	)
	(segment
		(start 101.920934 132.647983)
		(end 101.920934 132.702083)
		(width 0.1)
		(layer "In2.Cu")
		(net 158)
	)
	(segment
		(start 101.775033 132.172983)
		(end 101.775033 132.175033)
		(width 0.1)
		(layer "In2.Cu")
		(net 158)
	)
	(segment
		(start 101.91371 132.733734)
		(end 101.905019 132.747566)
		(width 0.1)
		(layer "In2.Cu")
		(net 158)
	)
	(segment
		(start 101.920934 132.247983)
		(end 101.920934 132.302083)
		(width 0.1)
		(layer "In2.Cu")
		(net 158)
	)
	(segment
		(start 101.864217 132.176862)
		(end 101.879636 132.182257)
		(width 0.1)
		(layer "In2.Cu")
		(net 158)
	)
	(segment
		(start 101.588832 132.430484)
		(end 101.581587 132.451187)
		(width 0.1)
		(layer "In2.Cu")
		(net 158)
	)
	(segment
		(start 101.581587 132.049137)
		(end 101.579132 132.070933)
		(width 0.1)
		(layer "In2.Cu")
		(net 158)
	)
	(segment
		(start 102.175 144.375)
		(end 102.175 143.375)
		(width 0.1)
		(layer "F.Cu")
		(net 159)
	)
	(segment
		(start 102.575 144.775)
		(end 102.175 144.375)
		(width 0.1)
		(layer "F.Cu")
		(net 159)
	)
	(segment
		(start 100.775 125.175)
		(end 101.275 125.675)
		(width 0.15)
		(layer "F.Cu")
		(net 159)
	)
	(via
		(at 102.175 143.375)
		(size 0.5)
		(drill 0.2)
		(layers "F.Cu" "B.Cu")
		(net 159)
	)
	(via blind
		(at 101.275 125.675)
		(size 0.5)
		(drill 0.2)
		(layers "F.Cu" "In5.Cu")
		(net 159)
	)
	(segment
		(start 102.175 143.375)
		(end 102.175 142.36)
		(width 0.1)
		(layer "B.Cu")
		(net 159)
	)
	(segment
		(start 101.975044 130.475044)
		(end 102.175 130.675)
		(width 0.1)
		(layer "In5.Cu")
		(net 159)
	)
	(segment
		(start 102.459838 131.647492)
		(end 102.437585 131.65)
		(width 0.1)
		(layer "In5.Cu")
		(net 159)
	)
	(segment
		(start 102.083609 131.01901)
		(end 102.094282 131.025717)
		(width 0.1)
		(layer "In5.Cu")
		(net 159)
	)
	(segment
		(start 102.275 132.45)
		(end 102.252748 132.452507)
		(width 0.1)
		(layer "In5.Cu")
		(net 159)
	)
	(segment
		(start 102.535078 132.327747)
		(end 102.537585 132.35)
		(width 0.1)
		(layer "In5.Cu")
		(net 159)
	)
	(segment
		(start 102.094282 130.836866)
		(end 102.083609 130.843573)
		(width 0.1)
		(layer "In5.Cu")
		(net 159)
	)
	(segment
		(start 102.074696 132.071194)
		(end 102.067989 132.081867)
		(width 0.1)
		(layer "In5.Cu")
		(net 159)
	)
	(segment
		(start 102.527682 131.506611)
		(end 102.535078 131.527747)
		(width 0.1)
		(layer "In5.Cu")
		(net 159)
	)
	(segment
		(start 102.062415 131.393708)
		(end 102.063826 131.406234)
		(width 0.1)
		(layer "In5.Cu")
		(net 159)
	)
	(segment
		(start 102.118707 131.45)
		(end 102.437585 131.45)
		(width 0.1)
		(layer "In5.Cu")
		(net 159)
	)
	(segment
		(start 102.063826 132.093765)
		(end 102.062415 132.106292)
		(width 0.1)
		(layer "In5.Cu")
		(net 159)
	)
	(segment
		(start 102.094282 132.055574)
		(end 102.083609 132.062281)
		(width 0.1)
		(layer "In5.Cu")
		(net 159)
	)
	(segment
		(start 102.535078 131.527747)
		(end 102.537585 131.55)
		(width 0.1)
		(layer "In5.Cu")
		(net 159)
	)
	(segment
		(start 101.975044 126.728597)
		(end 101.975044 130.475044)
		(width 0.1)
		(layer "In5.Cu")
		(net 159)
	)
	(segment
		(start 102.437585 131.45)
		(end 102.459838 131.452507)
		(width 0.1)
		(layer "In5.Cu")
		(net 159)
	)
	(segment
		(start 102.10618 131.448588)
		(end 102.118707 131.45)
		(width 0.1)
		(layer "In5.Cu")
		(net 159)
	)
	(segment
		(start 102.535078 131.572252)
		(end 102.527682 131.593388)
		(width 0.1)
		(layer "In5.Cu")
		(net 159)
	)
	(segment
		(start 101.275 126.028553)
		(end 101.975044 126.728597)
		(width 0.1)
		(layer "In5.Cu")
		(net 159)
	)
	(segment
		(start 102.063826 131.406234)
		(end 102.067989 131.418132)
		(width 0.1)
		(layer "In5.Cu")
		(net 159)
	)
	(segment
		(start 101.275 125.675)
		(end 101.275 126.028553)
		(width 0.1)
		(layer "In5.Cu")
		(net 159)
	)
	(segment
		(start 102.074696 131.671194)
		(end 102.067989 131.681867)
		(width 0.1)
		(layer "In5.Cu")
		(net 159)
	)
	(segment
		(start 102.083609 131.437718)
		(end 102.094282 131.444425)
		(width 0.1)
		(layer "In5.Cu")
		(net 159)
	)
	(segment
		(start 102.074696 130.852486)
		(end 102.067989 130.863159)
		(width 0.1)
		(layer "In5.Cu")
		(net 159)
	)
	(segment
		(start 102.459838 131.052507)
		(end 102.480974 131.059903)
		(width 0.1)
		(layer "In5.Cu")
		(net 159)
	)
	(segment
		(start 102.527682 131.193388)
		(end 102.515769 131.212348)
		(width 0.1)
		(layer "In5.Cu")
		(net 159)
	)
	(segment
		(start 102.177508 132.527747)
		(end 102.175 132.55)
		(width 0.1)
		(layer "In5.Cu")
		(net 159)
	)
	(segment
		(start 102.537585 132.35)
		(end 102.535078 132.372252)
		(width 0.1)
		(layer "In5.Cu")
		(net 159)
	)
	(segment
		(start 102.175 130.775)
		(end 102.173588 130.787526)
		(width 0.1)
		(layer "In5.Cu")
		(net 159)
	)
	(segment
		(start 102.118707 132.05)
		(end 102.10618 132.051411)
		(width 0.1)
		(layer "In5.Cu")
		(net 159)
	)
	(segment
		(start 102.437585 132.05)
		(end 102.118707 132.05)
		(width 0.1)
		(layer "In5.Cu")
		(net 159)
	)
	(segment
		(start 102.118707 131.85)
		(end 102.437585 131.85)
		(width 0.1)
		(layer "In5.Cu")
		(net 159)
	)
	(segment
		(start 102.094282 131.655574)
		(end 102.083609 131.662281)
		(width 0.1)
		(layer "In5.Cu")
		(net 159)
	)
	(segment
		(start 102.459838 132.447492)
		(end 102.437585 132.45)
		(width 0.1)
		(layer "In5.Cu")
		(net 159)
	)
	(segment
		(start 102.537585 131.95)
		(end 102.535078 131.972252)
		(width 0.1)
		(layer "In5.Cu")
		(net 159)
	)
	(segment
		(start 102.153805 130.81901)
		(end 102.143132 130.825717)
		(width 0.1)
		(layer "In5.Cu")
		(net 159)
	)
	(segment
		(start 102.118708 131.031292)
		(end 102.175 131.031292)
		(width 0.1)
		(layer "In5.Cu")
		(net 159)
	)
	(segment
		(start 102.480974 132.259903)
		(end 102.499934 132.271816)
		(width 0.1)
		(layer "In5.Cu")
		(net 159)
	)
	(segment
		(start 102.067989 132.218132)
		(end 102.074696 132.228805)
		(width 0.1)
		(layer "In5.Cu")
		(net 159)
	)
	(segment
		(start 102.067989 131.418132)
		(end 102.074696 131.428805)
		(width 0.1)
		(layer "In5.Cu")
		(net 159)
	)
	(segment
		(start 102.175 131.031292)
		(end 102.175 131.05)
		(width 0.1)
		(layer "In5.Cu")
		(net 159)
	)
	(segment
		(start 102.535078 131.972252)
		(end 102.527682 131.993388)
		(width 0.1)
		(layer "In5.Cu")
		(net 159)
	)
	(segment
		(start 102.118707 132.25)
		(end 102.437585 132.25)
		(width 0.1)
		(layer "In5.Cu")
		(net 159)
	)
	(segment
		(start 102.083609 131.837718)
		(end 102.094282 131.844425)
		(width 0.1)
		(layer "In5.Cu")
		(net 159)
	)
	(segment
		(start 102.480974 131.459903)
		(end 102.499934 131.471816)
		(width 0.1)
		(layer "In5.Cu")
		(net 159)
	)
	(segment
		(start 102.062415 131.793708)
		(end 102.063826 131.806234)
		(width 0.1)
		(layer "In5.Cu")
		(net 159)
	)
	(segment
		(start 102.10618 131.848588)
		(end 102.118707 131.85)
		(width 0.1)
		(layer "In5.Cu")
		(net 159)
	)
	(segment
		(start 102.515769 132.412348)
		(end 102.499934 132.428183)
		(width 0.1)
		(layer "In5.Cu")
		(net 159)
	)
	(segment
		(start 102.10618 131.651411)
		(end 102.094282 131.655574)
		(width 0.1)
		(layer "In5.Cu")
		(net 159)
	)
	(segment
		(start 102.535078 131.927747)
		(end 102.537585 131.95)
		(width 0.1)
		(layer "In5.Cu")
		(net 159)
	)
	(segment
		(start 102.063826 131.806234)
		(end 102.067989 131.818132)
		(width 0.1)
		(layer "In5.Cu")
		(net 159)
	)
	(segment
		(start 102.535078 131.172252)
		(end 102.527682 131.193388)
		(width 0.1)
		(layer "In5.Cu")
		(net 159)
	)
	(segment
		(start 102.499934 131.228183)
		(end 102.480974 131.240096)
		(width 0.1)
		(layer "In5.Cu")
		(net 159)
	)
	(segment
		(start 102.212652 132.471816)
		(end 102.196817 132.487651)
		(width 0.1)
		(layer "In5.Cu")
		(net 159)
	)
	(segment
		(start 102.10618 132.248588)
		(end 102.118707 132.25)
		(width 0.1)
		(layer "In5.Cu")
		(net 159)
	)
	(segment
		(start 102.437585 132.45)
		(end 102.275 132.45)
		(width 0.1)
		(layer "In5.Cu")
		(net 159)
	)
	(segment
		(start 102.083609 131.262281)
		(end 102.074696 131.271194)
		(width 0.1)
		(layer "In5.Cu")
		(net 159)
	)
	(segment
		(start 102.515769 132.287651)
		(end 102.527682 132.306611)
		(width 0.1)
		(layer "In5.Cu")
		(net 159)
	)
	(segment
		(start 102.083609 132.062281)
		(end 102.074696 132.071194)
		(width 0.1)
		(layer "In5.Cu")
		(net 159)
	)
	(segment
		(start 102.480974 132.440096)
		(end 102.459838 132.447492)
		(width 0.1)
		(layer "In5.Cu")
		(net 159)
	)
	(segment
		(start 102.094282 132.244425)
		(end 102.10618 132.248588)
		(width 0.1)
		(layer "In5.Cu")
		(net 159)
	)
	(segment
		(start 102.437585 132.25)
		(end 102.459838 132.252507)
		(width 0.1)
		(layer "In5.Cu")
		(net 159)
	)
	(segment
		(start 102.499934 131.071816)
		(end 102.515769 131.087651)
		(width 0.1)
		(layer "In5.Cu")
		(net 159)
	)
	(segment
		(start 102.10618 131.02988)
		(end 102.118708 131.031292)
		(width 0.1)
		(layer "In5.Cu")
		(net 159)
	)
	(segment
		(start 102.067989 131.681867)
		(end 102.063826 131.693765)
		(width 0.1)
		(layer "In5.Cu")
		(net 159)
	)
	(segment
		(start 102.074696 131.428805)
		(end 102.083609 131.437718)
		(width 0.1)
		(layer "In5.Cu")
		(net 159)
	)
	(segment
		(start 102.083609 131.662281)
		(end 102.074696 131.671194)
		(width 0.1)
		(layer "In5.Cu")
		(net 159)
	)
	(segment
		(start 102.515769 131.487651)
		(end 102.527682 131.506611)
		(width 0.1)
		(layer "In5.Cu")
		(net 159)
	)
	(segment
		(start 102.515769 131.087651)
		(end 102.527682 131.106611)
		(width 0.1)
		(layer "In5.Cu")
		(net 159)
	)
	(segment
		(start 102.480974 131.859903)
		(end 102.499934 131.871816)
		(width 0.1)
		(layer "In5.Cu")
		(net 159)
	)
	(segment
		(start 102.437585 131.25)
		(end 102.118707 131.25)
		(width 0.1)
		(layer "In5.Cu")
		(net 159)
	)
	(segment
		(start 102.074696 131.271194)
		(end 102.067989 131.281867)
		(width 0.1)
		(layer "In5.Cu")
		(net 159)
	)
	(segment
		(start 102.063826 131.693765)
		(end 102.062415 131.706292)
		(width 0.1)
		(layer "In5.Cu")
		(net 159)
	)
	(segment
		(start 102.062415 131.306292)
		(end 102.062415 131.393708)
		(width 0.1)
		(layer "In5.Cu")
		(net 159)
	)
	(segment
		(start 102.527682 132.393388)
		(end 102.515769 132.412348)
		(width 0.1)
		(layer "In5.Cu")
		(net 159)
	)
	(segment
		(start 102.118707 131.25)
		(end 102.10618 131.251411)
		(width 0.1)
		(layer "In5.Cu")
		(net 159)
	)
	(segment
		(start 102.131234 130.82988)
		(end 102.10618 130.832703)
		(width 0.1)
		(layer "In5.Cu")
		(net 159)
	)
	(segment
		(start 102.480974 132.040096)
		(end 102.459838 132.047492)
		(width 0.1)
		(layer "In5.Cu")
		(net 159)
	)
	(segment
		(start 102.459838 131.247492)
		(end 102.437585 131.25)
		(width 0.1)
		(layer "In5.Cu")
		(net 159)
	)
	(segment
		(start 102.063826 131.293765)
		(end 102.062415 131.306292)
		(width 0.1)
		(layer "In5.Cu")
		(net 159)
	)
	(segment
		(start 102.063826 130.987526)
		(end 102.067989 130.999424)
		(width 0.1)
		(layer "In5.Cu")
		(net 159)
	)
	(segment
		(start 102.480974 131.240096)
		(end 102.459838 131.247492)
		(width 0.1)
		(layer "In5.Cu")
		(net 159)
	)
	(segment
		(start 102.499934 131.471816)
		(end 102.515769 131.487651)
		(width 0.1)
		(layer "In5.Cu")
		(net 159)
	)
	(segment
		(start 102.184904 132.506611)
		(end 102.177508 132.527747)
		(width 0.1)
		(layer "In5.Cu")
		(net 159)
	)
	(segment
		(start 102.175 130.675)
		(end 102.175 130.775)
		(width 0.1)
		(layer "In5.Cu")
		(net 159)
	)
	(segment
		(start 102.437585 131.85)
		(end 102.459838 131.852507)
		(width 0.1)
		(layer "In5.Cu")
		(net 159)
	)
	(segment
		(start 102.459838 131.452507)
		(end 102.480974 131.459903)
		(width 0.1)
		(layer "In5.Cu")
		(net 159)
	)
	(segment
		(start 102.118707 131.65)
		(end 102.10618 131.651411)
		(width 0.1)
		(layer "In5.Cu")
		(net 159)
	)
	(segment
		(start 102.535078 131.127747)
		(end 102.537585 131.15)
		(width 0.1)
		(layer "In5.Cu")
		(net 159)
	)
	(segment
		(start 102.499934 131.628183)
		(end 102.480974 131.640096)
		(width 0.1)
		(layer "In5.Cu")
		(net 159)
	)
	(segment
		(start 102.231612 132.459903)
		(end 102.212652 132.471816)
		(width 0.1)
		(layer "In5.Cu")
		(net 159)
	)
	(segment
		(start 102.515769 131.212348)
		(end 102.499934 131.228183)
		(width 0.1)
		(layer "In5.Cu")
		(net 159)
	)
	(segment
		(start 102.143132 130.825717)
		(end 102.131234 130.82988)
		(width 0.1)
		(layer "In5.Cu")
		(net 159)
	)
	(segment
		(start 102.437585 131.65)
		(end 102.118707 131.65)
		(width 0.1)
		(layer "In5.Cu")
		(net 159)
	)
	(segment
		(start 102.094282 131.844425)
		(end 102.10618 131.848588)
		(width 0.1)
		(layer "In5.Cu")
		(net 159)
	)
	(segment
		(start 102.527682 131.106611)
		(end 102.535078 131.127747)
		(width 0.1)
		(layer "In5.Cu")
		(net 159)
	)
	(segment
		(start 102.169425 130.799424)
		(end 102.162718 130.810097)
		(width 0.1)
		(layer "In5.Cu")
		(net 159)
	)
	(segment
		(start 102.10618 132.051411)
		(end 102.094282 132.055574)
		(width 0.1)
		(layer "In5.Cu")
		(net 159)
	)
	(segment
		(start 102.459838 131.852507)
		(end 102.480974 131.859903)
		(width 0.1)
		(layer "In5.Cu")
		(net 159)
	)
	(segment
		(start 102.459838 132.047492)
		(end 102.437585 132.05)
		(width 0.1)
		(layer "In5.Cu")
		(net 159)
	)
	(segment
		(start 102.537585 131.15)
		(end 102.535078 131.172252)
		(width 0.1)
		(layer "In5.Cu")
		(net 159)
	)
	(segment
		(start 102.067989 132.081867)
		(end 102.063826 132.093765)
		(width 0.1)
		(layer "In5.Cu")
		(net 159)
	)
	(segment
		(start 102.094282 131.444425)
		(end 102.10618 131.448588)
		(width 0.1)
		(layer "In5.Cu")
		(net 159)
	)
	(segment
		(start 102.063826 132.206234)
		(end 102.067989 132.218132)
		(width 0.1)
		(layer "In5.Cu")
		(net 159)
	)
	(segment
		(start 102.067989 131.818132)
		(end 102.074696 131.828805)
		(width 0.1)
		(layer "In5.Cu")
		(net 159)
	)
	(segment
		(start 102.196817 132.487651)
		(end 102.184904 132.506611)
		(width 0.1)
		(layer "In5.Cu")
		(net 159)
	)
	(segment
		(start 102.083609 130.843573)
		(end 102.074696 130.852486)
		(width 0.1)
		(layer "In5.Cu")
		(net 159)
	)
	(segment
		(start 102.499934 132.028183)
		(end 102.480974 132.040096)
		(width 0.1)
		(layer "In5.Cu")
		(net 159)
	)
	(segment
		(start 102.527682 131.906611)
		(end 102.535078 131.927747)
		(width 0.1)
		(layer "In5.Cu")
		(net 159)
	)
	(segment
		(start 102.173588 130.787526)
		(end 102.169425 130.799424)
		(width 0.1)
		(layer "In5.Cu")
		(net 159)
	)
	(segment
		(start 102.062415 131.706292)
		(end 102.062415 131.793708)
		(width 0.1)
		(layer "In5.Cu")
		(net 159)
	)
	(segment
		(start 102.527682 132.306611)
		(end 102.535078 132.327747)
		(width 0.1)
		(layer "In5.Cu")
		(net 159)
	)
	(segment
		(start 102.062415 130.975)
		(end 102.063826 130.987526)
		(width 0.1)
		(layer "In5.Cu")
		(net 159)
	)
	(segment
		(start 102.063826 130.875057)
		(end 102.062415 130.887584)
		(width 0.1)
		(layer "In5.Cu")
		(net 159)
	)
	(segment
		(start 102.537585 131.55)
		(end 102.535078 131.572252)
		(width 0.1)
		(layer "In5.Cu")
		(net 159)
	)
	(segment
		(start 102.459838 132.252507)
		(end 102.480974 132.259903)
		(width 0.1)
		(layer "In5.Cu")
		(net 159)
	)
	(segment
		(start 102.480974 131.059903)
		(end 102.499934 131.071816)
		(width 0.1)
		(layer "In5.Cu")
		(net 159)
	)
	(segment
		(start 102.067989 131.281867)
		(end 102.063826 131.293765)
		(width 0.1)
		(layer "In5.Cu")
		(net 159)
	)
	(segment
		(start 102.499934 132.271816)
		(end 102.515769 132.287651)
		(width 0.1)
		(layer "In5.Cu")
		(net 159)
	)
	(segment
		(start 102.074696 131.010097)
		(end 102.083609 131.01901)
		(width 0.1)
		(layer "In5.Cu")
		(net 159)
	)
	(segment
		(start 102.480974 131.640096)
		(end 102.459838 131.647492)
		(width 0.1)
		(layer "In5.Cu")
		(net 159)
	)
	(segment
		(start 102.067989 130.999424)
		(end 102.074696 131.010097)
		(width 0.1)
		(layer "In5.Cu")
		(net 159)
	)
	(segment
		(start 102.062415 132.106292)
		(end 102.062415 132.193708)
		(width 0.1)
		(layer "In5.Cu")
		(net 159)
	)
	(segment
		(start 102.062415 132.193708)
		(end 102.063826 132.206234)
		(width 0.1)
		(layer "In5.Cu")
		(net 159)
	)
	(segment
		(start 102.162718 130.810097)
		(end 102.153805 130.81901)
		(width 0.1)
		(layer "In5.Cu")
		(net 159)
	)
	(segment
		(start 102.515769 131.887651)
		(end 102.527682 131.906611)
		(width 0.1)
		(layer "In5.Cu")
		(net 159)
	)
	(segment
		(start 102.515769 132.012348)
		(end 102.499934 132.028183)
		(width 0.1)
		(layer "In5.Cu")
		(net 159)
	)
	(segment
		(start 102.499934 132.428183)
		(end 102.480974 132.440096)
		(width 0.1)
		(layer "In5.Cu")
		(net 159)
	)
	(segment
		(start 102.083609 132.237718)
		(end 102.094282 132.244425)
		(width 0.1)
		(layer "In5.Cu")
		(net 159)
	)
	(segment
		(start 102.067989 130.863159)
		(end 102.063826 130.875057)
		(width 0.1)
		(layer "In5.Cu")
		(net 159)
	)
	(segment
		(start 102.527682 131.993388)
		(end 102.515769 132.012348)
		(width 0.1)
		(layer "In5.Cu")
		(net 159)
	)
	(segment
		(start 102.094282 131.025717)
		(end 102.10618 131.02988)
		(width 0.1)
		(layer "In5.Cu")
		(net 159)
	)
	(segment
		(start 102.252748 132.452507)
		(end 102.231612 132.459903)
		(width 0.1)
		(layer "In5.Cu")
		(net 159)
	)
	(segment
		(start 102.074696 132.228805)
		(end 102.083609 132.237718)
		(width 0.1)
		(layer "In5.Cu")
		(net 159)
	)
	(segment
		(start 102.535078 132.372252)
		(end 102.527682 132.393388)
		(width 0.1)
		(layer "In5.Cu")
		(net 159)
	)
	(segment
		(start 102.175 132.55)
		(end 102.175 143.375)
		(width 0.1)
		(layer "In5.Cu")
		(net 159)
	)
	(segment
		(start 102.499934 131.871816)
		(end 102.515769 131.887651)
		(width 0.1)
		(layer "In5.Cu")
		(net 159)
	)
	(segment
		(start 102.094282 131.255574)
		(end 102.083609 131.262281)
		(width 0.1)
		(layer "In5.Cu")
		(net 159)
	)
	(segment
		(start 102.527682 131.593388)
		(end 102.515769 131.612348)
		(width 0.1)
		(layer "In5.Cu")
		(net 159)
	)
	(segment
		(start 102.175 131.05)
		(end 102.437585 131.05)
		(width 0.1)
		(layer "In5.Cu")
		(net 159)
	)
	(segment
		(start 102.437585 131.05)
		(end 102.459838 131.052507)
		(width 0.1)
		(layer "In5.Cu")
		(net 159)
	)
	(segment
		(start 102.062415 130.887584)
		(end 102.062415 130.975)
		(width 0.1)
		(layer "In5.Cu")
		(net 159)
	)
	(segment
		(start 102.10618 131.251411)
		(end 102.094282 131.255574)
		(width 0.1)
		(layer "In5.Cu")
		(net 159)
	)
	(segment
		(start 102.515769 131.612348)
		(end 102.499934 131.628183)
		(width 0.1)
		(layer "In5.Cu")
		(net 159)
	)
	(segment
		(start 102.10618 130.832703)
		(end 102.094282 130.836866)
		(width 0.1)
		(layer "In5.Cu")
		(net 159)
	)
	(segment
		(start 102.074696 131.828805)
		(end 102.083609 131.837718)
		(width 0.1)
		(layer "In5.Cu")
		(net 159)
	)
	(segment
		(start 99.375 143.975)
		(end 99.375 143.375)
		(width 0.1)
		(layer "F.Cu")
		(net 160)
	)
	(segment
		(start 98.775 125.175)
		(end 99.275 125.675)
		(width 0.15)
		(layer "F.Cu")
		(net 160)
	)
	(via
		(at 99.375 143.375)
		(size 0.5)
		(drill 0.2)
		(layers "F.Cu" "B.Cu")
		(net 160)
	)
	(via blind
		(at 99.275 125.675)
		(size 0.5)
		(drill 0.2)
		(layers "F.Cu" "In5.Cu")
		(net 160)
	)
	(segment
		(start 98.59 144.16)
		(end 99.375 143.375)
		(width 0.2)
		(layer "B.Cu")
		(net 160)
	)
	(segment
		(start 98.59 144.775)
		(end 98.59 144.16)
		(width 0.2)
		(layer "B.Cu")
		(net 160)
	)
	(segment
		(start 99.275 125.675)
		(end 99.675 126.075)
		(width 0.1)
		(layer "In5.Cu")
		(net 160)
	)
	(segment
		(start 99.574989 127.092153)
		(end 99.574989 130.175011)
		(width 0.1)
		(layer "In5.Cu")
		(net 160)
	)
	(segment
		(start 99.574989 130.175011)
		(end 99.375 130.375)
		(width 0.1)
		(layer "In5.Cu")
		(net 160)
	)
	(segment
		(start 99.675 126.075)
		(end 99.675 126.992142)
		(width 0.1)
		(layer "In5.Cu")
		(net 160)
	)
	(segment
		(start 99.675 126.992142)
		(end 99.574989 127.092153)
		(width 0.1)
		(layer "In5.Cu")
		(net 160)
	)
	(segment
		(start 99.375 130.375)
		(end 99.375 143.375)
		(width 0.1)
		(layer "In5.Cu")
		(net 160)
	)
	(segment
		(start 99.775 127.175)
		(end 99.275 127.675)
		(width 0.15)
		(layer "F.Cu")
		(net 161)
	)
	(segment
		(start 99.775 149.975)
		(end 99.775 147.675)
		(width 0.1)
		(layer "F.Cu")
		(net 161)
	)
	(segment
		(start 99.375 150.375)
		(end 99.775 149.975)
		(width 0.1)
		(layer "F.Cu")
		(net 161)
	)
	(via blind
		(at 99.275 127.675)
		(size 0.5)
		(drill 0.2)
		(layers "F.Cu" "In2.Cu")
		(net 161)
	)
	(via
		(at 99.775 147.675)
		(size 0.5)
		(drill 0.2)
		(layers "F.Cu" "B.Cu")
		(net 161)
	)
	(segment
		(start 99.26 146.86)
		(end 99.775 147.375)
		(width 0.1)
		(layer "B.Cu")
		(net 161)
	)
	(segment
		(start 99.075 146.86)
		(end 99.26 146.86)
		(width 0.1)
		(layer "B.Cu")
		(net 161)
	)
	(segment
		(start 99.775 147.375)
		(end 99.775 147.675)
		(width 0.1)
		(layer "B.Cu")
		(net 161)
	)
	(segment
		(start 98.975 142.975)
		(end 98.975 146.592144)
		(width 0.1)
		(layer "In2.Cu")
		(net 161)
	)
	(segment
		(start 99.674988 128.074988)
		(end 99.674988 130.482978)
		(width 0.1)
		(layer "In2.Cu")
		(net 161)
	)
	(segment
		(start 99.775 147.392144)
		(end 99.775 147.575)
		(width 0.1)
		(layer "In2.Cu")
		(net 161)
	)
	(segment
		(start 99.674967 130.482999)
		(end 99.674967 142.275033)
		(width 0.1)
		(layer "In2.Cu")
		(net 161)
	)
	(segment
		(start 99.674988 130.482978)
		(end 99.674967 130.482999)
		(width 0.1)
		(layer "In2.Cu")
		(net 161)
	)
	(segment
		(start 99.275 127.675)
		(end 99.674988 128.074988)
		(width 0.1)
		(layer "In2.Cu")
		(net 161)
	)
	(segment
		(start 98.975 146.592144)
		(end 99.775 147.392144)
		(width 0.1)
		(layer "In2.Cu")
		(net 161)
	)
	(segment
		(start 99.674967 142.275033)
		(end 98.975 142.975)
		(width 0.1)
		(layer "In2.Cu")
		(net 161)
	)
	(segment
		(start 98.575 148.775)
		(end 98.575 148.175)
		(width 0.1)
		(layer "F.Cu")
		(net 162)
	)
	(segment
		(start 98.775 127.175)
		(end 98.275 127.675)
		(width 0.15)
		(layer "F.Cu")
		(net 162)
	)
	(via
		(at 98.575 148.175)
		(size 0.5)
		(drill 0.2)
		(layers "F.Cu" "B.Cu")
		(net 162)
	)
	(via blind
		(at 98.275 127.675)
		(size 0.5)
		(drill 0.2)
		(layers "F.Cu" "In2.Cu")
		(net 162)
	)
	(segment
		(start 94.975 148.575)
		(end 95.375 148.175)
		(width 0.2)
		(layer "B.Cu")
		(net 162)
	)
	(segment
		(start 95.375 148.175)
		(end 98.575 148.175)
		(width 0.2)
		(layer "B.Cu")
		(net 162)
	)
	(segment
		(start 94.975 149.19)
		(end 94.975 148.575)
		(width 0.2)
		(layer "B.Cu")
		(net 162)
	)
	(segment
		(start 97.874999 128.075001)
		(end 97.874999 142.892143)
		(width 0.1)
		(layer "In2.Cu")
		(net 162)
	)
	(segment
		(start 98.175 143.192144)
		(end 98.175 147.775)
		(width 0.1)
		(layer "In2.Cu")
		(net 162)
	)
	(segment
		(start 97.874999 142.892143)
		(end 98.175 143.192144)
		(width 0.1)
		(layer "In2.Cu")
		(net 162)
	)
	(segment
		(start 98.175 147.775)
		(end 98.575 148.175)
		(width 0.1)
		(layer "In2.Cu")
		(net 162)
	)
	(segment
		(start 98.275 127.675)
		(end 97.874999 128.075001)
		(width 0.1)
		(layer "In2.Cu")
		(net 162)
	)
	(segment
		(start 100.55 151.65)
		(end 100.5 151.7)
		(width 0.1)
		(layer "F.Cu")
		(net 163)
	)
	(segment
		(start 100.175 149.575)
		(end 100.55 149.95)
		(width 0.1)
		(layer "F.Cu")
		(net 163)
	)
	(segment
		(start 100.55 149.95)
		(end 100.55 151.65)
		(width 0.1)
		(layer "F.Cu")
		(net 163)
	)
	(via
		(at 100.5 151.7)
		(size 0.5)
		(drill 0.2)
		(layers "F.Cu" "B.Cu")
		(net 163)
	)
	(segment
		(start 100.5 151.7)
		(end 101.365 151.7)
		(width 0.1)
		(layer "B.Cu")
		(net 163)
	)
	(segment
		(start 101.365 151.7)
		(end 101.39 151.675)
		(width 0.1)
		(layer "B.Cu")
		(net 163)
	)
	(segment
		(start 100.775 128.175)
		(end 100.275 128.675)
		(width 0.15)
		(layer "F.Cu")
		(net 164)
	)
	(segment
		(start 100.575 149.175)
		(end 100.575 147.675)
		(width 0.1)
		(layer "F.Cu")
		(net 164)
	)
	(segment
		(start 100.975 149.575)
		(end 100.575 149.175)
		(width 0.1)
		(layer "F.Cu")
		(net 164)
	)
	(via blind
		(at 100.275 128.675)
		(size 0.5)
		(drill 0.2)
		(layers "F.Cu" "In2.Cu")
		(net 164)
	)
	(via
		(at 100.575 147.675)
		(size 0.5)
		(drill 0.2)
		(layers "F.Cu" "B.Cu")
		(net 164)
	)
	(segment
		(start 100.075 147.175)
		(end 100.575 147.675)
		(width 0.1)
		(layer "B.Cu")
		(net 164)
	)
	(segment
		(start 100.075 146.86)
		(end 100.075 147.175)
		(width 0.1)
		(layer "B.Cu")
		(net 164)
	)
	(segment
		(start 100.143352 129.318376)
		(end 100.155265 129.337336)
		(width 0.1)
		(layer "In2.Cu")
		(net 164)
	)
	(segment
		(start 100.275 128.675)
		(end 100.674988 129.074988)
		(width 0.1)
		(layer "In2.Cu")
		(net 164)
	)
	(segment
		(start 100.59724 129.377495)
		(end 100.618376 129.384891)
		(width 0.1)
		(layer "In2.Cu")
		(net 164)
	)
	(segment
		(start 100.653171 129.537336)
		(end 100.637336 129.553171)
		(width 0.1)
		(layer "In2.Cu")
		(net 164)
	)
	(segment
		(start 100.155265 129.737336)
		(end 100.1711 129.753171)
		(width 0.1)
		(layer "In2.Cu")
		(net 164)
	)
	(segment
		(start 100.653171 129.412639)
		(end 100.665084 129.431599)
		(width 0.1)
		(layer "In2.Cu")
		(net 164)
	)
	(segment
		(start 100.637336 129.153171)
		(end 100.618376 129.165084)
		(width 0.1)
		(layer "In2.Cu")
		(net 164)
	)
	(segment
		(start 100.574988 129.774988)
		(end 100.59724 129.777495)
		(width 0.1)
		(layer "In2.Cu")
		(net 164)
	)
	(segment
		(start 100.233449 129.574988)
		(end 100.211196 129.577495)
		(width 0.1)
		(layer "In2.Cu")
		(net 164)
	)
	(segment
		(start 100.135956 129.652735)
		(end 100.133449 129.674988)
		(width 0.1)
		(layer "In2.Cu")
		(net 164)
	)
	(segment
		(start 100.233449 129.374988)
		(end 100.574988 129.374988)
		(width 0.1)
		(layer "In2.Cu")
		(net 164)
	)
	(segment
		(start 100.618376 129.384891)
		(end 100.637336 129.396804)
		(width 0.1)
		(layer "In2.Cu")
		(net 164)
	)
	(segment
		(start 100.155265 129.212639)
		(end 100.143352 129.231599)
		(width 0.1)
		(layer "In2.Cu")
		(net 164)
	)
	(segment
		(start 100.19006 129.584891)
		(end 100.1711 129.596804)
		(width 0.1)
		(layer "In2.Cu")
		(net 164)
	)
	(segment
		(start 100.637336 129.796804)
		(end 100.653171 129.812639)
		(width 0.1)
		(layer "In2.Cu")
		(net 164)
	)
	(segment
		(start 100.637336 129.396804)
		(end 100.653171 129.412639)
		(width 0.1)
		(layer "In2.Cu")
		(net 164)
	)
	(segment
		(start 100.67248 129.852735)
		(end 100.674988 129.874988)
		(width 0.1)
		(layer "In2.Cu")
		(net 164)
	)
	(segment
		(start 100.135956 129.29724)
		(end 100.143352 129.318376)
		(width 0.1)
		(layer "In2.Cu")
		(net 164)
	)
	(segment
		(start 100.574988 129.174988)
		(end 100.233449 129.174988)
		(width 0.1)
		(layer "In2.Cu")
		(net 164)
	)
	(segment
		(start 100.1711 129.596804)
		(end 100.155265 129.612639)
		(width 0.1)
		(layer "In2.Cu")
		(net 164)
	)
	(segment
		(start 100.874989 131.207847)
		(end 100.874989 131.775011)
		(width 0.1)
		(layer "In2.Cu")
		(net 164)
	)
	(segment
		(start 100.665084 129.118376)
		(end 100.653171 129.137336)
		(width 0.1)
		(layer "In2.Cu")
		(net 164)
	)
	(segment
		(start 100.143352 129.631599)
		(end 100.135956 129.652735)
		(width 0.1)
		(layer "In2.Cu")
		(net 164)
	)
	(segment
		(start 100.59724 129.17248)
		(end 100.574988 129.174988)
		(width 0.1)
		(layer "In2.Cu")
		(net 164)
	)
	(segment
		(start 100.211196 129.37248)
		(end 100.233449 129.374988)
		(width 0.1)
		(layer "In2.Cu")
		(net 164)
	)
	(segment
		(start 100.665084 129.831599)
		(end 100.67248 129.852735)
		(width 0.1)
		(layer "In2.Cu")
		(net 164)
	)
	(segment
		(start 100.211196 129.177495)
		(end 100.19006 129.184891)
		(width 0.1)
		(layer "In2.Cu")
		(net 164)
	)
	(segment
		(start 100.574988 129.374988)
		(end 100.59724 129.377495)
		(width 0.1)
		(layer "In2.Cu")
		(net 164)
	)
	(segment
		(start 100.67248 129.452735)
		(end 100.674988 129.474988)
		(width 0.1)
		(layer "In2.Cu")
		(net 164)
	)
	(segment
		(start 100.143352 129.231599)
		(end 100.135956 129.252735)
		(width 0.1)
		(layer "In2.Cu")
		(net 164)
	)
	(segment
		(start 100.1711 129.353171)
		(end 100.19006 129.365084)
		(width 0.1)
		(layer "In2.Cu")
		(net 164)
	)
	(segment
		(start 100.653171 129.137336)
		(end 100.637336 129.153171)
		(width 0.1)
		(layer "In2.Cu")
		(net 164)
	)
	(segment
		(start 100.59724 129.57248)
		(end 100.574988 129.574988)
		(width 0.1)
		(layer "In2.Cu")
		(net 164)
	)
	(segment
		(start 100.211196 129.577495)
		(end 100.19006 129.584891)
		(width 0.1)
		(layer "In2.Cu")
		(net 164)
	)
	(segment
		(start 100.19006 129.765084)
		(end 100.211196 129.77248)
		(width 0.1)
		(layer "In2.Cu")
		(net 164)
	)
	(segment
		(start 100.674989 131.007847)
		(end 100.874989 131.207847)
		(width 0.1)
		(layer "In2.Cu")
		(net 164)
	)
	(segment
		(start 100.133449 129.274988)
		(end 100.135956 129.29724)
		(width 0.1)
		(layer "In2.Cu")
		(net 164)
	)
	(segment
		(start 100.133449 129.674988)
		(end 100.135956 129.69724)
		(width 0.1)
		(layer "In2.Cu")
		(net 164)
	)
	(segment
		(start 100.637336 129.553171)
		(end 100.618376 129.565084)
		(width 0.1)
		(layer "In2.Cu")
		(net 164)
	)
	(segment
		(start 100.233449 129.174988)
		(end 100.211196 129.177495)
		(width 0.1)
		(layer "In2.Cu")
		(net 164)
	)
	(segment
		(start 100.155265 129.612639)
		(end 100.143352 129.631599)
		(width 0.1)
		(layer "In2.Cu")
		(net 164)
	)
	(segment
		(start 100.653171 129.812639)
		(end 100.665084 129.831599)
		(width 0.1)
		(layer "In2.Cu")
		(net 164)
	)
	(segment
		(start 100.59724 129.777495)
		(end 100.618376 129.784891)
		(width 0.1)
		(layer "In2.Cu")
		(net 164)
	)
	(segment
		(start 100.618376 129.784891)
		(end 100.637336 129.796804)
		(width 0.1)
		(layer "In2.Cu")
		(net 164)
	)
	(segment
		(start 100.574988 129.574988)
		(end 100.233449 129.574988)
		(width 0.1)
		(layer "In2.Cu")
		(net 164)
	)
	(segment
		(start 100.19006 129.184891)
		(end 100.1711 129.196804)
		(width 0.1)
		(layer "In2.Cu")
		(net 164)
	)
	(segment
		(start 100.155265 129.337336)
		(end 100.1711 129.353171)
		(width 0.1)
		(layer "In2.Cu")
		(net 164)
	)
	(segment
		(start 100.618376 129.565084)
		(end 100.59724 129.57248)
		(width 0.1)
		(layer "In2.Cu")
		(net 164)
	)
	(segment
		(start 100.874989 131.775011)
		(end 100.575 132.075)
		(width 0.1)
		(layer "In2.Cu")
		(net 164)
	)
	(segment
		(start 100.674988 129.074988)
		(end 100.67248 129.09724)
		(width 0.1)
		(layer "In2.Cu")
		(net 164)
	)
	(segment
		(start 100.135956 129.69724)
		(end 100.143352 129.718376)
		(width 0.1)
		(layer "In2.Cu")
		(net 164)
	)
	(segment
		(start 100.211196 129.77248)
		(end 100.233449 129.774988)
		(width 0.1)
		(layer "In2.Cu")
		(net 164)
	)
	(segment
		(start 100.233449 129.774988)
		(end 100.574988 129.774988)
		(width 0.1)
		(layer "In2.Cu")
		(net 164)
	)
	(segment
		(start 100.618376 129.165084)
		(end 100.59724 129.17248)
		(width 0.1)
		(layer "In2.Cu")
		(net 164)
	)
	(segment
		(start 100.1711 129.196804)
		(end 100.155265 129.212639)
		(width 0.1)
		(layer "In2.Cu")
		(net 164)
	)
	(segment
		(start 100.67248 129.49724)
		(end 100.665084 129.518376)
		(width 0.1)
		(layer "In2.Cu")
		(net 164)
	)
	(segment
		(start 100.67248 129.09724)
		(end 100.665084 129.118376)
		(width 0.1)
		(layer "In2.Cu")
		(net 164)
	)
	(segment
		(start 100.665084 129.518376)
		(end 100.653171 129.537336)
		(width 0.1)
		(layer "In2.Cu")
		(net 164)
	)
	(segment
		(start 100.1711 129.753171)
		(end 100.19006 129.765084)
		(width 0.1)
		(layer "In2.Cu")
		(net 164)
	)
	(segment
		(start 100.19006 129.365084)
		(end 100.211196 129.37248)
		(width 0.1)
		(layer "In2.Cu")
		(net 164)
	)
	(segment
		(start 100.575 132.075)
		(end 100.575 147.675)
		(width 0.1)
		(layer "In2.Cu")
		(net 164)
	)
	(segment
		(start 100.674988 129.474988)
		(end 100.67248 129.49724)
		(width 0.1)
		(layer "In2.Cu")
		(net 164)
	)
	(segment
		(start 100.143352 129.718376)
		(end 100.155265 129.737336)
		(width 0.1)
		(layer "In2.Cu")
		(net 164)
	)
	(segment
		(start 100.135956 129.252735)
		(end 100.133449 129.274988)
		(width 0.1)
		(layer "In2.Cu")
		(net 164)
	)
	(segment
		(start 100.665084 129.431599)
		(end 100.67248 129.452735)
		(width 0.1)
		(layer "In2.Cu")
		(net 164)
	)
	(segment
		(start 100.674988 129.874988)
		(end 100.674989 131.007847)
		(width 0.1)
		(layer "In2.Cu")
		(net 164)
	)
	(segment
		(start 101.775 149.575)
		(end 101.375 149.175)
		(width 0.1)
		(layer "F.Cu")
		(net 165)
	)
	(segment
		(start 101.775 130.175)
		(end 101.275 130.675)
		(width 0.15)
		(layer "F.Cu")
		(net 165)
	)
	(segment
		(start 101.375 149.175)
		(end 101.375 147.675)
		(width 0.1)
		(layer "F.Cu")
		(net 165)
	)
	(via blind
		(at 101.275 130.675)
		(size 0.5)
		(drill 0.2)
		(layers "F.Cu" "In2.Cu")
		(net 165)
	)
	(via
		(at 101.375 147.675)
		(size 0.5)
		(drill 0.2)
		(layers "F.Cu" "B.Cu")
		(net 165)
	)
	(segment
		(start 101.375 147.475)
		(end 101.375 147.675)
		(width 0.1)
		(layer "B.Cu")
		(net 165)
	)
	(segment
		(start 101.075 146.86)
		(end 101.075 147.175)
		(width 0.1)
		(layer "B.Cu")
		(net 165)
	)
	(segment
		(start 101.075 147.175)
		(end 101.375 147.475)
		(width 0.1)
		(layer "B.Cu")
		(net 165)
	)
	(segment
		(start 101.537603 140.440641)
		(end 101.523154 140.45509)
		(width 0.1)
		(layer "In2.Cu")
		(net 165)
	)
	(segment
		(start 101.557512 139.583744)
		(end 101.555225 139.60405)
		(width 0.1)
		(layer "In2.Cu")
		(net 165)
	)
	(segment
		(start 101.120235 140.672492)
		(end 101.142488 140.675)
		(width 0.1)
		(layer "In2.Cu")
		(net 165)
	)
	(segment
		(start 101.505851 139.665962)
		(end 101.486563 139.672712)
		(width 0.1)
		(layer "In2.Cu")
		(net 165)
	)
	(segment
		(start 101.548475 140.326661)
		(end 101.555225 140.345949)
		(width 0.1)
		(layer "In2.Cu")
		(net 165)
	)
	(segment
		(start 101.537603 139.909358)
		(end 101.548475 139.926661)
		(width 0.1)
		(layer "In2.Cu")
		(net 165)
	)
	(segment
		(start 101.120235 140.477507)
		(end 101.099099 140.484903)
		(width 0.1)
		(layer "In2.Cu")
		(net 165)
	)
	(segment
		(start 101.080139 140.096816)
		(end 101.064304 140.112651)
		(width 0.1)
		(layer "In2.Cu")
		(net 165)
	)
	(segment
		(start 101.052391 139.331611)
		(end 101.044995 139.352747)
		(width 0.1)
		(layer "In2.Cu")
		(net 165)
	)
	(segment
		(start 101.044995 138.952747)
		(end 101.042488 138.975)
		(width 0.1)
		(layer "In2.Cu")
		(net 165)
	)
	(segment
		(start 101.505851 139.084037)
		(end 101.523154 139.094909)
		(width 0.1)
		(layer "In2.Cu")
		(net 165)
	)
	(segment
		(start 101.042488 138.975)
		(end 101.044995 138.997252)
		(width 0.1)
		(layer "In2.Cu")
		(net 165)
	)
	(segment
		(start 101.044995 140.152747)
		(end 101.042488 140.175)
		(width 0.1)
		(layer "In2.Cu")
		(net 165)
	)
	(segment
		(start 101.120235 140.077507)
		(end 101.099099 140.084903)
		(width 0.1)
		(layer "In2.Cu")
		(net 165)
	)
	(segment
		(start 101.044995 140.197252)
		(end 101.052391 140.218388)
		(width 0.1)
		(layer "In2.Cu")
		(net 165)
	)
	(segment
		(start 101.080139 139.453183)
		(end 101.099099 139.465096)
		(width 0.1)
		(layer "In2.Cu")
		(net 165)
	)
	(segment
		(start 101.052391 139.018388)
		(end 101.064304 139.037348)
		(width 0.1)
		(layer "In2.Cu")
		(net 165)
	)
	(segment
		(start 101.318388 140.684903)
		(end 101.337348 140.696816)
		(width 0.1)
		(layer "In2.Cu")
		(net 165)
	)
	(segment
		(start 101.365096 140.731611)
		(end 101.372492 140.752747)
		(width 0.1)
		(layer "In2.Cu")
		(net 165)
	)
	(segment
		(start 101.523154 139.094909)
		(end 101.537603 139.109358)
		(width 0.1)
		(layer "In2.Cu")
		(net 165)
	)
	(segment
		(start 101.466256 139.475)
		(end 101.486563 139.477287)
		(width 0.1)
		(layer "In2.Cu")
		(net 165)
	)
	(segment
		(start 101.120235 139.872492)
		(end 101.142488 139.875)
		(width 0.1)
		(layer "In2.Cu")
		(net 165)
	)
	(segment
		(start 101.555225 139.60405)
		(end 101.548475 139.623338)
		(width 0.1)
		(layer "In2.Cu")
		(net 165)
	)
	(segment
		(start 101.548475 139.223338)
		(end 101.537603 139.240641)
		(width 0.1)
		(layer "In2.Cu")
		(net 165)
	)
	(segment
		(start 101.466256 140.075)
		(end 101.142488 140.075)
		(width 0.1)
		(layer "In2.Cu")
		(net 165)
	)
	(segment
		(start 101.052391 139.418388)
		(end 101.064304 139.437348)
		(width 0.1)
		(layer "In2.Cu")
		(net 165)
	)
	(segment
		(start 101.099099 138.884903)
		(end 101.080139 138.896816)
		(width 0.1)
		(layer "In2.Cu")
		(net 165)
	)
	(segment
		(start 101.523154 139.25509)
		(end 101.505851 139.265962)
		(width 0.1)
		(layer "In2.Cu")
		(net 165)
	)
	(segment
		(start 101.505851 139.265962)
		(end 101.486563 139.272712)
		(width 0.1)
		(layer "In2.Cu")
		(net 165)
	)
	(segment
		(start 101.044995 140.597252)
		(end 101.052391 140.618388)
		(width 0.1)
		(layer "In2.Cu")
		(net 165)
	)
	(segment
		(start 101.372492 140.752747)
		(end 101.375 140.775)
		(width 0.1)
		(layer "In2.Cu")
		(net 165)
	)
	(segment
		(start 101.486563 140.072712)
		(end 101.466256 140.075)
		(width 0.1)
		(layer "In2.Cu")
		(net 165)
	)
	(segment
		(start 101.523154 140.294909)
		(end 101.537603 140.309358)
		(width 0.1)
		(layer "In2.Cu")
		(net 165)
	)
	(segment
		(start 101.099099 140.084903)
		(end 101.080139 140.096816)
		(width 0.1)
		(layer "In2.Cu")
		(net 165)
	)
	(segment
		(start 101.275 138.875)
		(end 101.142488 138.875)
		(width 0.1)
		(layer "In2.Cu")
		(net 165)
	)
	(segment
		(start 101.523154 140.45509)
		(end 101.505851 140.465962)
		(width 0.1)
		(layer "In2.Cu")
		(net 165)
	)
	(segment
		(start 101.080139 140.653183)
		(end 101.099099 140.665096)
		(width 0.1)
		(layer "In2.Cu")
		(net 165)
	)
	(segment
		(start 101.099099 139.284903)
		(end 101.080139 139.296816)
		(width 0.1)
		(layer "In2.Cu")
		(net 165)
	)
	(segment
		(start 101.044995 138.997252)
		(end 101.052391 139.018388)
		(width 0.1)
		(layer "In2.Cu")
		(net 165)
	)
	(segment
		(start 101.555225 139.945949)
		(end 101.557512 139.966256)
		(width 0.1)
		(layer "In2.Cu")
		(net 165)
	)
	(segment
		(start 101.523154 139.494909)
		(end 101.537603 139.509358)
		(width 0.1)
		(layer "In2.Cu")
		(net 165)
	)
	(segment
		(start 101.099099 140.265096)
		(end 101.120235 140.272492)
		(width 0.1)
		(layer "In2.Cu")
		(net 165)
	)
	(segment
		(start 101.557512 140.383744)
		(end 101.555225 140.40405)
		(width 0.1)
		(layer "In2.Cu")
		(net 165)
	)
	(segment
		(start 101.505851 140.465962)
		(end 101.486563 140.472712)
		(width 0.1)
		(layer "In2.Cu")
		(net 165)
	)
	(segment
		(start 101.505851 140.284037)
		(end 101.523154 140.294909)
		(width 0.1)
		(layer "In2.Cu")
		(net 165)
	)
	(segment
		(start 101.142488 139.275)
		(end 101.120235 139.277507)
		(width 0.1)
		(layer "In2.Cu")
		(net 165)
	)
	(segment
		(start 101.142488 138.875)
		(end 101.120235 138.877507)
		(width 0.1)
		(layer "In2.Cu")
		(net 165)
	)
	(segment
		(start 101.375 131.128553)
		(end 101.375 138.775)
		(width 0.1)
		(layer "In2.Cu")
		(net 165)
	)
	(segment
		(start 101.142488 139.875)
		(end 101.466256 139.875)
		(width 0.1)
		(layer "In2.Cu")
		(net 165)
	)
	(segment
		(start 101.486563 139.477287)
		(end 101.505851 139.484037)
		(width 0.1)
		(layer "In2.Cu")
		(net 165)
	)
	(segment
		(start 101.466256 140.475)
		(end 101.142488 140.475)
		(width 0.1)
		(layer "In2.Cu")
		(net 165)
	)
	(segment
		(start 101.548475 139.623338)
		(end 101.537603 139.640641)
		(width 0.1)
		(layer "In2.Cu")
		(net 165)
	)
	(segment
		(start 101.537603 140.309358)
		(end 101.548475 140.326661)
		(width 0.1)
		(layer "In2.Cu")
		(net 165)
	)
	(segment
		(start 101.042488 139.775)
		(end 101.044995 139.797252)
		(width 0.1)
		(layer "In2.Cu")
		(net 165)
	)
	(segment
		(start 101.486563 140.277287)
		(end 101.505851 140.284037)
		(width 0.1)
		(layer "In2.Cu")
		(net 165)
	)
	(segment
		(start 101.080139 139.296816)
		(end 101.064304 139.312651)
		(width 0.1)
		(layer "In2.Cu")
		(net 165)
	)
	(segment
		(start 101.080139 139.853183)
		(end 101.099099 139.865096)
		(width 0.1)
		(layer "In2.Cu")
		(net 165)
	)
	(segment
		(start 101.120235 139.277507)
		(end 101.099099 139.284903)
		(width 0.1)
		(layer "In2.Cu")
		(net 165)
	)
	(segment
		(start 101.297252 138.872492)
		(end 101.275 138.875)
		(width 0.1)
		(layer "In2.Cu")
		(net 165)
	)
	(segment
		(start 101.353183 138.837348)
		(end 101.337348 138.853183)
		(width 0.1)
		(layer "In2.Cu")
		(net 165)
	)
	(segment
		(start 101.080139 139.696816)
		(end 101.064304 139.712651)
		(width 0.1)
		(layer "In2.Cu")
		(net 165)
	)
	(segment
		(start 101.080139 140.253183)
		(end 101.099099 140.265096)
		(width 0.1)
		(layer "In2.Cu")
		(net 165)
	)
	(segment
		(start 101.555225 140.345949)
		(end 101.557512 140.366256)
		(width 0.1)
		(layer "In2.Cu")
		(net 165)
	)
	(segment
		(start 101.555225 139.145949)
		(end 101.557512 139.166256)
		(width 0.1)
		(layer "In2.Cu")
		(net 165)
	)
	(segment
		(start 101.142488 140.475)
		(end 101.120235 140.477507)
		(width 0.1)
		(layer "In2.Cu")
		(net 165)
	)
	(segment
		(start 101.537603 139.109358)
		(end 101.548475 139.126661)
		(width 0.1)
		(layer "In2.Cu")
		(net 165)
	)
	(segment
		(start 101.548475 139.526661)
		(end 101.555225 139.545949)
		(width 0.1)
		(layer "In2.Cu")
		(net 165)
	)
	(segment
		(start 101.486563 139.672712)
		(end 101.466256 139.675)
		(width 0.1)
		(layer "In2.Cu")
		(net 165)
	)
	(segment
		(start 101.548475 140.023338)
		(end 101.537603 140.040641)
		(width 0.1)
		(layer "In2.Cu")
		(net 165)
	)
	(segment
		(start 101.044995 139.352747)
		(end 101.042488 139.375)
		(width 0.1)
		(layer "In2.Cu")
		(net 165)
	)
	(segment
		(start 101.375 140.775)
		(end 101.375 141.575)
		(width 0.1)
		(layer "In2.Cu")
		(net 165)
	)
	(segment
		(start 101.064304 139.712651)
		(end 101.052391 139.731611)
		(width 0.1)
		(layer "In2.Cu")
		(net 165)
	)
	(segment
		(start 101.080139 140.496816)
		(end 101.064304 140.512651)
		(width 0.1)
		(layer "In2.Cu")
		(net 165)
	)
	(segment
		(start 101.044995 139.797252)
		(end 101.052391 139.818388)
		(width 0.1)
		(layer "In2.Cu")
		(net 165)
	)
	(segment
		(start 101.548475 139.926661)
		(end 101.555225 139.945949)
		(width 0.1)
		(layer "In2.Cu")
		(net 165)
	)
	(segment
		(start 101.466256 139.075)
		(end 101.486563 139.077287)
		(width 0.1)
		(layer "In2.Cu")
		(net 165)
	)
	(segment
		(start 101.052391 139.731611)
		(end 101.044995 139.752747)
		(width 0.1)
		(layer "In2.Cu")
		(net 165)
	)
	(segment
		(start 101.466256 139.675)
		(end 101.142488 139.675)
		(width 0.1)
		(layer "In2.Cu")
		(net 165)
	)
	(segment
		(start 101.120235 138.877507)
		(end 101.099099 138.884903)
		(width 0.1)
		(layer "In2.Cu")
		(net 165)
	)
	(segment
		(start 101.297252 140.677507)
		(end 101.318388 140.684903)
		(width 0.1)
		(layer "In2.Cu")
		(net 165)
	)
	(segment
		(start 101.275 140.675)
		(end 101.297252 140.677507)
		(width 0.1)
		(layer "In2.Cu")
		(net 165)
	)
	(segment
		(start 101.099099 140.665096)
		(end 101.120235 140.672492)
		(width 0.1)
		(layer "In2.Cu")
		(net 165)
	)
	(segment
		(start 101.044995 139.752747)
		(end 101.042488 139.775)
		(width 0.1)
		(layer "In2.Cu")
		(net 165)
	)
	(segment
		(start 101.099099 139.684903)
		(end 101.080139 139.696816)
		(width 0.1)
		(layer "In2.Cu")
		(net 165)
	)
	(segment
		(start 101.486563 139.877287)
		(end 101.505851 139.884037)
		(width 0.1)
		(layer "In2.Cu")
		(net 165)
	)
	(segment
		(start 101.548475 139.126661)
		(end 101.555225 139.145949)
		(width 0.1)
		(layer "In2.Cu")
		(net 165)
	)
	(segment
		(start 101.523154 140.05509)
		(end 101.505851 140.065962)
		(width 0.1)
		(layer "In2.Cu")
		(net 165)
	)
	(segment
		(start 101.064304 139.437348)
		(end 101.080139 139.453183)
		(width 0.1)
		(layer "In2.Cu")
		(net 165)
	)
	(segment
		(start 101.486563 139.077287)
		(end 101.505851 139.084037)
		(width 0.1)
		(layer "In2.Cu")
		(net 165)
	)
	(segment
		(start 101.044995 139.397252)
		(end 101.052391 139.418388)
		(width 0.1)
		(layer "In2.Cu")
		(net 165)
	)
	(segment
		(start 101.548475 140.423338)
		(end 101.537603 140.440641)
		(width 0.1)
		(layer "In2.Cu")
		(net 165)
	)
	(segment
		(start 101.557512 139.983744)
		(end 101.555225 140.00405)
		(width 0.1)
		(layer "In2.Cu")
		(net 165)
	)
	(segment
		(start 101.275 131.028553)
		(end 101.375 131.128553)
		(width 0.1)
		(layer "In2.Cu")
		(net 165)
	)
	(segment
		(start 101.099099 139.465096)
		(end 101.120235 139.472492)
		(width 0.1)
		(layer "In2.Cu")
		(net 165)
	)
	(segment
		(start 101.537603 139.240641)
		(end 101.523154 139.25509)
		(width 0.1)
		(layer "In2.Cu")
		(net 165)
	)
	(segment
		(start 101.365096 138.818388)
		(end 101.353183 138.837348)
		(width 0.1)
		(layer "In2.Cu")
		(net 165)
	)
	(segment
		(start 101.337348 140.696816)
		(end 101.353183 140.712651)
		(width 0.1)
		(layer "In2.Cu")
		(net 165)
	)
	(segment
		(start 101.052391 138.931611)
		(end 101.044995 138.952747)
		(width 0.1)
		(layer "In2.Cu")
		(net 165)
	)
	(segment
		(start 100.975022 147.075022)
		(end 101.374999 147.474999)
		(width 0.1)
		(layer "In2.Cu")
		(net 165)
	)
	(segment
		(start 101.064304 139.837348)
		(end 101.080139 139.853183)
		(width 0.1)
		(layer "In2.Cu")
		(net 165)
	)
	(segment
		(start 101.537603 139.509358)
		(end 101.548475 139.526661)
		(width 0.1)
		(layer "In2.Cu")
		(net 165)
	)
	(segment
		(start 101.052391 140.218388)
		(end 101.064304 140.237348)
		(width 0.1)
		(layer "In2.Cu")
		(net 165)
	)
	(segment
		(start 101.099099 139.865096)
		(end 101.120235 139.872492)
		(width 0.1)
		(layer "In2.Cu")
		(net 165)
	)
	(segment
		(start 101.555225 139.20405)
		(end 101.548475 139.223338)
		(width 0.1)
		(layer "In2.Cu")
		(net 165)
	)
	(segment
		(start 101.523154 139.65509)
		(end 101.505851 139.665962)
		(width 0.1)
		(layer "In2.Cu")
		(net 165)
	)
	(segment
		(start 101.505851 139.884037)
		(end 101.523154 139.894909)
		(width 0.1)
		(layer "In2.Cu")
		(net 165)
	)
	(segment
		(start 101.557512 139.566256)
		(end 101.557512 139.583744)
		(width 0.1)
		(layer "In2.Cu")
		(net 165)
	)
	(segment
		(start 101.466256 139.275)
		(end 101.142488 139.275)
		(width 0.1)
		(layer "In2.Cu")
		(net 165)
	)
	(segment
		(start 101.044995 140.552747)
		(end 101.042488 140.575)
		(width 0.1)
		(layer "In2.Cu")
		(net 165)
	)
	(segment
		(start 101.353183 140.712651)
		(end 101.365096 140.731611)
		(width 0.1)
		(layer "In2.Cu")
		(net 165)
	)
	(segment
		(start 101.375 138.775)
		(end 101.372492 138.797252)
		(width 0.1)
		(layer "In2.Cu")
		(net 165)
	)
	(segment
		(start 101.042488 140.175)
		(end 101.044995 140.197252)
		(width 0.1)
		(layer "In2.Cu")
		(net 165)
	)
	(segment
		(start 101.537603 139.640641)
		(end 101.523154 139.65509)
		(width 0.1)
		(layer "In2.Cu")
		(net 165)
	)
	(segment
		(start 101.486563 140.472712)
		(end 101.466256 140.475)
		(width 0.1)
		(layer "In2.Cu")
		(net 165)
	)
	(segment
		(start 101.099099 139.065096)
		(end 101.120235 139.072492)
		(width 0.1)
		(layer "In2.Cu")
		(net 165)
	)
	(segment
		(start 101.318388 138.865096)
		(end 101.297252 138.872492)
		(width 0.1)
		(layer "In2.Cu")
		(net 165)
	)
	(segment
		(start 101.042488 139.375)
		(end 101.044995 139.397252)
		(width 0.1)
		(layer "In2.Cu")
		(net 165)
	)
	(segment
		(start 101.064304 138.912651)
		(end 101.052391 138.931611)
		(width 0.1)
		(layer "In2.Cu")
		(net 165)
	)
	(segment
		(start 101.052391 140.531611)
		(end 101.044995 140.552747)
		(width 0.1)
		(layer "In2.Cu")
		(net 165)
	)
	(segment
		(start 101.466256 139.875)
		(end 101.486563 139.877287)
		(width 0.1)
		(layer "In2.Cu")
		(net 165)
	)
	(segment
		(start 101.557512 139.166256)
		(end 101.557512 139.183744)
		(width 0.1)
		(layer "In2.Cu")
		(net 165)
	)
	(segment
		(start 101.275 130.675)
		(end 101.275 131.028553)
		(width 0.1)
		(layer "In2.Cu")
		(net 165)
	)
	(segment
		(start 101.557512 139.183744)
		(end 101.555225 139.20405)
		(width 0.1)
		(layer "In2.Cu")
		(net 165)
	)
	(segment
		(start 101.064304 139.037348)
		(end 101.080139 139.053183)
		(width 0.1)
		(layer "In2.Cu")
		(net 165)
	)
	(segment
		(start 101.120235 140.272492)
		(end 101.142488 140.275)
		(width 0.1)
		(layer "In2.Cu")
		(net 165)
	)
	(segment
		(start 101.142488 139.675)
		(end 101.120235 139.677507)
		(width 0.1)
		(layer "In2.Cu")
		(net 165)
	)
	(segment
		(start 101.064304 140.512651)
		(end 101.052391 140.531611)
		(width 0.1)
		(layer "In2.Cu")
		(net 165)
	)
	(segment
		(start 101.375 141.575)
		(end 100.975022 141.974978)
		(width 0.1)
		(layer "In2.Cu")
		(net 165)
	)
	(segment
		(start 101.374999 147.474999)
		(end 101.374999 147.574999)
		(width 0.1)
		(layer "In2.Cu")
		(net 165)
	)
	(segment
		(start 101.099099 140.484903)
		(end 101.080139 140.496816)
		(width 0.1)
		(layer "In2.Cu")
		(net 165)
	)
	(segment
		(start 101.486563 139.272712)
		(end 101.466256 139.275)
		(width 0.1)
		(layer "In2.Cu")
		(net 165)
	)
	(segment
		(start 101.064304 139.312651)
		(end 101.052391 139.331611)
		(width 0.1)
		(layer "In2.Cu")
		(net 165)
	)
	(segment
		(start 101.505851 140.065962)
		(end 101.486563 140.072712)
		(width 0.1)
		(layer "In2.Cu")
		(net 165)
	)
	(segment
		(start 101.142488 139.075)
		(end 101.466256 139.075)
		(width 0.1)
		(layer "In2.Cu")
		(net 165)
	)
	(segment
		(start 100.975022 141.974978)
		(end 100.975022 147.075022)
		(width 0.1)
		(layer "In2.Cu")
		(net 165)
	)
	(segment
		(start 101.555225 139.545949)
		(end 101.557512 139.566256)
		(width 0.1)
		(layer "In2.Cu")
		(net 165)
	)
	(segment
		(start 101.052391 140.131611)
		(end 101.044995 140.152747)
		(width 0.1)
		(layer "In2.Cu")
		(net 165)
	)
	(segment
		(start 101.142488 140.075)
		(end 101.120235 140.077507)
		(width 0.1)
		(layer "In2.Cu")
		(net 165)
	)
	(segment
		(start 101.042488 140.575)
		(end 101.044995 140.597252)
		(width 0.1)
		(layer "In2.Cu")
		(net 165)
	)
	(segment
		(start 101.557512 139.966256)
		(end 101.557512 139.983744)
		(width 0.1)
		(layer "In2.Cu")
		(net 165)
	)
	(segment
		(start 101.120235 139.472492)
		(end 101.142488 139.475)
		(width 0.1)
		(layer "In2.Cu")
		(net 165)
	)
	(segment
		(start 101.052391 140.618388)
		(end 101.064304 140.637348)
		(width 0.1)
		(layer "In2.Cu")
		(net 165)
	)
	(segment
		(start 101.142488 140.275)
		(end 101.466256 140.275)
		(width 0.1)
		(layer "In2.Cu")
		(net 165)
	)
	(segment
		(start 101.555225 140.40405)
		(end 101.548475 140.423338)
		(width 0.1)
		(layer "In2.Cu")
		(net 165)
	)
	(segment
		(start 101.466256 140.275)
		(end 101.486563 140.277287)
		(width 0.1)
		(layer "In2.Cu")
		(net 165)
	)
	(segment
		(start 101.555225 140.00405)
		(end 101.548475 140.023338)
		(width 0.1)
		(layer "In2.Cu")
		(net 165)
	)
	(segment
		(start 101.557512 140.366256)
		(end 101.557512 140.383744)
		(width 0.1)
		(layer "In2.Cu")
		(net 165)
	)
	(segment
		(start 101.523154 139.894909)
		(end 101.537603 139.909358)
		(width 0.1)
		(layer "In2.Cu")
		(net 165)
	)
	(segment
		(start 101.372492 138.797252)
		(end 101.365096 138.818388)
		(width 0.1)
		(layer "In2.Cu")
		(net 165)
	)
	(segment
		(start 101.537603 140.040641)
		(end 101.523154 140.05509)
		(width 0.1)
		(layer "In2.Cu")
		(net 165)
	)
	(segment
		(start 101.064304 140.237348)
		(end 101.080139 140.253183)
		(width 0.1)
		(layer "In2.Cu")
		(net 165)
	)
	(segment
		(start 101.052391 139.818388)
		(end 101.064304 139.837348)
		(width 0.1)
		(layer "In2.Cu")
		(net 165)
	)
	(segment
		(start 101.064304 140.112651)
		(end 101.052391 140.131611)
		(width 0.1)
		(layer "In2.Cu")
		(net 165)
	)
	(segment
		(start 101.142488 140.675)
		(end 101.275 140.675)
		(width 0.1)
		(layer "In2.Cu")
		(net 165)
	)
	(segment
		(start 101.080139 138.896816)
		(end 101.064304 138.912651)
		(width 0.1)
		(layer "In2.Cu")
		(net 165)
	)
	(segment
		(start 101.120235 139.072492)
		(end 101.142488 139.075)
		(width 0.1)
		(layer "In2.Cu")
		(net 165)
	)
	(segment
		(start 101.142488 139.475)
		(end 101.466256 139.475)
		(width 0.1)
		(layer "In2.Cu")
		(net 165)
	)
	(segment
		(start 101.505851 139.484037)
		(end 101.523154 139.494909)
		(width 0.1)
		(layer "In2.Cu")
		(net 165)
	)
	(segment
		(start 101.064304 140.637348)
		(end 101.080139 140.653183)
		(width 0.1)
		(layer "In2.Cu")
		(net 165)
	)
	(segment
		(start 101.120235 139.677507)
		(end 101.099099 139.684903)
		(width 0.1)
		(layer "In2.Cu")
		(net 165)
	)
	(segment
		(start 101.080139 139.053183)
		(end 101.099099 139.065096)
		(width 0.1)
		(layer "In2.Cu")
		(net 165)
	)
	(segment
		(start 101.337348 138.853183)
		(end 101.318388 138.865096)
		(width 0.1)
		(layer "In2.Cu")
		(net 165)
	)
	(segment
		(start 99.375 148.775)
		(end 99.375 148.175)
		(width 0.1)
		(layer "F.Cu")
		(net 166)
	)
	(segment
		(start 99.775 128.175)
		(end 99.275 128.675)
		(width 0.15)
		(layer "F.Cu")
		(net 166)
	)
	(segment
		(start 99.275 128.675)
		(end 99.274978 128.675)
		(width 0.15)
		(layer "F.Cu")
		(net 166)
	)
	(via
		(at 99.375 148.175)
		(size 0.5)
		(drill 0.2)
		(layers "F.Cu" "B.Cu")
		(net 166)
	)
	(via blind
		(at 99.274978 128.675)
		(size 0.5)
		(drill 0.2)
		(layers "F.Cu" "In2.Cu")
		(net 166)
	)
	(segment
		(start 98.375 148.575)
		(end 98.175 148.775)
		(width 0.1)
		(layer "B.Cu")
		(net 166)
	)
	(segment
		(start 98.975 148.575)
		(end 98.375 148.575)
		(width 0.1)
		(layer "B.Cu")
		(net 166)
	)
	(segment
		(start 98.175 148.775)
		(end 98.175 149.19)
		(width 0.1)
		(layer "B.Cu")
		(net 166)
	)
	(segment
		(start 99.375 148.175)
		(end 98.975 148.575)
		(width 0.1)
		(layer "B.Cu")
		(net 166)
	)
	(segment
		(start 98.774978 129.075012)
		(end 99.17499 128.675)
		(width 0.1)
		(layer "In2.Cu")
		(net 166)
	)
	(segment
		(start 99.375 148.175)
		(end 98.375 147.175)
		(width 0.1)
		(layer "In2.Cu")
		(net 166)
	)
	(segment
		(start 98.375 147.175)
		(end 98.375 130.266979)
		(width 0.1)
		(layer "In2.Cu")
		(net 166)
	)
	(segment
		(start 98.375 130.266979)
		(end 98.774978 129.867001)
		(width 0.1)
		(layer "In2.Cu")
		(net 166)
	)
	(segment
		(start 98.774978 129.867001)
		(end 98.774978 129.075012)
		(width 0.1)
		(layer "In2.Cu")
		(net 166)
	)
	(segment
		(start 103.775 130.175)
		(end 104.275 129.675)
		(width 0.15)
		(layer "F.Cu")
		(net 167)
	)
	(segment
		(start 102.575 149.575)
		(end 102.975 149.975)
		(width 0.1)
		(layer "F.Cu")
		(net 167)
	)
	(segment
		(start 102.975 149.975)
		(end 103.493002 149.975)
		(width 0.1)
		(layer "F.Cu")
		(net 167)
	)
	(segment
		(start 103.493002 149.975)
		(end 103.775 149.693002)
		(width 0.1)
		(layer "F.Cu")
		(net 167)
	)
	(segment
		(start 103.775 149.693002)
		(end 103.775 147.675)
		(width 0.1)
		(layer "F.Cu")
		(net 167)
	)
	(via blind
		(at 104.275 129.675)
		(size 0.5)
		(drill 0.2)
		(layers "F.Cu" "In2.Cu")
		(net 167)
	)
	(via
		(at 103.775 147.675)
		(size 0.5)
		(drill 0.2)
		(layers "F.Cu" "B.Cu")
		(net 167)
	)
	(segment
		(start 103.775 146.775)
		(end 104.575 145.975)
		(width 0.1)
		(layer "B.Cu")
		(net 167)
	)
	(segment
		(start 104.575 145.975)
		(end 104.575 145.66)
		(width 0.1)
		(layer "B.Cu")
		(net 167)
	)
	(segment
		(start 104.575 145.975)
		(end 104.575 145.96)
		(width 0.1)
		(layer "B.Cu")
		(net 167)
	)
	(segment
		(start 103.775 147.675)
		(end 103.775 146.775)
		(width 0.1)
		(layer "B.Cu")
		(net 167)
	)
	(segment
		(start 104.571179 134.475)
		(end 104.568672 134.497252)
		(width 0.1)
		(layer "In2.Cu")
		(net 167)
	)
	(segment
		(start 104.10022 135.538068)
		(end 104.115752 135.5536)
		(width 0.1)
		(layer "In2.Cu")
		(net 167)
	)
	(segment
		(start 104.471179 134.775)
		(end 104.493432 134.777507)
		(width 0.1)
		(layer "In2.Cu")
		(net 167)
	)
	(segment
		(start 104.514568 135.184903)
		(end 104.533528 135.196816)
		(width 0.1)
		(layer "In2.Cu")
		(net 167)
	)
	(segment
		(start 104.533528 135.353183)
		(end 104.514568 135.365096)
		(width 0.1)
		(layer "In2.Cu")
		(net 167)
	)
	(segment
		(start 104.10022 134.336157)
		(end 104.115752 134.351689)
		(width 0.1)
		(layer "In2.Cu")
		(net 167)
	)
	(segment
		(start 104.078821 134.673089)
		(end 104.078821 134.676911)
		(width 0.1)
		(layer "In2.Cu")
		(net 167)
	)
	(segment
		(start 104.514568 134.965096)
		(end 104.493432 134.972492)
		(width 0.1)
		(layer "In2.Cu")
		(net 167)
	)
	(segment
		(start 104.471179 134.375)
		(end 104.493432 134.377507)
		(width 0.1)
		(layer "In2.Cu")
		(net 167)
	)
	(segment
		(start 104.238068 134.151689)
		(end 104.21947 134.163375)
		(width 0.1)
		(layer "In2.Cu")
		(net 167)
	)
	(segment
		(start 104.493432 134.972492)
		(end 104.471179 134.975)
		(width 0.1)
		(layer "In2.Cu")
		(net 167)
	)
	(segment
		(start 104.115752 135.396399)
		(end 104.10022 135.411931)
		(width 0.1)
		(layer "In2.Cu")
		(net 167)
	)
	(segment
		(start 104.13435 134.363375)
		(end 104.155083 134.370629)
		(width 0.1)
		(layer "In2.Cu")
		(net 167)
	)
	(segment
		(start 104.078821 134.676911)
		(end 104.08128 134.698737)
		(width 0.1)
		(layer "In2.Cu")
		(net 167)
	)
	(segment
		(start 104.568672 134.452747)
		(end 104.571179 134.475)
		(width 0.1)
		(layer "In2.Cu")
		(net 167)
	)
	(segment
		(start 104.561276 135.318388)
		(end 104.549363 135.337348)
		(width 0.1)
		(layer "In2.Cu")
		(net 167)
	)
	(segment
		(start 104.275 130.075)
		(end 104.475 130.275)
		(width 0.1)
		(layer "In2.Cu")
		(net 167)
	)
	(segment
		(start 104.561276 135.231611)
		(end 104.568672 135.252747)
		(width 0.1)
		(layer "In2.Cu")
		(net 167)
	)
	(segment
		(start 104.155083 135.17254)
		(end 104.17691 135.175)
		(width 0.1)
		(layer "In2.Cu")
		(net 167)
	)
	(segment
		(start 104.549363 134.937348)
		(end 104.533528 134.953183)
		(width 0.1)
		(layer "In2.Cu")
		(net 167)
	)
	(segment
		(start 104.115752 134.194488)
		(end 104.10022 134.21002)
		(width 0.1)
		(layer "In2.Cu")
		(net 167)
	)
	(segment
		(start 104.265286 134.117559)
		(end 104.2536 134.136157)
		(width 0.1)
		(layer "In2.Cu")
		(net 167)
	)
	(segment
		(start 104.088534 135.430529)
		(end 104.08128 135.451262)
		(width 0.1)
		(layer "In2.Cu")
		(net 167)
	)
	(segment
		(start 104.2536 135.611931)
		(end 104.265286 135.630529)
		(width 0.1)
		(layer "In2.Cu")
		(net 167)
	)
	(segment
		(start 104.471179 135.175)
		(end 104.493432 135.177507)
		(width 0.1)
		(layer "In2.Cu")
		(net 167)
	)
	(segment
		(start 104.13435 134.765286)
		(end 104.155083 134.77254)
		(width 0.1)
		(layer "In2.Cu")
		(net 167)
	)
	(segment
		(start 104.475 133.575)
		(end 104.275 133.775)
		(width 0.1)
		(layer "In2.Cu")
		(net 167)
	)
	(segment
		(start 104.17691 135.175)
		(end 104.471179 135.175)
		(width 0.1)
		(layer "In2.Cu")
		(net 167)
	)
	(segment
		(start 104.275 134.375)
		(end 104.471179 134.375)
		(width 0.1)
		(layer "In2.Cu")
		(net 167)
	)
	(segment
		(start 104.27254 135.651262)
		(end 104.275 135.673089)
		(width 0.1)
		(layer "In2.Cu")
		(net 167)
	)
	(segment
		(start 104.568672 135.252747)
		(end 104.571179 135.275)
		(width 0.1)
		(layer "In2.Cu")
		(net 167)
	)
	(segment
		(start 104.13435 134.584713)
		(end 104.115752 134.596399)
		(width 0.1)
		(layer "In2.Cu")
		(net 167)
	)
	(segment
		(start 104.078821 135.476911)
		(end 104.08128 135.498737)
		(width 0.1)
		(layer "In2.Cu")
		(net 167)
	)
	(segment
		(start 104.155083 135.57254)
		(end 104.198737 135.577459)
		(width 0.1)
		(layer "In2.Cu")
		(net 167)
	)
	(segment
		(start 104.561276 134.431611)
		(end 104.568672 134.452747)
		(width 0.1)
		(layer "In2.Cu")
		(net 167)
	)
	(segment
		(start 104.08128 135.051262)
		(end 104.078821 135.073089)
		(width 0.1)
		(layer "In2.Cu")
		(net 167)
	)
	(segment
		(start 104.10022 135.011931)
		(end 104.088534 135.030529)
		(width 0.1)
		(layer "In2.Cu")
		(net 167)
	)
	(segment
		(start 104.08128 134.296826)
		(end 104.088534 134.317559)
		(width 0.1)
		(layer "In2.Cu")
		(net 167)
	)
	(segment
		(start 104.533528 135.196816)
		(end 104.549363 135.212651)
		(width 0.1)
		(layer "In2.Cu")
		(net 167)
	)
	(segment
		(start 104.155083 134.977459)
		(end 104.13435 134.984713)
		(width 0.1)
		(layer "In2.Cu")
		(net 167)
	)
	(segment
		(start 104.471179 134.575)
		(end 104.17691 134.575)
		(width 0.1)
		(layer "In2.Cu")
		(net 167)
	)
	(segment
		(start 104.471179 134.975)
		(end 104.17691 134.975)
		(width 0.1)
		(layer "In2.Cu")
		(net 167)
	)
	(segment
		(start 104.471179 135.375)
		(end 104.17691 135.375)
		(width 0.1)
		(layer "In2.Cu")
		(net 167)
	)
	(segment
		(start 104.08128 135.451262)
		(end 104.078821 135.473089)
		(width 0.1)
		(layer "In2.Cu")
		(net 167)
	)
	(segment
		(start 104.27254 134.096826)
		(end 104.265286 134.117559)
		(width 0.1)
		(layer "In2.Cu")
		(net 167)
	)
	(segment
		(start 104.475 146.975)
		(end 103.775 147.675)
		(width 0.1)
		(layer "In2.Cu")
		(net 167)
	)
	(segment
		(start 104.155083 134.175548)
		(end 104.13435 134.182802)
		(width 0.1)
		(layer "In2.Cu")
		(net 167)
	)
	(segment
		(start 104.088534 134.630529)
		(end 104.08128 134.651262)
		(width 0.1)
		(layer "In2.Cu")
		(net 167)
	)
	(segment
		(start 104.533528 134.396816)
		(end 104.549363 134.412651)
		(width 0.1)
		(layer "In2.Cu")
		(net 167)
	)
	(segment
		(start 104.115752 134.351689)
		(end 104.13435 134.363375)
		(width 0.1)
		(layer "In2.Cu")
		(net 167)
	)
	(segment
		(start 104.514568 135.365096)
		(end 104.493432 135.372492)
		(width 0.1)
		(layer "In2.Cu")
		(net 167)
	)
	(segment
		(start 104.176911 134.373089)
		(end 104.275 134.373089)
		(width 0.1)
		(layer "In2.Cu")
		(net 167)
	)
	(segment
		(start 104.265286 135.630529)
		(end 104.27254 135.651262)
		(width 0.1)
		(layer "In2.Cu")
		(net 167)
	)
	(segment
		(start 104.13435 134.182802)
		(end 104.115752 134.194488)
		(width 0.1)
		(layer "In2.Cu")
		(net 167)
	)
	(segment
		(start 104.13435 134.984713)
		(end 104.115752 134.996399)
		(width 0.1)
		(layer "In2.Cu")
		(net 167)
	)
	(segment
		(start 104.088534 134.317559)
		(end 104.10022 134.336157)
		(width 0.1)
		(layer "In2.Cu")
		(net 167)
	)
	(segment
		(start 104.13435 135.384713)
		(end 104.115752 135.396399)
		(width 0.1)
		(layer "In2.Cu")
		(net 167)
	)
	(segment
		(start 104.514568 134.384903)
		(end 104.533528 134.396816)
		(width 0.1)
		(layer "In2.Cu")
		(net 167)
	)
	(segment
		(start 104.475 130.275)
		(end 104.475 133.575)
		(width 0.1)
		(layer "In2.Cu")
		(net 167)
	)
	(segment
		(start 104.493432 135.177507)
		(end 104.514568 135.184903)
		(width 0.1)
		(layer "In2.Cu")
		(net 167)
	)
	(segment
		(start 104.078821 134.271178)
		(end 104.078821 134.275)
		(width 0.1)
		(layer "In2.Cu")
		(net 167)
	)
	(segment
		(start 104.08128 134.249351)
		(end 104.078821 134.271178)
		(width 0.1)
		(layer "In2.Cu")
		(net 167)
	)
	(segment
		(start 104.549363 134.537348)
		(end 104.533528 134.553183)
		(width 0.1)
		(layer "In2.Cu")
		(net 167)
	)
	(segment
		(start 104.088534 134.71947)
		(end 104.10022 134.738068)
		(width 0.1)
		(layer "In2.Cu")
		(net 167)
	)
	(segment
		(start 104.08128 135.098737)
		(end 104.088534 135.11947)
		(width 0.1)
		(layer "In2.Cu")
		(net 167)
	)
	(segment
		(start 104.275 133.775)
		(end 104.275 134.075)
		(width 0.1)
		(layer "In2.Cu")
		(net 167)
	)
	(segment
		(start 104.275 134.373089)
		(end 104.275 134.375)
		(width 0.1)
		(layer "In2.Cu")
		(net 167)
	)
	(segment
		(start 104.08128 134.698737)
		(end 104.088534 134.71947)
		(width 0.1)
		(layer "In2.Cu")
		(net 167)
	)
	(segment
		(start 104.115752 134.596399)
		(end 104.10022 134.611931)
		(width 0.1)
		(layer "In2.Cu")
		(net 167)
	)
	(segment
		(start 104.568672 134.852747)
		(end 104.571179 134.875)
		(width 0.1)
		(layer "In2.Cu")
		(net 167)
	)
	(segment
		(start 104.078821 135.076911)
		(end 104.08128 135.098737)
		(width 0.1)
		(layer "In2.Cu")
		(net 167)
	)
	(segment
		(start 104.533528 134.796816)
		(end 104.549363 134.812651)
		(width 0.1)
		(layer "In2.Cu")
		(net 167)
	)
	(segment
		(start 104.571179 135.275)
		(end 104.568672 135.297252)
		(width 0.1)
		(layer "In2.Cu")
		(net 167)
	)
	(segment
		(start 104.561276 134.831611)
		(end 104.568672 134.852747)
		(width 0.1)
		(layer "In2.Cu")
		(net 167)
	)
	(segment
		(start 104.238068 135.596399)
		(end 104.2536 135.611931)
		(width 0.1)
		(layer "In2.Cu")
		(net 167)
	)
	(segment
		(start 104.21947 135.584713)
		(end 104.238068 135.596399)
		(width 0.1)
		(layer "In2.Cu")
		(net 167)
	)
	(segment
		(start 104.533528 134.953183)
		(end 104.514568 134.965096)
		(width 0.1)
		(layer "In2.Cu")
		(net 167)
	)
	(segment
		(start 104.155083 134.577459)
		(end 104.13435 134.584713)
		(width 0.1)
		(layer "In2.Cu")
		(net 167)
	)
	(segment
		(start 104.198737 135.577459)
		(end 104.21947 135.584713)
		(width 0.1)
		(layer "In2.Cu")
		(net 167)
	)
	(segment
		(start 104.2536 134.136157)
		(end 104.238068 134.151689)
		(width 0.1)
		(layer "In2.Cu")
		(net 167)
	)
	(segment
		(start 104.17691 135.375)
		(end 104.155083 135.377459)
		(width 0.1)
		(layer "In2.Cu")
		(net 167)
	)
	(segment
		(start 104.08128 134.651262)
		(end 104.078821 134.673089)
		(width 0.1)
		(layer "In2.Cu")
		(net 167)
	)
	(segment
		(start 104.10022 134.21002)
		(end 104.088534 134.228618)
		(width 0.1)
		(layer "In2.Cu")
		(net 167)
	)
	(segment
		(start 104.088534 135.030529)
		(end 104.08128 135.051262)
		(width 0.1)
		(layer "In2.Cu")
		(net 167)
	)
	(segment
		(start 104.514568 134.784903)
		(end 104.533528 134.796816)
		(width 0.1)
		(layer "In2.Cu")
		(net 167)
	)
	(segment
		(start 104.10022 134.738068)
		(end 104.115752 134.7536)
		(width 0.1)
		(layer "In2.Cu")
		(net 167)
	)
	(segment
		(start 104.155083 135.377459)
		(end 104.13435 135.384713)
		(width 0.1)
		(layer "In2.Cu")
		(net 167)
	)
	(segment
		(start 104.493432 134.777507)
		(end 104.514568 134.784903)
		(width 0.1)
		(layer "In2.Cu")
		(net 167)
	)
	(segment
		(start 104.549363 135.212651)
		(end 104.561276 135.231611)
		(width 0.1)
		(layer "In2.Cu")
		(net 167)
	)
	(segment
		(start 104.571179 134.875)
		(end 104.568672 134.897252)
		(width 0.1)
		(layer "In2.Cu")
		(net 167)
	)
	(segment
		(start 104.549363 135.337348)
		(end 104.533528 135.353183)
		(width 0.1)
		(layer "In2.Cu")
		(net 167)
	)
	(segment
		(start 104.275 134.075)
		(end 104.27254 134.096826)
		(width 0.1)
		(layer "In2.Cu")
		(net 167)
	)
	(segment
		(start 104.155083 134.77254)
		(end 104.17691 134.775)
		(width 0.1)
		(layer "In2.Cu")
		(net 167)
	)
	(segment
		(start 104.568672 135.297252)
		(end 104.561276 135.318388)
		(width 0.1)
		(layer "In2.Cu")
		(net 167)
	)
	(segment
		(start 104.078821 135.073089)
		(end 104.078821 135.076911)
		(width 0.1)
		(layer "In2.Cu")
		(net 167)
	)
	(segment
		(start 104.10022 135.138068)
		(end 104.115752 135.1536)
		(width 0.1)
		(layer "In2.Cu")
		(net 167)
	)
	(segment
		(start 104.475 140.775)
		(end 104.475 146.975)
		(width 0.1)
		(layer "In2.Cu")
		(net 167)
	)
	(segment
		(start 104.115752 134.996399)
		(end 104.10022 135.011931)
		(width 0.1)
		(layer "In2.Cu")
		(net 167)
	)
	(segment
		(start 104.088534 134.228618)
		(end 104.08128 134.249351)
		(width 0.1)
		(layer "In2.Cu")
		(net 167)
	)
	(segment
		(start 104.10022 135.411931)
		(end 104.088534 135.430529)
		(width 0.1)
		(layer "In2.Cu")
		(net 167)
	)
	(segment
		(start 104.088534 135.51947)
		(end 104.10022 135.538068)
		(width 0.1)
		(layer "In2.Cu")
		(net 167)
	)
	(segment
		(start 104.08128 135.498737)
		(end 104.088534 135.51947)
		(width 0.1)
		(layer "In2.Cu")
		(net 167)
	)
	(segment
		(start 104.17691 134.775)
		(end 104.471179 134.775)
		(width 0.1)
		(layer "In2.Cu")
		(net 167)
	)
	(segment
		(start 104.533528 134.553183)
		(end 104.514568 134.565096)
		(width 0.1)
		(layer "In2.Cu")
		(net 167)
	)
	(segment
		(start 104.561276 134.918388)
		(end 104.549363 134.937348)
		(width 0.1)
		(layer "In2.Cu")
		(net 167)
	)
	(segment
		(start 104.568672 134.897252)
		(end 104.561276 134.918388)
		(width 0.1)
		(layer "In2.Cu")
		(net 167)
	)
	(segment
		(start 104.115752 135.5536)
		(end 104.13435 135.565286)
		(width 0.1)
		(layer "In2.Cu")
		(net 167)
	)
	(segment
		(start 104.493432 134.572492)
		(end 104.471179 134.575)
		(width 0.1)
		(layer "In2.Cu")
		(net 167)
	)
	(segment
		(start 104.17691 134.575)
		(end 104.155083 134.577459)
		(width 0.1)
		(layer "In2.Cu")
		(net 167)
	)
	(segment
		(start 104.088534 135.11947)
		(end 104.10022 135.138068)
		(width 0.1)
		(layer "In2.Cu")
		(net 167)
	)
	(segment
		(start 104.13435 135.565286)
		(end 104.155083 135.57254)
		(width 0.1)
		(layer "In2.Cu")
		(net 167)
	)
	(segment
		(start 104.155083 134.370629)
		(end 104.176911 134.373089)
		(width 0.1)
		(layer "In2.Cu")
		(net 167)
	)
	(segment
		(start 104.549363 134.812651)
		(end 104.561276 134.831611)
		(width 0.1)
		(layer "In2.Cu")
		(net 167)
	)
	(segment
		(start 104.561276 134.518388)
		(end 104.549363 134.537348)
		(width 0.1)
		(layer "In2.Cu")
		(net 167)
	)
	(segment
		(start 104.514568 134.565096)
		(end 104.493432 134.572492)
		(width 0.1)
		(layer "In2.Cu")
		(net 167)
	)
	(segment
		(start 104.275 140.575)
		(end 104.475 140.775)
		(width 0.1)
		(layer "In2.Cu")
		(net 167)
	)
	(segment
		(start 104.549363 134.412651)
		(end 104.561276 134.431611)
		(width 0.1)
		(layer "In2.Cu")
		(net 167)
	)
	(segment
		(start 104.13435 135.165286)
		(end 104.155083 135.17254)
		(width 0.1)
		(layer "In2.Cu")
		(net 167)
	)
	(segment
		(start 104.275 129.675)
		(end 104.275 130.075)
		(width 0.1)
		(layer "In2.Cu")
		(net 167)
	)
	(segment
		(start 104.198737 134.170629)
		(end 104.155083 134.175548)
		(width 0.1)
		(layer "In2.Cu")
		(net 167)
	)
	(segment
		(start 104.493432 134.377507)
		(end 104.514568 134.384903)
		(width 0.1)
		(layer "In2.Cu")
		(net 167)
	)
	(segment
		(start 104.115752 134.7536)
		(end 104.13435 134.765286)
		(width 0.1)
		(layer "In2.Cu")
		(net 167)
	)
	(segment
		(start 104.10022 134.611931)
		(end 104.088534 134.630529)
		(width 0.1)
		(layer "In2.Cu")
		(net 167)
	)
	(segment
		(start 104.17691 134.975)
		(end 104.155083 134.977459)
		(width 0.1)
		(layer "In2.Cu")
		(net 167)
	)
	(segment
		(start 104.275 135.673089)
		(end 104.275 140.575)
		(width 0.1)
		(layer "In2.Cu")
		(net 167)
	)
	(segment
		(start 104.493432 135.372492)
		(end 104.471179 135.375)
		(width 0.1)
		(layer "In2.Cu")
		(net 167)
	)
	(segment
		(start 104.078821 134.275)
		(end 104.08128 134.296826)
		(width 0.1)
		(layer "In2.Cu")
		(net 167)
	)
	(segment
		(start 104.21947 134.163375)
		(end 104.198737 134.170629)
		(width 0.1)
		(layer "In2.Cu")
		(net 167)
	)
	(segment
		(start 104.568672 134.497252)
		(end 104.561276 134.518388)
		(width 0.1)
		(layer "In2.Cu")
		(net 167)
	)
	(segment
		(start 104.115752 135.1536)
		(end 104.13435 135.165286)
		(width 0.1)
		(layer "In2.Cu")
		(net 167)
	)
	(segment
		(start 104.078821 135.473089)
		(end 104.078821 135.476911)
		(width 0.1)
		(layer "In2.Cu")
		(net 167)
	)
	(segment
		(start 91.775 111.175)
		(end 91.275 110.675)
		(width 0.15)
		(layer "F.Cu")
		(net 168)
	)
	(segment
		(start 77.265 164.93)
		(end 77.265 164.35)
		(width 0.15)
		(layer "F.Cu")
		(net 168)
	)
	(segment
		(start 74.74 162.84)
		(end 75.615 163.715)
		(width 0.15)
		(layer "F.Cu")
		(net 168)
	)
	(segment
		(start 74.74 162.545)
		(end 74.74 162.84)
		(width 0.15)
		(layer "F.Cu")
		(net 168)
	)
	(segment
		(start 77.265 164.35)
		(end 76.63 163.715)
		(width 0.15)
		(layer "F.Cu")
		(net 168)
	)
	(segment
		(start 76.63 163.715)
		(end 75.615 163.715)
		(width 0.15)
		(layer "F.Cu")
		(net 168)
	)
	(via blind
		(at 91.275 110.675)
		(size 0.5)
		(drill 0.2)
		(layers "F.Cu" "In2.Cu")
		(net 168)
	)
	(via
		(at 75.615 163.715)
		(size 0.5)
		(drill 0.2)
		(layers "F.Cu" "B.Cu")
		(net 168)
	)
	(segment
		(start 75.465 160.331998)
		(end 75.465 163.565)
		(width 0.15)
		(layer "In2.Cu")
		(net 168)
	)
	(segment
		(start 78.674923 120.023633)
		(end 78.674923 157.122075)
		(width 0.15)
		(layer "In2.Cu")
		(net 168)
	)
	(segment
		(start 78.674923 157.122075)
		(end 75.465 160.331998)
		(width 0.15)
		(layer "In2.Cu")
		(net 168)
	)
	(segment
		(start 91.275 110.675)
		(end 88.023556 110.675)
		(width 0.15)
		(layer "In2.Cu")
		(net 168)
	)
	(segment
		(start 88.023556 110.675)
		(end 78.674923 120.023633)
		(width 0.15)
		(layer "In2.Cu")
		(net 168)
	)
	(segment
		(start 75.465 163.565)
		(end 75.615 163.715)
		(width 0.15)
		(layer "In2.Cu")
		(net 168)
	)
	(segment
		(start 76.765 164.93)
		(end 76.765 164.35)
		(width 0.15)
		(layer "F.Cu")
		(net 169)
	)
	(segment
		(start 73.74 162.545)
		(end 73.74 162.839998)
		(width 0.15)
		(layer "F.Cu")
		(net 169)
	)
	(segment
		(start 90.775 110.175)
		(end 90.275 109.675)
		(width 0.15)
		(layer "F.Cu")
		(net 169)
	)
	(segment
		(start 76.765 164.35)
		(end 76.579998 164.164998)
		(width 0.15)
		(layer "F.Cu")
		(net 169)
	)
	(segment
		(start 76.579998 164.164998)
		(end 75.065 164.164998)
		(width 0.15)
		(layer "F.Cu")
		(net 169)
	)
	(segment
		(start 73.74 162.839998)
		(end 75.065 164.164998)
		(width 0.15)
		(layer "F.Cu")
		(net 169)
	)
	(via blind
		(at 90.275 109.675)
		(size 0.5)
		(drill 0.2)
		(layers "F.Cu" "In2.Cu")
		(net 169)
	)
	(via
		(at 75.065 164.164998)
		(size 0.5)
		(drill 0.2)
		(layers "F.Cu" "B.Cu")
		(net 169)
	)
	(segment
		(start 78.374912 119.899366)
		(end 78.374912 156.736416)
		(width 0.15)
		(layer "In2.Cu")
		(net 169)
	)
	(segment
		(start 90.275 109.675)
		(end 88.599278 109.675)
		(width 0.15)
		(layer "In2.Cu")
		(net 169)
	)
	(segment
		(start 78.374912 156.736416)
		(end 75.015 160.096328)
		(width 0.15)
		(layer "In2.Cu")
		(net 169)
	)
	(segment
		(start 75.015 164.114998)
		(end 75.065 164.164998)
		(width 0.15)
		(layer "In2.Cu")
		(net 169)
	)
	(segment
		(start 88.599278 109.675)
		(end 78.374912 119.899366)
		(width 0.15)
		(layer "In2.Cu")
		(net 169)
	)
	(segment
		(start 75.015 160.096328)
		(end 75.015 164.114998)
		(width 0.15)
		(layer "In2.Cu")
		(net 169)
	)
	(segment
		(start 78.265 164.115)
		(end 77.515 163.365)
		(width 0.15)
		(layer "F.Cu")
		(net 170)
	)
	(segment
		(start 78.265 164.93)
		(end 78.265 164.115)
		(width 0.15)
		(layer "F.Cu")
		(net 170)
	)
	(segment
		(start 76.74 162.59)
		(end 77.515 163.365)
		(width 0.15)
		(layer "F.Cu")
		(net 170)
	)
	(segment
		(start 95.775 111.175)
		(end 95.275 110.675)
		(width 0.15)
		(layer "F.Cu")
		(net 170)
	)
	(segment
		(start 76.74 162.545)
		(end 76.74 162.59)
		(width 0.15)
		(layer "F.Cu")
		(net 170)
	)
	(via
		(at 77.515 163.365)
		(size 0.5)
		(drill 0.2)
		(layers "F.Cu" "B.Cu")
		(net 170)
	)
	(via blind
		(at 95.275 110.675)
		(size 0.5)
		(drill 0.2)
		(layers "F.Cu" "In2.Cu")
		(net 170)
	)
	(segment
		(start 91.950001 111.199999)
		(end 94.750001 111.199999)
		(width 0.15)
		(layer "In2.Cu")
		(net 170)
	)
	(segment
		(start 91.775 111.375)
		(end 91.950001 111.199999)
		(width 0.15)
		(layer "In2.Cu")
		(net 170)
	)
	(segment
		(start 88.205054 111.375)
		(end 91.775 111.375)
		(width 0.15)
		(layer "In2.Cu")
		(net 170)
	)
	(segment
		(start 79.274945 157.775055)
		(end 76.84 160.21)
		(width 0.15)
		(layer "In2.Cu")
		(net 170)
	)
	(segment
		(start 76.84 162.69)
		(end 77.515 163.365)
		(width 0.15)
		(layer "In2.Cu")
		(net 170)
	)
	(segment
		(start 79.274945 120.305109)
		(end 88.205054 111.375)
		(width 0.15)
		(layer "In2.Cu")
		(net 170)
	)
	(segment
		(start 76.84 160.21)
		(end 76.84 162.69)
		(width 0.15)
		(layer "In2.Cu")
		(net 170)
	)
	(segment
		(start 94.750001 111.199999)
		(end 95.275 110.675)
		(width 0.15)
		(layer "In2.Cu")
		(net 170)
	)
	(segment
		(start 79.274945 120.305109)
		(end 79.274945 157.775055)
		(width 0.15)
		(layer "In2.Cu")
		(net 170)
	)
	(segment
		(start 93.775 111.175)
		(end 93.412237 110.812237)
		(width 0.15)
		(layer "F.Cu")
		(net 171)
	)
	(segment
		(start 93.412237 110.812237)
		(end 93.412237 110.714358)
		(width 0.15)
		(layer "F.Cu")
		(net 171)
	)
	(segment
		(start 75.74 162.89)
		(end 76.115 163.265)
		(width 0.15)
		(layer "F.Cu")
		(net 171)
	)
	(segment
		(start 75.74 162.545)
		(end 75.74 162.89)
		(width 0.15)
		(layer "F.Cu")
		(net 171)
	)
	(segment
		(start 77.765 164.35)
		(end 76.68 163.265)
		(width 0.15)
		(layer "F.Cu")
		(net 171)
	)
	(segment
		(start 76.68 163.265)
		(end 76.115 163.265)
		(width 0.15)
		(layer "F.Cu")
		(net 171)
	)
	(segment
		(start 77.765 164.93)
		(end 77.765 164.35)
		(width 0.15)
		(layer "F.Cu")
		(net 171)
	)
	(via blind
		(at 93.412237 110.714358)
		(size 0.5)
		(drill 0.2)
		(layers "F.Cu" "In2.Cu")
		(net 171)
	)
	(via
		(at 76.115 163.265)
		(size 0.5)
		(drill 0.2)
		(layers "F.Cu" "B.Cu")
		(net 171)
	)
	(segment
		(start 78.974934 157.565076)
		(end 76.065 160.47501)
		(width 0.15)
		(layer "In2.Cu")
		(net 171)
	)
	(segment
		(start 76.065 160.47501)
		(end 76.065 163.215)
		(width 0.15)
		(layer "In2.Cu")
		(net 171)
	)
	(segment
		(start 78.974934 120.180836)
		(end 78.974934 157.565076)
		(width 0.15)
		(layer "In2.Cu")
		(net 171)
	)
	(segment
		(start 93.412237 110.714358)
		(end 91.923503 110.714358)
		(width 0.15)
		(layer "In2.Cu")
		(net 171)
	)
	(segment
		(start 91.923503 110.714358)
		(end 91.512861 111.125)
		(width 0.15)
		(layer "In2.Cu")
		(net 171)
	)
	(segment
		(start 91.512861 111.125)
		(end 88.03077 111.125)
		(width 0.15)
		(layer "In2.Cu")
		(net 171)
	)
	(segment
		(start 88.03077 111.125)
		(end 78.974934 120.180836)
		(width 0.15)
		(layer "In2.Cu")
		(net 171)
	)
	(segment
		(start 76.065 163.215)
		(end 76.115 163.265)
		(width 0.15)
		(layer "In2.Cu")
		(net 171)
	)
	(segment
		(start 95.775 112.175)
		(end 95.275 111.675)
		(width 0.15)
		(layer "F.Cu")
		(net 172)
	)
	(segment
		(start 78.74 163.19)
		(end 79.065 163.515)
		(width 0.15)
		(layer "F.Cu")
		(net 172)
	)
	(segment
		(start 79.265 164.93)
		(end 79.265 164.244004)
		(width 0.15)
		(layer "F.Cu")
		(net 172)
	)
	(segment
		(start 79.065 164.044004)
		(end 79.065 163.515)
		(width 0.15)
		(layer "F.Cu")
		(net 172)
	)
	(segment
		(start 79.265 164.244004)
		(end 79.065 164.044004)
		(width 0.15)
		(layer "F.Cu")
		(net 172)
	)
	(segment
		(start 78.74 162.545)
		(end 78.74 163.19)
		(width 0.15)
		(layer "F.Cu")
		(net 172)
	)
	(via blind
		(at 95.275 111.675)
		(size 0.5)
		(drill 0.2)
		(layers "F.Cu" "In2.Cu")
		(net 172)
	)
	(via
		(at 79.065 163.515)
		(size 0.5)
		(drill 0.2)
		(layers "F.Cu" "B.Cu")
		(net 172)
	)
	(segment
		(start 79.874967 120.55364)
		(end 79.874967 158.626476)
		(width 0.15)
		(layer "In2.Cu")
		(net 172)
	)
	(segment
		(start 92.925 111.675)
		(end 92.475 112.125)
		(width 0.15)
		(layer "In2.Cu")
		(net 172)
	)
	(segment
		(start 78.398709 160.102734)
		(end 78.398709 162.848709)
		(width 0.15)
		(layer "In2.Cu")
		(net 172)
	)
	(segment
		(start 79.874967 158.626476)
		(end 78.398709 160.102734)
		(width 0.15)
		(layer "In2.Cu")
		(net 172)
	)
	(segment
		(start 88.303607 112.125)
		(end 79.874967 120.55364)
		(width 0.15)
		(layer "In2.Cu")
		(net 172)
	)
	(segment
		(start 78.398709 162.848709)
		(end 79.065 163.515)
		(width 0.15)
		(layer "In2.Cu")
		(net 172)
	)
	(segment
		(start 92.475 112.125)
		(end 88.303607 112.125)
		(width 0.15)
		(layer "In2.Cu")
		(net 172)
	)
	(segment
		(start 95.275 111.675)
		(end 92.925 111.675)
		(width 0.15)
		(layer "In2.Cu")
		(net 172)
	)
	(segment
		(start 77.74 162.89)
		(end 78.365 163.515)
		(width 0.15)
		(layer "F.Cu")
		(net 173)
	)
	(segment
		(start 78.765 164.93)
		(end 78.765 163.915)
		(width 0.15)
		(layer "F.Cu")
		(net 173)
	)
	(segment
		(start 78.765 163.915)
		(end 78.365 163.515)
		(width 0.15)
		(layer "F.Cu")
		(net 173)
	)
	(segment
		(start 92.775 112.175)
		(end 92.275 111.675)
		(width 0.15)
		(layer "F.Cu")
		(net 173)
	)
	(segment
		(start 77.74 162.545)
		(end 77.74 162.89)
		(width 0.15)
		(layer "F.Cu")
		(net 173)
	)
	(via
		(at 78.365 163.515)
		(size 0.5)
		(drill 0.2)
		(layers "F.Cu" "B.Cu")
		(net 173)
	)
	(via blind
		(at 92.275 111.675)
		(size 0.5)
		(drill 0.2)
		(layers "F.Cu" "In2.Cu")
		(net 173)
	)
	(segment
		(start 77.74 162.89)
		(end 78.365 163.515)
		(width 0.15)
		(layer "In2.Cu")
		(net 173)
	)
	(segment
		(start 79.574956 120.429376)
		(end 88.329332 111.675)
		(width 0.15)
		(layer "In2.Cu")
		(net 173)
	)
	(segment
		(start 88.329332 111.675)
		(end 92.275 111.675)
		(width 0.15)
		(layer "In2.Cu")
		(net 173)
	)
	(segment
		(start 79.574956 120.429376)
		(end 79.574956 158.375044)
		(width 0.15)
		(layer "In2.Cu")
		(net 173)
	)
	(segment
		(start 79.574956 158.375044)
		(end 77.74 160.21)
		(width 0.15)
		(layer "In2.Cu")
		(net 173)
	)
	(segment
		(start 77.74 160.21)
		(end 77.74 162.89)
		(width 0.15)
		(layer "In2.Cu")
		(net 173)
	)
	(segment
		(start 80.315 163.915)
		(end 80.74 163.49)
		(width 0.15)
		(layer "F.Cu")
		(net 174)
	)
	(segment
		(start 80.2 164.03)
		(end 80.315 163.915)
		(width 0.15)
		(layer "F.Cu")
		(net 174)
	)
	(segment
		(start 80.74 163.49)
		(end 80.74 162.545)
		(width 0.15)
		(layer "F.Cu")
		(net 174)
	)
	(segment
		(start 95.775 113.175)
		(end 95.275 112.675)
		(width 0.15)
		(layer "F.Cu")
		(net 174)
	)
	(segment
		(start 80.2 165.865)
		(end 80.2 164.03)
		(width 0.15)
		(layer "F.Cu")
		(net 174)
	)
	(via blind
		(at 95.275 112.675)
		(size 0.5)
		(drill 0.2)
		(layers "F.Cu" "In2.Cu")
		(net 174)
	)
	(via
		(at 80.315 163.915)
		(size 0.5)
		(drill 0.2)
		(layers "F.Cu" "B.Cu")
		(net 174)
	)
	(segment
		(start 80.174978 158.750744)
		(end 80.174978 120.677908)
		(width 0.15)
		(layer "In2.Cu")
		(net 174)
	)
	(segment
		(start 79.276989 159.648733)
		(end 80.174978 158.750744)
		(width 0.15)
		(layer "In2.Cu")
		(net 174)
	)
	(segment
		(start 80.174978 120.677908)
		(end 88.477888 112.375)
		(width 0.15)
		(layer "In2.Cu")
		(net 174)
	)
	(segment
		(start 92.975 112.175)
		(end 94.775 112.175)
		(width 0.15)
		(layer "In2.Cu")
		(net 174)
	)
	(segment
		(start 79.276989 163.080983)
		(end 80.111006 163.915)
		(width 0.15)
		(layer "In2.Cu")
		(net 174)
	)
	(segment
		(start 92.774992 112.375008)
		(end 92.975 112.175)
		(width 0.15)
		(layer "In2.Cu")
		(net 174)
	)
	(segment
		(start 79.276989 159.648733)
		(end 79.276989 163.080983)
		(width 0.15)
		(layer "In2.Cu")
		(net 174)
	)
	(segment
		(start 80.111006 163.915)
		(end 80.315 163.915)
		(width 0.15)
		(layer "In2.Cu")
		(net 174)
	)
	(segment
		(start 88.477896 112.375008)
		(end 92.774992 112.375008)
		(width 0.15)
		(layer "In2.Cu")
		(net 174)
	)
	(segment
		(start 88.477888 112.375)
		(end 88.477896 112.375008)
		(width 0.15)
		(layer "In2.Cu")
		(net 174)
	)
	(segment
		(start 94.799999 112.199999)
		(end 95.275 112.675)
		(width 0.15)
		(layer "In2.Cu")
		(net 174)
	)
	(segment
		(start 93.775 112.175)
		(end 93.275 112.675)
		(width 0.15)
		(layer "F.Cu")
		(net 175)
	)
	(segment
		(start 79.765 164.93)
		(end 79.765 163.539992)
		(width 0.15)
		(layer "F.Cu")
		(net 175)
	)
	(segment
		(start 79.765 163.539992)
		(end 80.065 163.239992)
		(width 0.15)
		(layer "F.Cu")
		(net 175)
	)
	(segment
		(start 79.74 162.914992)
		(end 80.065 163.239992)
		(width 0.15)
		(layer "F.Cu")
		(net 175)
	)
	(segment
		(start 79.74 162.545)
		(end 79.74 162.914992)
		(width 0.15)
		(layer "F.Cu")
		(net 175)
	)
	(via blind
		(at 93.275 112.675)
		(size 0.5)
		(drill 0.2)
		(layers "F.Cu" "In2.Cu")
		(net 175)
	)
	(via
		(at 80.065 163.239992)
		(size 0.5)
		(drill 0.2)
		(layers "F.Cu" "B.Cu")
		(net 175)
	)
	(segment
		(start 93.275 112.675)
		(end 88.602166 112.675)
		(width 0.15)
		(layer "In2.Cu")
		(net 175)
	)
	(segment
		(start 80.474989 158.875011)
		(end 79.775 159.575)
		(width 0.15)
		(layer "In2.Cu")
		(net 175)
	)
	(segment
		(start 79.775 162.949992)
		(end 80.065 163.239992)
		(width 0.15)
		(layer "In2.Cu")
		(net 175)
	)
	(segment
		(start 79.775 159.575)
		(end 79.775 162.949992)
		(width 0.15)
		(layer "In2.Cu")
		(net 175)
	)
	(segment
		(start 80.474989 120.802176)
		(end 80.474989 158.875011)
		(width 0.15)
		(layer "In2.Cu")
		(net 175)
	)
	(segment
		(start 80.474989 120.802176)
		(end 88.602166 112.675)
		(width 0.15)
		(layer "In2.Cu")
		(net 175)
	)
	(segment
		(start 95.375 145.575)
		(end 95.375 146.141436)
		(width 0.1)
		(layer "F.Cu")
		(net 176)
	)
	(segment
		(start 96.775 128.175)
		(end 96.275 127.675)
		(width 0.15)
		(layer "F.Cu")
		(net 176)
	)
	(via blind
		(at 96.275 127.675)
		(size 0.5)
		(drill 0.2)
		(layers "F.Cu" "In2.Cu")
		(net 176)
	)
	(via blind
		(at 95.375 146.141436)
		(size 0.5)
		(drill 0.2)
		(layers "F.Cu" "In2.Cu")
		(net 176)
	)
	(segment
		(start 96.075 127.875)
		(end 96.275 127.675)
		(width 0.1)
		(layer "In2.Cu")
		(net 176)
	)
	(segment
		(start 95.375 146.141436)
		(end 95.375 145.575)
		(width 0.1)
		(layer "In2.Cu")
		(net 176)
	)
	(segment
		(start 95.375 145.575)
		(end 95.675 145.275)
		(width 0.1)
		(layer "In2.Cu")
		(net 176)
	)
	(segment
		(start 95.675 145.275)
		(end 95.675 128.275)
		(width 0.1)
		(layer "In2.Cu")
		(net 176)
	)
	(segment
		(start 95.675 128.275)
		(end 96.075 127.875)
		(width 0.1)
		(layer "In2.Cu")
		(net 176)
	)
	(segment
		(start 92.175 148.775)
		(end 92.175 148.175)
		(width 0.1)
		(layer "F.Cu")
		(net 177)
	)
	(segment
		(start 91.775 130.175)
		(end 92.275 130.675)
		(width 0.15)
		(layer "F.Cu")
		(net 177)
	)
	(via blind
		(at 92.175 148.175)
		(size 0.5)
		(drill 0.2)
		(layers "F.Cu" "In2.Cu")
		(net 177)
	)
	(via blind
		(at 92.275 130.675)
		(size 0.5)
		(drill 0.2)
		(layers "F.Cu" "In2.Cu")
		(net 177)
	)
	(segment
		(start 91.90553 132.372492)
		(end 91.927783 132.375)
		(width 0.1)
		(layer "In2.Cu")
		(net 177)
	)
	(segment
		(start 92.197252 132.377507)
		(end 92.218388 132.384903)
		(width 0.1)
		(layer "In2.Cu")
		(net 177)
	)
	(segment
		(start 92.420372 132.032228)
		(end 92.422217 132.048608)
		(width 0.1)
		(layer "In2.Cu")
		(net 177)
	)
	(segment
		(start 91.675 145.475)
		(end 91.675 146.675)
		(width 0.1)
		(layer "In2.Cu")
		(net 177)
	)
	(segment
		(start 91.865434 131.796816)
		(end 91.849599 131.812651)
		(width 0.1)
		(layer "In2.Cu")
		(net 177)
	)
	(segment
		(start 91.927783 131.775)
		(end 91.90553 131.777507)
		(width 0.1)
		(layer "In2.Cu")
		(net 177)
	)
	(segment
		(start 92.175 132.375)
		(end 92.197252 132.377507)
		(width 0.1)
		(layer "In2.Cu")
		(net 177)
	)
	(segment
		(start 91.83029 132.252747)
		(end 91.827783 132.275)
		(width 0.1)
		(layer "In2.Cu")
		(net 177)
	)
	(segment
		(start 92.394503 132.158941)
		(end 92.380547 132.16771)
		(width 0.1)
		(layer "In2.Cu")
		(net 177)
	)
	(segment
		(start 92.394503 131.991058)
		(end 92.406159 132.002714)
		(width 0.1)
		(layer "In2.Cu")
		(net 177)
	)
	(segment
		(start 92.265096 131.718388)
		(end 92.253183 131.737348)
		(width 0.1)
		(layer "In2.Cu")
		(net 177)
	)
	(segment
		(start 91.849599 132.212651)
		(end 91.837686 132.231611)
		(width 0.1)
		(layer "In2.Cu")
		(net 177)
	)
	(segment
		(start 92.406159 132.002714)
		(end 92.414928 132.01667)
		(width 0.1)
		(layer "In2.Cu")
		(net 177)
	)
	(segment
		(start 91.849599 131.937348)
		(end 91.865434 131.953183)
		(width 0.1)
		(layer "In2.Cu")
		(net 177)
	)
	(segment
		(start 92.275 131.675)
		(end 92.272492 131.697252)
		(width 0.1)
		(layer "In2.Cu")
		(net 177)
	)
	(segment
		(start 91.927783 131.975)
		(end 92.348609 131.975)
		(width 0.1)
		(layer "In2.Cu")
		(net 177)
	)
	(segment
		(start 91.83029 131.897252)
		(end 91.837686 131.918388)
		(width 0.1)
		(layer "In2.Cu")
		(net 177)
	)
	(segment
		(start 92.272492 132.452747)
		(end 92.275 132.475)
		(width 0.1)
		(layer "In2.Cu")
		(net 177)
	)
	(segment
		(start 92.275 144.875)
		(end 91.675 145.475)
		(width 0.1)
		(layer "In2.Cu")
		(net 177)
	)
	(segment
		(start 92.364989 132.173154)
		(end 92.348609 132.175)
		(width 0.1)
		(layer "In2.Cu")
		(net 177)
	)
	(segment
		(start 92.380547 132.16771)
		(end 92.364989 132.173154)
		(width 0.1)
		(layer "In2.Cu")
		(net 177)
	)
	(segment
		(start 91.83029 131.852747)
		(end 91.827783 131.875)
		(width 0.1)
		(layer "In2.Cu")
		(net 177)
	)
	(segment
		(start 91.83029 132.297252)
		(end 91.837686 132.318388)
		(width 0.1)
		(layer "In2.Cu")
		(net 177)
	)
	(segment
		(start 91.865434 132.353183)
		(end 91.884394 132.365096)
		(width 0.1)
		(layer "In2.Cu")
		(net 177)
	)
	(segment
		(start 91.675 146.675)
		(end 92.175 147.175)
		(width 0.1)
		(layer "In2.Cu")
		(net 177)
	)
	(segment
		(start 91.837686 131.918388)
		(end 91.849599 131.937348)
		(width 0.1)
		(layer "In2.Cu")
		(net 177)
	)
	(segment
		(start 92.414928 132.133329)
		(end 92.406159 132.147285)
		(width 0.1)
		(layer "In2.Cu")
		(net 177)
	)
	(segment
		(start 92.175 147.175)
		(end 92.175 148.175)
		(width 0.1)
		(layer "In2.Cu")
		(net 177)
	)
	(segment
		(start 92.422217 132.048608)
		(end 92.422217 132.101392)
		(width 0.1)
		(layer "In2.Cu")
		(net 177)
	)
	(segment
		(start 92.380547 131.982289)
		(end 92.394503 131.991058)
		(width 0.1)
		(layer "In2.Cu")
		(net 177)
	)
	(segment
		(start 91.90553 131.972492)
		(end 91.927783 131.975)
		(width 0.1)
		(layer "In2.Cu")
		(net 177)
	)
	(segment
		(start 92.348609 131.975)
		(end 92.364989 131.976845)
		(width 0.1)
		(layer "In2.Cu")
		(net 177)
	)
	(segment
		(start 91.884394 131.784903)
		(end 91.865434 131.796816)
		(width 0.1)
		(layer "In2.Cu")
		(net 177)
	)
	(segment
		(start 92.272492 131.697252)
		(end 92.265096 131.718388)
		(width 0.1)
		(layer "In2.Cu")
		(net 177)
	)
	(segment
		(start 92.237348 131.753183)
		(end 92.218388 131.765096)
		(width 0.1)
		(layer "In2.Cu")
		(net 177)
	)
	(segment
		(start 91.827783 131.875)
		(end 91.83029 131.897252)
		(width 0.1)
		(layer "In2.Cu")
		(net 177)
	)
	(segment
		(start 92.406159 132.147285)
		(end 92.394503 132.158941)
		(width 0.1)
		(layer "In2.Cu")
		(net 177)
	)
	(segment
		(start 91.865434 132.196816)
		(end 91.849599 132.212651)
		(width 0.1)
		(layer "In2.Cu")
		(net 177)
	)
	(segment
		(start 92.422217 132.101392)
		(end 92.420372 132.117771)
		(width 0.1)
		(layer "In2.Cu")
		(net 177)
	)
	(segment
		(start 91.837686 131.831611)
		(end 91.83029 131.852747)
		(width 0.1)
		(layer "In2.Cu")
		(net 177)
	)
	(segment
		(start 92.197252 131.772492)
		(end 92.175 131.775)
		(width 0.1)
		(layer "In2.Cu")
		(net 177)
	)
	(segment
		(start 91.927783 132.375)
		(end 92.175 132.375)
		(width 0.1)
		(layer "In2.Cu")
		(net 177)
	)
	(segment
		(start 92.253183 131.737348)
		(end 92.237348 131.753183)
		(width 0.1)
		(layer "In2.Cu")
		(net 177)
	)
	(segment
		(start 91.884394 131.965096)
		(end 91.90553 131.972492)
		(width 0.1)
		(layer "In2.Cu")
		(net 177)
	)
	(segment
		(start 92.414928 132.01667)
		(end 92.420372 132.032228)
		(width 0.1)
		(layer "In2.Cu")
		(net 177)
	)
	(segment
		(start 92.364989 131.976845)
		(end 92.380547 131.982289)
		(width 0.1)
		(layer "In2.Cu")
		(net 177)
	)
	(segment
		(start 92.175 131.775)
		(end 91.927783 131.775)
		(width 0.1)
		(layer "In2.Cu")
		(net 177)
	)
	(segment
		(start 91.90553 132.177507)
		(end 91.884394 132.184903)
		(width 0.1)
		(layer "In2.Cu")
		(net 177)
	)
	(segment
		(start 91.927783 132.175)
		(end 91.90553 132.177507)
		(width 0.1)
		(layer "In2.Cu")
		(net 177)
	)
	(segment
		(start 92.420372 132.117771)
		(end 92.414928 132.133329)
		(width 0.1)
		(layer "In2.Cu")
		(net 177)
	)
	(segment
		(start 92.218388 131.765096)
		(end 92.197252 131.772492)
		(width 0.1)
		(layer "In2.Cu")
		(net 177)
	)
	(segment
		(start 91.849599 131.812651)
		(end 91.837686 131.831611)
		(width 0.1)
		(layer "In2.Cu")
		(net 177)
	)
	(segment
		(start 92.218388 132.384903)
		(end 92.237348 132.396816)
		(width 0.1)
		(layer "In2.Cu")
		(net 177)
	)
	(segment
		(start 92.265096 132.431611)
		(end 92.272492 132.452747)
		(width 0.1)
		(layer "In2.Cu")
		(net 177)
	)
	(segment
		(start 91.837686 132.318388)
		(end 91.849599 132.337348)
		(width 0.1)
		(layer "In2.Cu")
		(net 177)
	)
	(segment
		(start 91.865434 131.953183)
		(end 91.884394 131.965096)
		(width 0.1)
		(layer "In2.Cu")
		(net 177)
	)
	(segment
		(start 91.827783 132.275)
		(end 91.83029 132.297252)
		(width 0.1)
		(layer "In2.Cu")
		(net 177)
	)
	(segment
		(start 91.884394 132.365096)
		(end 91.90553 132.372492)
		(width 0.1)
		(layer "In2.Cu")
		(net 177)
	)
	(segment
		(start 92.275 132.475)
		(end 92.275 144.875)
		(width 0.1)
		(layer "In2.Cu")
		(net 177)
	)
	(segment
		(start 92.275 130.675)
		(end 92.275 131.675)
		(width 0.1)
		(layer "In2.Cu")
		(net 177)
	)
	(segment
		(start 92.348609 132.175)
		(end 91.927783 132.175)
		(width 0.1)
		(layer "In2.Cu")
		(net 177)
	)
	(segment
		(start 91.849599 132.337348)
		(end 91.865434 132.353183)
		(width 0.1)
		(layer "In2.Cu")
		(net 177)
	)
	(segment
		(start 92.253183 132.412651)
		(end 92.265096 132.431611)
		(width 0.1)
		(layer "In2.Cu")
		(net 177)
	)
	(segment
		(start 91.884394 132.184903)
		(end 91.865434 132.196816)
		(width 0.1)
		(layer "In2.Cu")
		(net 177)
	)
	(segment
		(start 91.90553 131.777507)
		(end 91.884394 131.784903)
		(width 0.1)
		(layer "In2.Cu")
		(net 177)
	)
	(segment
		(start 91.837686 132.231611)
		(end 91.83029 132.252747)
		(width 0.1)
		(layer "In2.Cu")
		(net 177)
	)
	(segment
		(start 92.237348 132.396816)
		(end 92.253183 132.412651)
		(width 0.1)
		(layer "In2.Cu")
		(net 177)
	)
	(segment
		(start 92.175 149.575)
		(end 91.775 149.175)
		(width 0.1)
		(layer "F.Cu")
		(net 178)
	)
	(segment
		(start 91.775 149.175)
		(end 91.775 147.675)
		(width 0.1)
		(layer "F.Cu")
		(net 178)
	)
	(segment
		(start 90.775 130.175)
		(end 91.275 130.675)
		(width 0.15)
		(layer "F.Cu")
		(net 178)
	)
	(via blind
		(at 91.775 147.675)
		(size 0.5)
		(drill 0.2)
		(layers "F.Cu" "In5.Cu")
		(net 178)
	)
	(via blind
		(at 91.275 130.675)
		(size 0.5)
		(drill 0.2)
		(layers "F.Cu" "In5.Cu")
		(net 178)
	)
	(segment
		(start 91.775 131.175)
		(end 91.775 132.575)
		(width 0.1)
		(layer "In5.Cu")
		(net 178)
	)
	(segment
		(start 91.718388 132.884903)
		(end 91.737348 132.896816)
		(width 0.1)
		(layer "In5.Cu")
		(net 178)
	)
	(segment
		(start 91.235049 132.684903)
		(end 91.216089 132.696816)
		(width 0.1)
		(layer "In5.Cu")
		(net 178)
	)
	(segment
		(start 91.278438 132.875)
		(end 91.675 132.875)
		(width 0.1)
		(layer "In5.Cu")
		(net 178)
	)
	(segment
		(start 91.737348 132.653183)
		(end 91.718388 132.665096)
		(width 0.1)
		(layer "In5.Cu")
		(net 178)
	)
	(segment
		(start 91.235049 132.865096)
		(end 91.256185 132.872492)
		(width 0.1)
		(layer "In5.Cu")
		(net 178)
	)
	(segment
		(start 91.775 132.575)
		(end 91.772492 132.597252)
		(width 0.1)
		(layer "In5.Cu")
		(net 178)
	)
	(segment
		(start 91.697252 132.672492)
		(end 91.675 132.675)
		(width 0.1)
		(layer "In5.Cu")
		(net 178)
	)
	(segment
		(start 91.753183 132.637348)
		(end 91.737348 132.653183)
		(width 0.1)
		(layer "In5.Cu")
		(net 178)
	)
	(segment
		(start 91.718388 132.665096)
		(end 91.697252 132.672492)
		(width 0.1)
		(layer "In5.Cu")
		(net 178)
	)
	(segment
		(start 91.180945 132.752747)
		(end 91.178438 132.775)
		(width 0.1)
		(layer "In5.Cu")
		(net 178)
	)
	(segment
		(start 91.216089 132.696816)
		(end 91.200254 132.712651)
		(width 0.1)
		(layer "In5.Cu")
		(net 178)
	)
	(segment
		(start 91.188341 132.818388)
		(end 91.200254 132.837348)
		(width 0.1)
		(layer "In5.Cu")
		(net 178)
	)
	(segment
		(start 91.200254 132.712651)
		(end 91.188341 132.731611)
		(width 0.1)
		(layer "In5.Cu")
		(net 178)
	)
	(segment
		(start 91.188341 132.731611)
		(end 91.180945 132.752747)
		(width 0.1)
		(layer "In5.Cu")
		(net 178)
	)
	(segment
		(start 91.775 132.975)
		(end 91.775 147.675)
		(width 0.1)
		(layer "In5.Cu")
		(net 178)
	)
	(segment
		(start 91.765096 132.931611)
		(end 91.772492 132.952747)
		(width 0.1)
		(layer "In5.Cu")
		(net 178)
	)
	(segment
		(start 91.675 132.875)
		(end 91.697252 132.877507)
		(width 0.1)
		(layer "In5.Cu")
		(net 178)
	)
	(segment
		(start 91.772492 132.952747)
		(end 91.775 132.975)
		(width 0.1)
		(layer "In5.Cu")
		(net 178)
	)
	(segment
		(start 91.753183 132.912651)
		(end 91.765096 132.931611)
		(width 0.1)
		(layer "In5.Cu")
		(net 178)
	)
	(segment
		(start 91.772492 132.597252)
		(end 91.765096 132.618388)
		(width 0.1)
		(layer "In5.Cu")
		(net 178)
	)
	(segment
		(start 91.216089 132.853183)
		(end 91.235049 132.865096)
		(width 0.1)
		(layer "In5.Cu")
		(net 178)
	)
	(segment
		(start 91.675 132.675)
		(end 91.278438 132.675)
		(width 0.1)
		(layer "In5.Cu")
		(net 178)
	)
	(segment
		(start 91.178438 132.775)
		(end 91.180945 132.797252)
		(width 0.1)
		(layer "In5.Cu")
		(net 178)
	)
	(segment
		(start 91.737348 132.896816)
		(end 91.753183 132.912651)
		(width 0.1)
		(layer "In5.Cu")
		(net 178)
	)
	(segment
		(start 91.256185 132.677507)
		(end 91.235049 132.684903)
		(width 0.1)
		(layer "In5.Cu")
		(net 178)
	)
	(segment
		(start 91.697252 132.877507)
		(end 91.718388 132.884903)
		(width 0.1)
		(layer "In5.Cu")
		(net 178)
	)
	(segment
		(start 91.765096 132.618388)
		(end 91.753183 132.637348)
		(width 0.1)
		(layer "In5.Cu")
		(net 178)
	)
	(segment
		(start 91.275 130.675)
		(end 91.775 131.175)
		(width 0.1)
		(layer "In5.Cu")
		(net 178)
	)
	(segment
		(start 91.200254 132.837348)
		(end 91.216089 132.853183)
		(width 0.1)
		(layer "In5.Cu")
		(net 178)
	)
	(segment
		(start 91.278438 132.675)
		(end 91.256185 132.677507)
		(width 0.1)
		(layer "In5.Cu")
		(net 178)
	)
	(segment
		(start 91.256185 132.872492)
		(end 91.278438 132.875)
		(width 0.1)
		(layer "In5.Cu")
		(net 178)
	)
	(segment
		(start 91.180945 132.797252)
		(end 91.188341 132.818388)
		(width 0.1)
		(layer "In5.Cu")
		(net 178)
	)
	(segment
		(start 94.775 129.175)
		(end 94.275 128.675)
		(width 0.15)
		(layer "F.Cu")
		(net 179)
	)
	(segment
		(start 93.374998 145.174998)
		(end 93.374998 146.421443)
		(width 0.1)
		(layer "F.Cu")
		(net 179)
	)
	(segment
		(start 93.375002 146.421447)
		(end 93.375002 146.775)
		(width 0.1)
		(layer "F.Cu")
		(net 179)
	)
	(segment
		(start 92.975 144.775)
		(end 93.374998 145.174998)
		(width 0.1)
		(layer "F.Cu")
		(net 179)
	)
	(segment
		(start 93.374998 146.421443)
		(end 93.375002 146.421447)
		(width 0.1)
		(layer "F.Cu")
		(net 179)
	)
	(via blind
		(at 94.275 128.675)
		(size 0.5)
		(drill 0.2)
		(layers "F.Cu" "In2.Cu")
		(net 179)
	)
	(via blind
		(at 93.375002 146.775)
		(size 0.5)
		(drill 0.2)
		(layers "F.Cu" "In2.Cu")
		(net 179)
	)
	(segment
		(start 93.899688 134.766388)
		(end 93.881308 134.772819)
		(width 0.1)
		(layer "In2.Cu")
		(net 179)
	)
	(segment
		(start 93.675 134.375)
		(end 93.601084 134.375)
		(width 0.1)
		(layer "In2.Cu")
		(net 179)
	)
	(segment
		(start 93.929945 135.00774)
		(end 93.940305 135.024228)
		(width 0.1)
		(layer "In2.Cu")
		(net 179)
	)
	(segment
		(start 93.737348 135.396816)
		(end 93.753183 135.412651)
		(width 0.1)
		(layer "In2.Cu")
		(net 179)
	)
	(segment
		(start 93.578831 135.372492)
		(end 93.601084 135.375)
		(width 0.1)
		(layer "In2.Cu")
		(net 179)
	)
	(segment
		(start 93.940305 134.624228)
		(end 93.946736 134.642608)
		(width 0.1)
		(layer "In2.Cu")
		(net 179)
	)
	(segment
		(start 93.861958 134.575)
		(end 93.881308 134.57718)
		(width 0.1)
		(layer "In2.Cu")
		(net 179)
	)
	(segment
		(start 93.5229 134.937348)
		(end 93.538735 134.953183)
		(width 0.1)
		(layer "In2.Cu")
		(net 179)
	)
	(segment
		(start 93.538735 135.196816)
		(end 93.5229 135.212651)
		(width 0.1)
		(layer "In2.Cu")
		(net 179)
	)
	(segment
		(start 93.916176 134.756028)
		(end 93.899688 134.766388)
		(width 0.1)
		(layer "In2.Cu")
		(net 179)
	)
	(segment
		(start 93.929945 134.60774)
		(end 93.940305 134.624228)
		(width 0.1)
		(layer "In2.Cu")
		(net 179)
	)
	(segment
		(start 93.5229 135.212651)
		(end 93.510987 135.231611)
		(width 0.1)
		(layer "In2.Cu")
		(net 179)
	)
	(segment
		(start 93.940305 134.725771)
		(end 93.929945 134.742259)
		(width 0.1)
		(layer "In2.Cu")
		(net 179)
	)
	(segment
		(start 93.510987 134.431611)
		(end 93.503591 134.452747)
		(width 0.1)
		(layer "In2.Cu")
		(net 179)
	)
	(segment
		(start 93.775 135.475)
		(end 93.775 144.875)
		(width 0.1)
		(layer "In2.Cu")
		(net 179)
	)
	(segment
		(start 93.557695 134.384903)
		(end 93.538735 134.396816)
		(width 0.1)
		(layer "In2.Cu")
		(net 179)
	)
	(segment
		(start 93.538735 134.396816)
		(end 93.5229 134.412651)
		(width 0.1)
		(layer "In2.Cu")
		(net 179)
	)
	(segment
		(start 93.538735 134.953183)
		(end 93.557695 134.965096)
		(width 0.1)
		(layer "In2.Cu")
		(net 179)
	)
	(segment
		(start 93.772492 135.452747)
		(end 93.775 135.475)
		(width 0.1)
		(layer "In2.Cu")
		(net 179)
	)
	(segment
		(start 93.601084 134.975)
		(end 93.861958 134.975)
		(width 0.1)
		(layer "In2.Cu")
		(net 179)
	)
	(segment
		(start 93.948916 135.088042)
		(end 93.946736 135.107391)
		(width 0.1)
		(layer "In2.Cu")
		(net 179)
	)
	(segment
		(start 93.753183 134.337348)
		(end 93.737348 134.353183)
		(width 0.1)
		(layer "In2.Cu")
		(net 179)
	)
	(segment
		(start 93.916176 135.156028)
		(end 93.899688 135.166388)
		(width 0.1)
		(layer "In2.Cu")
		(net 179)
	)
	(segment
		(start 93.765096 135.431611)
		(end 93.772492 135.452747)
		(width 0.1)
		(layer "In2.Cu")
		(net 179)
	)
	(segment
		(start 93.929945 135.142259)
		(end 93.916176 135.156028)
		(width 0.1)
		(layer "In2.Cu")
		(net 179)
	)
	(segment
		(start 93.948916 134.661958)
		(end 93.948916 134.688042)
		(width 0.1)
		(layer "In2.Cu")
		(net 179)
	)
	(segment
		(start 93.881308 134.97718)
		(end 93.899688 134.983611)
		(width 0.1)
		(layer "In2.Cu")
		(net 179)
	)
	(segment
		(start 93.899688 134.583611)
		(end 93.916176 134.593971)
		(width 0.1)
		(layer "In2.Cu")
		(net 179)
	)
	(segment
		(start 93.861958 135.175)
		(end 93.601084 135.175)
		(width 0.1)
		(layer "In2.Cu")
		(net 179)
	)
	(segment
		(start 93.557695 134.784903)
		(end 93.538735 134.796816)
		(width 0.1)
		(layer "In2.Cu")
		(net 179)
	)
	(segment
		(start 93.501084 135.275)
		(end 93.503591 135.297252)
		(width 0.1)
		(layer "In2.Cu")
		(net 179)
	)
	(segment
		(start 93.503591 134.452747)
		(end 93.501084 134.475)
		(width 0.1)
		(layer "In2.Cu")
		(net 179)
	)
	(segment
		(start 93.916176 134.993971)
		(end 93.929945 135.00774)
		(width 0.1)
		(layer "In2.Cu")
		(net 179)
	)
	(segment
		(start 93.946736 135.042608)
		(end 93.948916 135.061958)
		(width 0.1)
		(layer "In2.Cu")
		(net 179)
	)
	(segment
		(start 93.899688 134.983611)
		(end 93.916176 134.993971)
		(width 0.1)
		(layer "In2.Cu")
		(net 179)
	)
	(segment
		(start 93.697252 134.372492)
		(end 93.675 134.375)
		(width 0.1)
		(layer "In2.Cu")
		(net 179)
	)
	(segment
		(start 93.601084 134.575)
		(end 93.861958 134.575)
		(width 0.1)
		(layer "In2.Cu")
		(net 179)
	)
	(segment
		(start 93.510987 135.231611)
		(end 93.503591 135.252747)
		(width 0.1)
		(layer "In2.Cu")
		(net 179)
	)
	(segment
		(start 93.940305 135.024228)
		(end 93.946736 135.042608)
		(width 0.1)
		(layer "In2.Cu")
		(net 179)
	)
	(segment
		(start 93.5229 135.337348)
		(end 93.538735 135.353183)
		(width 0.1)
		(layer "In2.Cu")
		(net 179)
	)
	(segment
		(start 93.538735 135.353183)
		(end 93.557695 135.365096)
		(width 0.1)
		(layer "In2.Cu")
		(net 179)
	)
	(segment
		(start 93.578831 135.177507)
		(end 93.557695 135.184903)
		(width 0.1)
		(layer "In2.Cu")
		(net 179)
	)
	(segment
		(start 93.916176 134.593971)
		(end 93.929945 134.60774)
		(width 0.1)
		(layer "In2.Cu")
		(net 179)
	)
	(segment
		(start 93.5229 134.537348)
		(end 93.538735 134.553183)
		(width 0.1)
		(layer "In2.Cu")
		(net 179)
	)
	(segment
		(start 93.881308 135.172819)
		(end 93.861958 135.175)
		(width 0.1)
		(layer "In2.Cu")
		(net 179)
	)
	(segment
		(start 93.861958 134.775)
		(end 93.601084 134.775)
		(width 0.1)
		(layer "In2.Cu")
		(net 179)
	)
	(segment
		(start 93.503591 134.852747)
		(end 93.501084 134.875)
		(width 0.1)
		(layer "In2.Cu")
		(net 179)
	)
	(segment
		(start 93.557695 135.184903)
		(end 93.538735 135.196816)
		(width 0.1)
		(layer "In2.Cu")
		(net 179)
	)
	(segment
		(start 93.501084 134.475)
		(end 93.503591 134.497252)
		(width 0.1)
		(layer "In2.Cu")
		(net 179)
	)
	(segment
		(start 93.753183 135.412651)
		(end 93.765096 135.431611)
		(width 0.1)
		(layer "In2.Cu")
		(net 179)
	)
	(segment
		(start 93.5229 134.812651)
		(end 93.510987 134.831611)
		(width 0.1)
		(layer "In2.Cu")
		(net 179)
	)
	(segment
		(start 93.737348 134.353183)
		(end 93.718388 134.365096)
		(width 0.1)
		(layer "In2.Cu")
		(net 179)
	)
	(segment
		(start 93.940305 135.125771)
		(end 93.929945 135.142259)
		(width 0.1)
		(layer "In2.Cu")
		(net 179)
	)
	(segment
		(start 93.538735 134.796816)
		(end 93.5229 134.812651)
		(width 0.1)
		(layer "In2.Cu")
		(net 179)
	)
	(segment
		(start 93.5229 134.412651)
		(end 93.510987 134.431611)
		(width 0.1)
		(layer "In2.Cu")
		(net 179)
	)
	(segment
		(start 93.718388 134.365096)
		(end 93.697252 134.372492)
		(width 0.1)
		(layer "In2.Cu")
		(net 179)
	)
	(segment
		(start 93.503591 134.897252)
		(end 93.510987 134.918388)
		(width 0.1)
		(layer "In2.Cu")
		(net 179)
	)
	(segment
		(start 93.578831 134.377507)
		(end 93.557695 134.384903)
		(width 0.1)
		(layer "In2.Cu")
		(net 179)
	)
	(segment
		(start 93.510987 135.318388)
		(end 93.5229 135.337348)
		(width 0.1)
		(layer "In2.Cu")
		(net 179)
	)
	(segment
		(start 93.510987 134.918388)
		(end 93.5229 134.937348)
		(width 0.1)
		(layer "In2.Cu")
		(net 179)
	)
	(segment
		(start 93.503591 134.497252)
		(end 93.510987 134.518388)
		(width 0.1)
		(layer "In2.Cu")
		(net 179)
	)
	(segment
		(start 93.601084 135.375)
		(end 93.675 135.375)
		(width 0.1)
		(layer "In2.Cu")
		(net 179)
	)
	(segment
		(start 93.578831 134.777507)
		(end 93.557695 134.784903)
		(width 0.1)
		(layer "In2.Cu")
		(net 179)
	)
	(segment
		(start 93.948916 134.688042)
		(end 93.946736 134.707391)
		(width 0.1)
		(layer "In2.Cu")
		(net 179)
	)
	(segment
		(start 93.772492 134.297252)
		(end 93.765096 134.318388)
		(width 0.1)
		(layer "In2.Cu")
		(net 179)
	)
	(segment
		(start 93.375 145.275)
		(end 93.375 146.775)
		(width 0.1)
		(layer "In2.Cu")
		(net 179)
	)
	(segment
		(start 93.503591 135.252747)
		(end 93.501084 135.275)
		(width 0.1)
		(layer "In2.Cu")
		(net 179)
	)
	(segment
		(start 93.578831 134.572492)
		(end 93.601084 134.575)
		(width 0.1)
		(layer "In2.Cu")
		(net 179)
	)
	(segment
		(start 93.697252 135.377507)
		(end 93.718388 135.384903)
		(width 0.1)
		(layer "In2.Cu")
		(net 179)
	)
	(segment
		(start 93.946736 134.642608)
		(end 93.948916 134.661958)
		(width 0.1)
		(layer "In2.Cu")
		(net 179)
	)
	(segment
		(start 93.765096 134.318388)
		(end 93.753183 134.337348)
		(width 0.1)
		(layer "In2.Cu")
		(net 179)
	)
	(segment
		(start 93.899688 135.166388)
		(end 93.881308 135.172819)
		(width 0.1)
		(layer "In2.Cu")
		(net 179)
	)
	(segment
		(start 93.578831 134.972492)
		(end 93.601084 134.975)
		(width 0.1)
		(layer "In2.Cu")
		(net 179)
	)
	(segment
		(start 93.881308 134.772819)
		(end 93.861958 134.775)
		(width 0.1)
		(layer "In2.Cu")
		(net 179)
	)
	(segment
		(start 93.775 134.275)
		(end 93.772492 134.297252)
		(width 0.1)
		(layer "In2.Cu")
		(net 179)
	)
	(segment
		(start 93.510987 134.518388)
		(end 93.5229 134.537348)
		(width 0.1)
		(layer "In2.Cu")
		(net 179)
	)
	(segment
		(start 93.675 135.375)
		(end 93.697252 135.377507)
		(width 0.1)
		(layer "In2.Cu")
		(net 179)
	)
	(segment
		(start 93.946736 135.107391)
		(end 93.940305 135.125771)
		(width 0.1)
		(layer "In2.Cu")
		(net 179)
	)
	(segment
		(start 93.601084 134.375)
		(end 93.578831 134.377507)
		(width 0.1)
		(layer "In2.Cu")
		(net 179)
	)
	(segment
		(start 93.501084 134.875)
		(end 93.503591 134.897252)
		(width 0.1)
		(layer "In2.Cu")
		(net 179)
	)
	(segment
		(start 93.538735 134.553183)
		(end 93.557695 134.565096)
		(width 0.1)
		(layer "In2.Cu")
		(net 179)
	)
	(segment
		(start 94.275 128.675)
		(end 93.775 129.175)
		(width 0.1)
		(layer "In2.Cu")
		(net 179)
	)
	(segment
		(start 93.946736 134.707391)
		(end 93.940305 134.725771)
		(width 0.1)
		(layer "In2.Cu")
		(net 179)
	)
	(segment
		(start 93.557695 134.965096)
		(end 93.578831 134.972492)
		(width 0.1)
		(layer "In2.Cu")
		(net 179)
	)
	(segment
		(start 93.510987 134.831611)
		(end 93.503591 134.852747)
		(width 0.1)
		(layer "In2.Cu")
		(net 179)
	)
	(segment
		(start 93.718388 135.384903)
		(end 93.737348 135.396816)
		(width 0.1)
		(layer "In2.Cu")
		(net 179)
	)
	(segment
		(start 93.557695 135.365096)
		(end 93.578831 135.372492)
		(width 0.1)
		(layer "In2.Cu")
		(net 179)
	)
	(segment
		(start 93.557695 134.565096)
		(end 93.578831 134.572492)
		(width 0.1)
		(layer "In2.Cu")
		(net 179)
	)
	(segment
		(start 93.775 129.175)
		(end 93.775 134.275)
		(width 0.1)
		(layer "In2.Cu")
		(net 179)
	)
	(segment
		(start 93.601084 135.175)
		(end 93.578831 135.177507)
		(width 0.1)
		(layer "In2.Cu")
		(net 179)
	)
	(segment
		(start 93.861958 134.975)
		(end 93.881308 134.97718)
		(width 0.1)
		(layer "In2.Cu")
		(net 179)
	)
	(segment
		(start 93.881308 134.57718)
		(end 93.899688 134.583611)
		(width 0.1)
		(layer "In2.Cu")
		(net 179)
	)
	(segment
		(start 93.601084 134.775)
		(end 93.578831 134.777507)
		(width 0.1)
		(layer "In2.Cu")
		(net 179)
	)
	(segment
		(start 93.503591 135.297252)
		(end 93.510987 135.318388)
		(width 0.1)
		(layer "In2.Cu")
		(net 179)
	)
	(segment
		(start 93.948916 135.061958)
		(end 93.948916 135.088042)
		(width 0.1)
		(layer "In2.Cu")
		(net 179)
	)
	(segment
		(start 93.775 144.875)
		(end 93.375 145.275)
		(width 0.1)
		(layer "In2.Cu")
		(net 179)
	)
	(segment
		(start 93.929945 134.742259)
		(end 93.916176 134.756028)
		(width 0.1)
		(layer "In2.Cu")
		(net 179)
	)
	(segment
		(start 93.775 148.775)
		(end 93.775 148.175)
		(width 0.1)
		(layer "F.Cu")
		(net 180)
	)
	(segment
		(start 91.775 129.175)
		(end 91.275 129.675)
		(width 0.15)
		(layer "F.Cu")
		(net 180)
	)
	(via blind
		(at 93.775 148.175)
		(size 0.5)
		(drill 0.2)
		(layers "F.Cu" "In5.Cu")
		(net 180)
	)
	(via blind
		(at 91.275 129.675)
		(size 0.5)
		(drill 0.2)
		(layers "F.Cu" "In5.Cu")
		(net 180)
	)
	(segment
		(start 92.372929 131.52181)
		(end 92.375 131.54019)
		(width 0.1)
		(layer "In5.Cu")
		(net 180)
	)
	(segment
		(start 92.328241 131.249415)
		(end 92.310784 131.255524)
		(width 0.1)
		(layer "In5.Cu")
		(net 180)
	)
	(segment
		(start 92.343902 131.475614)
		(end 92.35698 131.488692)
		(width 0.1)
		(layer "In5.Cu")
		(net 180)
	)
	(segment
		(start 92.217988 131.304353)
		(end 92.211879 131.32181)
		(width 0.1)
		(layer "In5.Cu")
		(net 180)
	)
	(segment
		(start 92.35698 131.488692)
		(end 92.36682 131.504353)
		(width 0.1)
		(layer "In5.Cu")
		(net 180)
	)
	(segment
		(start 92.256567 131.449415)
		(end 92.274024 131.455524)
		(width 0.1)
		(layer "In5.Cu")
		(net 180)
	)
	(segment
		(start 92.328241 131.465774)
		(end 92.343902 131.475614)
		(width 0.1)
		(layer "In5.Cu")
		(net 180)
	)
	(segment
		(start 92.240906 131.275614)
		(end 92.227828 131.288692)
		(width 0.1)
		(layer "In5.Cu")
		(net 180)
	)
	(segment
		(start 92.310784 131.459665)
		(end 92.328241 131.465774)
		(width 0.1)
		(layer "In5.Cu")
		(net 180)
	)
	(segment
		(start 92.310784 131.255524)
		(end 92.274024 131.259665)
		(width 0.1)
		(layer "In5.Cu")
		(net 180)
	)
	(segment
		(start 92.211879 131.32181)
		(end 92.209809 131.34019)
		(width 0.1)
		(layer "In5.Cu")
		(net 180)
	)
	(segment
		(start 92.211879 131.393379)
		(end 92.217988 131.410836)
		(width 0.1)
		(layer "In5.Cu")
		(net 180)
	)
	(segment
		(start 92.209809 131.375)
		(end 92.211879 131.393379)
		(width 0.1)
		(layer "In5.Cu")
		(net 180)
	)
	(segment
		(start 91.275 129.675)
		(end 92.375 130.775)
		(width 0.1)
		(layer "In5.Cu")
		(net 180)
	)
	(segment
		(start 92.375 131.54019)
		(end 92.375 146.275)
		(width 0.1)
		(layer "In5.Cu")
		(net 180)
	)
	(segment
		(start 92.274024 131.259665)
		(end 92.256567 131.265774)
		(width 0.1)
		(layer "In5.Cu")
		(net 180)
	)
	(segment
		(start 92.375 131.175)
		(end 92.372929 131.193379)
		(width 0.1)
		(layer "In5.Cu")
		(net 180)
	)
	(segment
		(start 92.35698 131.226497)
		(end 92.343902 131.239575)
		(width 0.1)
		(layer "In5.Cu")
		(net 180)
	)
	(segment
		(start 92.256567 131.265774)
		(end 92.240906 131.275614)
		(width 0.1)
		(layer "In5.Cu")
		(net 180)
	)
	(segment
		(start 93.775 147.675)
		(end 93.775 148.175)
		(width 0.1)
		(layer "In5.Cu")
		(net 180)
	)
	(segment
		(start 92.36682 131.210836)
		(end 92.35698 131.226497)
		(width 0.1)
		(layer "In5.Cu")
		(net 180)
	)
	(segment
		(start 92.375 130.775)
		(end 92.375 131.175)
		(width 0.1)
		(layer "In5.Cu")
		(net 180)
	)
	(segment
		(start 92.227828 131.426497)
		(end 92.240906 131.439575)
		(width 0.1)
		(layer "In5.Cu")
		(net 180)
	)
	(segment
		(start 92.240906 131.439575)
		(end 92.256567 131.449415)
		(width 0.1)
		(layer "In5.Cu")
		(net 180)
	)
	(segment
		(start 92.209809 131.34019)
		(end 92.209809 131.375)
		(width 0.1)
		(layer "In5.Cu")
		(net 180)
	)
	(segment
		(start 92.36682 131.504353)
		(end 92.372929 131.52181)
		(width 0.1)
		(layer "In5.Cu")
		(net 180)
	)
	(segment
		(start 92.375 146.275)
		(end 93.775 147.675)
		(width 0.1)
		(layer "In5.Cu")
		(net 180)
	)
	(segment
		(start 92.227828 131.288692)
		(end 92.217988 131.304353)
		(width 0.1)
		(layer "In5.Cu")
		(net 180)
	)
	(segment
		(start 92.274024 131.455524)
		(end 92.310784 131.459665)
		(width 0.1)
		(layer "In5.Cu")
		(net 180)
	)
	(segment
		(start 92.217988 131.410836)
		(end 92.227828 131.426497)
		(width 0.1)
		(layer "In5.Cu")
		(net 180)
	)
	(segment
		(start 92.372929 131.193379)
		(end 92.36682 131.210836)
		(width 0.1)
		(layer "In5.Cu")
		(net 180)
	)
	(segment
		(start 92.343902 131.239575)
		(end 92.328241 131.249415)
		(width 0.1)
		(layer "In5.Cu")
		(net 180)
	)
	(segment
		(start 94.575 148.775)
		(end 94.575 148.175)
		(width 0.1)
		(layer "F.Cu")
		(net 181)
	)
	(segment
		(start 95.775 130.175)
		(end 95.275 130.675)
		(width 0.15)
		(layer "F.Cu")
		(net 181)
	)
	(via blind
		(at 95.275 130.675)
		(size 0.5)
		(drill 0.2)
		(layers "F.Cu" "In2.Cu")
		(net 181)
	)
	(via blind
		(at 94.575 148.175)
		(size 0.5)
		(drill 0.2)
		(layers "F.Cu" "In2.Cu")
		(net 181)
	)
	(segment
		(start 94.575 146.875)
		(end 94.575 148.175)
		(width 0.1)
		(layer "In2.Cu")
		(net 181)
	)
	(segment
		(start 94.975 145.575)
		(end 94.975 146.475)
		(width 0.1)
		(layer "In2.Cu")
		(net 181)
	)
	(segment
		(start 95.275 130.675)
		(end 95.275 145.275)
		(width 0.1)
		(layer "In2.Cu")
		(net 181)
	)
	(segment
		(start 95.275 145.275)
		(end 94.975 145.575)
		(width 0.1)
		(layer "In2.Cu")
		(net 181)
	)
	(segment
		(start 94.975 146.475)
		(end 94.575 146.875)
		(width 0.1)
		(layer "In2.Cu")
		(net 181)
	)
	(segment
		(start 92.775 129.175)
		(end 93.275 128.675)
		(width 0.15)
		(layer "F.Cu")
		(net 182)
	)
	(segment
		(start 92.175 145.575)
		(end 92.175 146.174977)
		(width 0.1)
		(layer "F.Cu")
		(net 182)
	)
	(segment
		(start 92.175 146.174977)
		(end 92.174977 146.175)
		(width 0.1)
		(layer "F.Cu")
		(net 182)
	)
	(via blind
		(at 93.275 128.675)
		(size 0.5)
		(drill 0.2)
		(layers "F.Cu" "In2.Cu")
		(net 182)
	)
	(via blind
		(at 92.174977 146.175)
		(size 0.5)
		(drill 0.2)
		(layers "F.Cu" "In2.Cu")
		(net 182)
	)
	(segment
		(start 93.043717 131.297252)
		(end 93.036321 131.318388)
		(width 0.1)
		(layer "In2.Cu")
		(net 182)
	)
	(segment
		(start 93.275 128.675)
		(end 92.775 129.175)
		(width 0.1)
		(layer "In2.Cu")
		(net 182)
	)
	(segment
		(start 92.560387 131.165096)
		(end 92.581523 131.172492)
		(width 0.1)
		(layer "In2.Cu")
		(net 182)
	)
	(segment
		(start 92.506283 131.097252)
		(end 92.513679 131.118388)
		(width 0.1)
		(layer "In2.Cu")
		(net 182)
	)
	(segment
		(start 92.737348 130.953183)
		(end 92.718388 130.965096)
		(width 0.1)
		(layer "In2.Cu")
		(net 182)
	)
	(segment
		(start 92.581523 131.377507)
		(end 92.560387 131.384903)
		(width 0.1)
		(layer "In2.Cu")
		(net 182)
	)
	(segment
		(start 92.968477 131.372492)
		(end 92.946224 131.375)
		(width 0.1)
		(layer "In2.Cu")
		(net 182)
	)
	(segment
		(start 92.946224 131.175)
		(end 92.968477 131.177507)
		(width 0.1)
		(layer "In2.Cu")
		(net 182)
	)
	(segment
		(start 92.174977 145.375023)
		(end 92.174977 145.821447)
		(width 0.1)
		(layer "In2.Cu")
		(net 182)
	)
	(segment
		(start 92.697252 130.972492)
		(end 92.675 130.975)
		(width 0.1)
		(layer "In2.Cu")
		(net 182)
	)
	(segment
		(start 92.775 144.775)
		(end 92.174977 145.375023)
		(width 0.1)
		(layer "In2.Cu")
		(net 182)
	)
	(segment
		(start 92.513679 131.431611)
		(end 92.506283 131.452747)
		(width 0.1)
		(layer "In2.Cu")
		(net 182)
	)
	(segment
		(start 92.560387 131.384903)
		(end 92.541427 131.396816)
		(width 0.1)
		(layer "In2.Cu")
		(net 182)
	)
	(segment
		(start 93.024408 131.212651)
		(end 93.036321 131.231611)
		(width 0.1)
		(layer "In2.Cu")
		(net 182)
	)
	(segment
		(start 92.513679 131.518388)
		(end 92.525592 131.537348)
		(width 0.1)
		(layer "In2.Cu")
		(net 182)
	)
	(segment
		(start 93.008573 131.596816)
		(end 93.024408 131.612651)
		(width 0.1)
		(layer "In2.Cu")
		(net 182)
	)
	(segment
		(start 92.775 130.875)
		(end 92.772492 130.897252)
		(width 0.1)
		(layer "In2.Cu")
		(net 182)
	)
	(segment
		(start 92.772492 130.897252)
		(end 92.765096 130.918388)
		(width 0.1)
		(layer "In2.Cu")
		(net 182)
	)
	(segment
		(start 92.581523 131.172492)
		(end 92.603776 131.175)
		(width 0.1)
		(layer "In2.Cu")
		(net 182)
	)
	(segment
		(start 93.043717 131.697252)
		(end 93.036321 131.718388)
		(width 0.1)
		(layer "In2.Cu")
		(net 182)
	)
	(segment
		(start 93.008573 131.196816)
		(end 93.024408 131.212651)
		(width 0.1)
		(layer "In2.Cu")
		(net 182)
	)
	(segment
		(start 92.560387 131.565096)
		(end 92.581523 131.572492)
		(width 0.1)
		(layer "In2.Cu")
		(net 182)
	)
	(segment
		(start 92.560387 130.984903)
		(end 92.541427 130.996816)
		(width 0.1)
		(layer "In2.Cu")
		(net 182)
	)
	(segment
		(start 92.784904 131.831611)
		(end 92.777508 131.852747)
		(width 0.1)
		(layer "In2.Cu")
		(net 182)
	)
	(segment
		(start 93.036321 131.718388)
		(end 93.024408 131.737348)
		(width 0.1)
		(layer "In2.Cu")
		(net 182)
	)
	(segment
		(start 93.046224 131.675)
		(end 93.043717 131.697252)
		(width 0.1)
		(layer "In2.Cu")
		(net 182)
	)
	(segment
		(start 92.603776 130.975)
		(end 92.581523 130.977507)
		(width 0.1)
		(layer "In2.Cu")
		(net 182)
	)
	(segment
		(start 92.812652 131.796816)
		(end 92.796817 131.812651)
		(width 0.1)
		(layer "In2.Cu")
		(net 182)
	)
	(segment
		(start 93.024408 131.337348)
		(end 93.008573 131.353183)
		(width 0.1)
		(layer "In2.Cu")
		(net 182)
	)
	(segment
		(start 92.581523 130.977507)
		(end 92.560387 130.984903)
		(width 0.1)
		(layer "In2.Cu")
		(net 182)
	)
	(segment
		(start 93.036321 131.631611)
		(end 93.043717 131.652747)
		(width 0.1)
		(layer "In2.Cu")
		(net 182)
	)
	(segment
		(start 92.541427 131.396816)
		(end 92.525592 131.412651)
		(width 0.1)
		(layer "In2.Cu")
		(net 182)
	)
	(segment
		(start 92.989613 131.184903)
		(end 93.008573 131.196816)
		(width 0.1)
		(layer "In2.Cu")
		(net 182)
	)
	(segment
		(start 92.525592 131.137348)
		(end 92.541427 131.153183)
		(width 0.1)
		(layer "In2.Cu")
		(net 182)
	)
	(segment
		(start 92.603776 131.375)
		(end 92.581523 131.377507)
		(width 0.1)
		(layer "In2.Cu")
		(net 182)
	)
	(segment
		(start 92.603776 131.175)
		(end 92.946224 131.175)
		(width 0.1)
		(layer "In2.Cu")
		(net 182)
	)
	(segment
		(start 92.875 131.775)
		(end 92.852748 131.777507)
		(width 0.1)
		(layer "In2.Cu")
		(net 182)
	)
	(segment
		(start 92.513679 131.118388)
		(end 92.525592 131.137348)
		(width 0.1)
		(layer "In2.Cu")
		(net 182)
	)
	(segment
		(start 92.968477 131.577507)
		(end 92.989613 131.584903)
		(width 0.1)
		(layer "In2.Cu")
		(net 182)
	)
	(segment
		(start 92.581523 131.572492)
		(end 92.603776 131.575)
		(width 0.1)
		(layer "In2.Cu")
		(net 182)
	)
	(segment
		(start 93.036321 131.318388)
		(end 93.024408 131.337348)
		(width 0.1)
		(layer "In2.Cu")
		(net 182)
	)
	(segment
		(start 92.946224 131.775)
		(end 92.875 131.775)
		(width 0.1)
		(layer "In2.Cu")
		(net 182)
	)
	(segment
		(start 92.506283 131.452747)
		(end 92.503776 131.475)
		(width 0.1)
		(layer "In2.Cu")
		(net 182)
	)
	(segment
		(start 92.946224 131.575)
		(end 92.968477 131.577507)
		(width 0.1)
		(layer "In2.Cu")
		(net 182)
	)
	(segment
		(start 92.513679 131.031611)
		(end 92.506283 131.052747)
		(width 0.1)
		(layer "In2.Cu")
		(net 182)
	)
	(segment
		(start 92.946224 131.375)
		(end 92.603776 131.375)
		(width 0.1)
		(layer "In2.Cu")
		(net 182)
	)
	(segment
		(start 92.989613 131.365096)
		(end 92.968477 131.372492)
		(width 0.1)
		(layer "In2.Cu")
		(net 182)
	)
	(segment
		(start 93.024408 131.612651)
		(end 93.036321 131.631611)
		(width 0.1)
		(layer "In2.Cu")
		(net 182)
	)
	(segment
		(start 92.765096 130.918388)
		(end 92.753183 130.937348)
		(width 0.1)
		(layer "In2.Cu")
		(net 182)
	)
	(segment
		(start 93.008573 131.353183)
		(end 92.989613 131.365096)
		(width 0.1)
		(layer "In2.Cu")
		(net 182)
	)
	(segment
		(start 93.043717 131.252747)
		(end 93.046224 131.275)
		(width 0.1)
		(layer "In2.Cu")
		(net 182)
	)
	(segment
		(start 92.541427 131.153183)
		(end 92.560387 131.165096)
		(width 0.1)
		(layer "In2.Cu")
		(net 182)
	)
	(segment
		(start 92.831612 131.784903)
		(end 92.812652 131.796816)
		(width 0.1)
		(layer "In2.Cu")
		(net 182)
	)
	(segment
		(start 92.718388 130.965096)
		(end 92.697252 130.972492)
		(width 0.1)
		(layer "In2.Cu")
		(net 182)
	)
	(segment
		(start 92.503776 131.475)
		(end 92.506283 131.497252)
		(width 0.1)
		(layer "In2.Cu")
		(net 182)
	)
	(segment
		(start 92.968477 131.772492)
		(end 92.946224 131.775)
		(width 0.1)
		(layer "In2.Cu")
		(net 182)
	)
	(segment
		(start 92.525592 131.012651)
		(end 92.513679 131.031611)
		(width 0.1)
		(layer "In2.Cu")
		(net 182)
	)
	(segment
		(start 92.796817 131.812651)
		(end 92.784904 131.831611)
		(width 0.1)
		(layer "In2.Cu")
		(net 182)
	)
	(segment
		(start 92.174977 145.821447)
		(end 92.174977 146.175)
		(width 0.1)
		(layer "In2.Cu")
		(net 182)
	)
	(segment
		(start 92.541427 130.996816)
		(end 92.525592 131.012651)
		(width 0.1)
		(layer "In2.Cu")
		(net 182)
	)
	(segment
		(start 93.008573 131.753183)
		(end 92.989613 131.765096)
		(width 0.1)
		(layer "In2.Cu")
		(net 182)
	)
	(segment
		(start 93.024408 131.737348)
		(end 93.008573 131.753183)
		(width 0.1)
		(layer "In2.Cu")
		(net 182)
	)
	(segment
		(start 92.506283 131.497252)
		(end 92.513679 131.518388)
		(width 0.1)
		(layer "In2.Cu")
		(net 182)
	)
	(segment
		(start 93.043717 131.652747)
		(end 93.046224 131.675)
		(width 0.1)
		(layer "In2.Cu")
		(net 182)
	)
	(segment
		(start 92.852748 131.777507)
		(end 92.831612 131.784903)
		(width 0.1)
		(layer "In2.Cu")
		(net 182)
	)
	(segment
		(start 92.506283 131.052747)
		(end 92.503776 131.075)
		(width 0.1)
		(layer "In2.Cu")
		(net 182)
	)
	(segment
		(start 92.541427 131.553183)
		(end 92.560387 131.565096)
		(width 0.1)
		(layer "In2.Cu")
		(net 182)
	)
	(segment
		(start 92.503776 131.075)
		(end 92.506283 131.097252)
		(width 0.1)
		(layer "In2.Cu")
		(net 182)
	)
	(segment
		(start 92.675 130.975)
		(end 92.603776 130.975)
		(width 0.1)
		(layer "In2.Cu")
		(net 182)
	)
	(segment
		(start 92.525592 131.537348)
		(end 92.541427 131.553183)
		(width 0.1)
		(layer "In2.Cu")
		(net 182)
	)
	(segment
		(start 92.989613 131.765096)
		(end 92.968477 131.772492)
		(width 0.1)
		(layer "In2.Cu")
		(net 182)
	)
	(segment
		(start 93.046224 131.275)
		(end 93.043717 131.297252)
		(width 0.1)
		(layer "In2.Cu")
		(net 182)
	)
	(segment
		(start 92.989613 131.584903)
		(end 93.008573 131.596816)
		(width 0.1)
		(layer "In2.Cu")
		(net 182)
	)
	(segment
		(start 92.775 131.875)
		(end 92.775 144.775)
		(width 0.1)
		(layer "In2.Cu")
		(net 182)
	)
	(segment
		(start 92.525592 131.412651)
		(end 92.513679 131.431611)
		(width 0.1)
		(layer "In2.Cu")
		(net 182)
	)
	(segment
		(start 92.968477 131.177507)
		(end 92.989613 131.184903)
		(width 0.1)
		(layer "In2.Cu")
		(net 182)
	)
	(segment
		(start 92.775 129.175)
		(end 92.775 130.875)
		(width 0.1)
		(layer "In2.Cu")
		(net 182)
	)
	(segment
		(start 92.753183 130.937348)
		(end 92.737348 130.953183)
		(width 0.1)
		(layer "In2.Cu")
		(net 182)
	)
	(segment
		(start 92.603776 131.575)
		(end 92.946224 131.575)
		(width 0.1)
		(layer "In2.Cu")
		(net 182)
	)
	(segment
		(start 93.036321 131.231611)
		(end 93.043717 131.252747)
		(width 0.1)
		(layer "In2.Cu")
		(net 182)
	)
	(segment
		(start 92.777508 131.852747)
		(end 92.775 131.875)
		(width 0.1)
		(layer "In2.Cu")
		(net 182)
	)
	(segment
		(start 93.775 144.775)
		(end 94.175 145.175)
		(width 0.1)
		(layer "F.Cu")
		(net 183)
	)
	(segment
		(start 95.775 128.175)
		(end 95.275 127.675)
		(width 0.15)
		(layer "F.Cu")
		(net 183)
	)
	(segment
		(start 94.175 145.175)
		(end 94.175 146.774992)
		(width 0.1)
		(layer "F.Cu")
		(net 183)
	)
	(via blind
		(at 94.175 146.774992)
		(size 0.5)
		(drill 0.2)
		(layers "F.Cu" "In2.Cu")
		(net 183)
	)
	(via blind
		(at 95.275 127.675)
		(size 0.5)
		(drill 0.2)
		(layers "F.Cu" "In2.Cu")
		(net 183)
	)
	(segment
		(start 94.085908 132.043825)
		(end 94.079951 132.053305)
		(width 0.1)
		(layer "In2.Cu")
		(net 183)
	)
	(segment
		(start 94.093825 132.035908)
		(end 94.085908 132.043825)
		(width 0.1)
		(layer "In2.Cu")
		(net 183)
	)
	(segment
		(start 94.146694 132.020048)
		(end 94.136126 132.023746)
		(width 0.1)
		(layer "In2.Cu")
		(net 183)
	)
	(segment
		(start 94.156174 132.014091)
		(end 94.146694 132.020048)
		(width 0.1)
		(layer "In2.Cu")
		(net 183)
	)
	(segment
		(start 94.085908 132.206174)
		(end 94.093825 132.214091)
		(width 0.1)
		(layer "In2.Cu")
		(net 183)
	)
	(segment
		(start 94.175 132.575)
		(end 94.175 146.774992)
		(width 0.1)
		(layer "In2.Cu")
		(net 183)
	)
	(segment
		(start 94.517589 132.284903)
		(end 94.536549 132.296816)
		(width 0.1)
		(layer "In2.Cu")
		(net 183)
	)
	(segment
		(start 94.184904 132.531611)
		(end 94.177508 132.552747)
		(width 0.1)
		(layer "In2.Cu")
		(net 183)
	)
	(segment
		(start 94.170048 131.996694)
		(end 94.164091 132.006174)
		(width 0.1)
		(layer "In2.Cu")
		(net 183)
	)
	(segment
		(start 94.496453 132.472492)
		(end 94.4742 132.475)
		(width 0.1)
		(layer "In2.Cu")
		(net 183)
	)
	(segment
		(start 94.175 131.975)
		(end 94.173746 131.986126)
		(width 0.1)
		(layer "In2.Cu")
		(net 183)
	)
	(segment
		(start 94.177508 132.552747)
		(end 94.175 132.575)
		(width 0.1)
		(layer "In2.Cu")
		(net 183)
	)
	(segment
		(start 94.675 131.175)
		(end 94.175 131.675)
		(width 0.1)
		(layer "In2.Cu")
		(net 183)
	)
	(segment
		(start 94.675 128.275)
		(end 94.675 131.175)
		(width 0.1)
		(layer "In2.Cu")
		(net 183)
	)
	(segment
		(start 94.173746 131.986126)
		(end 94.170048 131.996694)
		(width 0.1)
		(layer "In2.Cu")
		(net 183)
	)
	(segment
		(start 94.075 132.075)
		(end 94.075 132.175)
		(width 0.1)
		(layer "In2.Cu")
		(net 183)
	)
	(segment
		(start 94.212652 132.496816)
		(end 94.196817 132.512651)
		(width 0.1)
		(layer "In2.Cu")
		(net 183)
	)
	(segment
		(start 94.231612 132.484903)
		(end 94.212652 132.496816)
		(width 0.1)
		(layer "In2.Cu")
		(net 183)
	)
	(segment
		(start 94.571693 132.397252)
		(end 94.564297 132.418388)
		(width 0.1)
		(layer "In2.Cu")
		(net 183)
	)
	(segment
		(start 94.5742 132.375)
		(end 94.571693 132.397252)
		(width 0.1)
		(layer "In2.Cu")
		(net 183)
	)
	(segment
		(start 94.093825 132.214091)
		(end 94.103305 132.220048)
		(width 0.1)
		(layer "In2.Cu")
		(net 183)
	)
	(segment
		(start 94.4742 132.275)
		(end 94.496453 132.277507)
		(width 0.1)
		(layer "In2.Cu")
		(net 183)
	)
	(segment
		(start 94.536549 132.453183)
		(end 94.517589 132.465096)
		(width 0.1)
		(layer "In2.Cu")
		(net 183)
	)
	(segment
		(start 94.103305 132.220048)
		(end 94.113873 132.223746)
		(width 0.1)
		(layer "In2.Cu")
		(net 183)
	)
	(segment
		(start 94.175 132.275)
		(end 94.4742 132.275)
		(width 0.1)
		(layer "In2.Cu")
		(net 183)
	)
	(segment
		(start 94.552384 132.437348)
		(end 94.536549 132.453183)
		(width 0.1)
		(layer "In2.Cu")
		(net 183)
	)
	(segment
		(start 94.536549 132.296816)
		(end 94.552384 132.312651)
		(width 0.1)
		(layer "In2.Cu")
		(net 183)
	)
	(segment
		(start 94.275 132.475)
		(end 94.252748 132.477507)
		(width 0.1)
		(layer "In2.Cu")
		(net 183)
	)
	(segment
		(start 94.564297 132.331611)
		(end 94.571693 132.352747)
		(width 0.1)
		(layer "In2.Cu")
		(net 183)
	)
	(segment
		(start 94.125 132.225)
		(end 94.175 132.225)
		(width 0.1)
		(layer "In2.Cu")
		(net 183)
	)
	(segment
		(start 94.079951 132.053305)
		(end 94.076253 132.063873)
		(width 0.1)
		(layer "In2.Cu")
		(net 183)
	)
	(segment
		(start 94.496453 132.277507)
		(end 94.517589 132.284903)
		(width 0.1)
		(layer "In2.Cu")
		(net 183)
	)
	(segment
		(start 94.113873 132.223746)
		(end 94.125 132.225)
		(width 0.1)
		(layer "In2.Cu")
		(net 183)
	)
	(segment
		(start 94.136126 132.023746)
		(end 94.113873 132.026253)
		(width 0.1)
		(layer "In2.Cu")
		(net 183)
	)
	(segment
		(start 94.113873 132.026253)
		(end 94.103305 132.029951)
		(width 0.1)
		(layer "In2.Cu")
		(net 183)
	)
	(segment
		(start 94.076253 132.186126)
		(end 94.079951 132.196694)
		(width 0.1)
		(layer "In2.Cu")
		(net 183)
	)
	(segment
		(start 94.175 132.225)
		(end 94.175 132.275)
		(width 0.1)
		(layer "In2.Cu")
		(net 183)
	)
	(segment
		(start 95.275 127.675)
		(end 94.675 128.275)
		(width 0.1)
		(layer "In2.Cu")
		(net 183)
	)
	(segment
		(start 94.076253 132.063873)
		(end 94.075 132.075)
		(width 0.1)
		(layer "In2.Cu")
		(net 183)
	)
	(segment
		(start 94.103305 132.029951)
		(end 94.093825 132.035908)
		(width 0.1)
		(layer "In2.Cu")
		(net 183)
	)
	(segment
		(start 94.079951 132.196694)
		(end 94.085908 132.206174)
		(width 0.1)
		(layer "In2.Cu")
		(net 183)
	)
	(segment
		(start 94.4742 132.475)
		(end 94.275 132.475)
		(width 0.1)
		(layer "In2.Cu")
		(net 183)
	)
	(segment
		(start 94.196817 132.512651)
		(end 94.184904 132.531611)
		(width 0.1)
		(layer "In2.Cu")
		(net 183)
	)
	(segment
		(start 94.552384 132.312651)
		(end 94.564297 132.331611)
		(width 0.1)
		(layer "In2.Cu")
		(net 183)
	)
	(segment
		(start 94.571693 132.352747)
		(end 94.5742 132.375)
		(width 0.1)
		(layer "In2.Cu")
		(net 183)
	)
	(segment
		(start 94.517589 132.465096)
		(end 94.496453 132.472492)
		(width 0.1)
		(layer "In2.Cu")
		(net 183)
	)
	(segment
		(start 94.564297 132.418388)
		(end 94.552384 132.437348)
		(width 0.1)
		(layer "In2.Cu")
		(net 183)
	)
	(segment
		(start 94.175 131.675)
		(end 94.175 131.975)
		(width 0.1)
		(layer "In2.Cu")
		(net 183)
	)
	(segment
		(start 94.164091 132.006174)
		(end 94.156174 132.014091)
		(width 0.1)
		(layer "In2.Cu")
		(net 183)
	)
	(segment
		(start 94.075 132.175)
		(end 94.076253 132.186126)
		(width 0.1)
		(layer "In2.Cu")
		(net 183)
	)
	(segment
		(start 94.252748 132.477507)
		(end 94.231612 132.484903)
		(width 0.1)
		(layer "In2.Cu")
		(net 183)
	)
	(segment
		(start 93.775 129.175)
		(end 93.275 129.675)
		(width 0.15)
		(layer "F.Cu")
		(net 184)
	)
	(segment
		(start 93.375 149.175)
		(end 93.375 147.675)
		(width 0.1)
		(layer "F.Cu")
		(net 184)
	)
	(segment
		(start 93.775 149.575)
		(end 93.375 149.175)
		(width 0.1)
		(layer "F.Cu")
		(net 184)
	)
	(via blind
		(at 93.275 129.675)
		(size 0.5)
		(drill 0.2)
		(layers "F.Cu" "In2.Cu")
		(net 184)
	)
	(via blind
		(at 93.375 147.675)
		(size 0.5)
		(drill 0.2)
		(layers "F.Cu" "In2.Cu")
		(net 184)
	)
	(segment
		(start 93.005962 133.818388)
		(end 93.017875 133.837348)
		(width 0.1)
		(layer "In2.Cu")
		(net 184)
	)
	(segment
		(start 93.017875 132.912651)
		(end 93.005962 132.931611)
		(width 0.1)
		(layer "In2.Cu")
		(net 184)
	)
	(segment
		(start 93.551434 133.197252)
		(end 93.544038 133.218388)
		(width 0.1)
		(layer "In2.Cu")
		(net 184)
	)
	(segment
		(start 93.096059 133.875)
		(end 93.453941 133.875)
		(width 0.1)
		(layer "In2.Cu")
		(net 184)
	)
	(segment
		(start 93.073806 133.872492)
		(end 93.096059 133.875)
		(width 0.1)
		(layer "In2.Cu")
		(net 184)
	)
	(segment
		(start 93.544038 132.818388)
		(end 93.532125 132.837348)
		(width 0.1)
		(layer "In2.Cu")
		(net 184)
	)
	(segment
		(start 93.476194 132.872492)
		(end 93.453941 132.875)
		(width 0.1)
		(layer "In2.Cu")
		(net 184)
	)
	(segment
		(start 93.03371 132.096816)
		(end 93.017875 132.112651)
		(width 0.1)
		(layer "In2.Cu")
		(net 184)
	)
	(segment
		(start 93.05267 133.284903)
		(end 93.03371 133.296816)
		(width 0.1)
		(layer "In2.Cu")
		(net 184)
	)
	(segment
		(start 93.476194 134.072492)
		(end 93.453941 134.075)
		(width 0.1)
		(layer "In2.Cu")
		(net 184)
	)
	(segment
		(start 93.096059 132.075)
		(end 93.073806 132.077507)
		(width 0.1)
		(layer "In2.Cu")
		(net 184)
	)
	(segment
		(start 92.574987 146.874987)
		(end 92.574987 145.475013)
		(width 0.1)
		(layer "In2.Cu")
		(net 184)
	)
	(segment
		(start 93.49733 133.084903)
		(end 93.51629 133.096816)
		(width 0.1)
		(layer "In2.Cu")
		(net 184)
	)
	(segment
		(start 93.453941 132.475)
		(end 93.096059 132.475)
		(width 0.1)
		(layer "In2.Cu")
		(net 184)
	)
	(segment
		(start 93.03371 132.253183)
		(end 93.05267 132.265096)
		(width 0.1)
		(layer "In2.Cu")
		(net 184)
	)
	(segment
		(start 93.073806 132.077507)
		(end 93.05267 132.084903)
		(width 0.1)
		(layer "In2.Cu")
		(net 184)
	)
	(segment
		(start 93.218388 132.065096)
		(end 93.197252 132.072492)
		(width 0.1)
		(layer "In2.Cu")
		(net 184)
	)
	(segment
		(start 93.51629 132.696816)
		(end 93.532125 132.712651)
		(width 0.1)
		(layer "In2.Cu")
		(net 184)
	)
	(segment
		(start 93.453941 133.075)
		(end 93.476194 133.077507)
		(width 0.1)
		(layer "In2.Cu")
		(net 184)
	)
	(segment
		(start 93.51629 133.653183)
		(end 93.49733 133.665096)
		(width 0.1)
		(layer "In2.Cu")
		(net 184)
	)
	(segment
		(start 92.998566 133.797252)
		(end 93.005962 133.818388)
		(width 0.1)
		(layer "In2.Cu")
		(net 184)
	)
	(segment
		(start 93.51629 133.096816)
		(end 93.532125 133.112651)
		(width 0.1)
		(layer "In2.Cu")
		(net 184)
	)
	(segment
		(start 93.05267 132.665096)
		(end 93.073806 132.672492)
		(width 0.1)
		(layer "In2.Cu")
		(net 184)
	)
	(segment
		(start 93.005962 132.618388)
		(end 93.017875 132.637348)
		(width 0.1)
		(layer "In2.Cu")
		(net 184)
	)
	(segment
		(start 93.544038 133.218388)
		(end 93.532125 133.237348)
		(width 0.1)
		(layer "In2.Cu")
		(net 184)
	)
	(segment
		(start 92.998566 132.952747)
		(end 92.996059 132.975)
		(width 0.1)
		(layer "In2.Cu")
		(net 184)
	)
	(segment
		(start 93.453941 133.275)
		(end 93.096059 133.275)
		(width 0.1)
		(layer "In2.Cu")
		(net 184)
	)
	(segment
		(start 93.017875 133.312651)
		(end 93.005962 133.331611)
		(width 0.1)
		(layer "In2.Cu")
		(net 184)
	)
	(segment
		(start 93.096059 132.275)
		(end 93.453941 132.275)
		(width 0.1)
		(layer "In2.Cu")
		(net 184)
	)
	(segment
		(start 93.03371 133.296816)
		(end 93.017875 133.312651)
		(width 0.1)
		(layer "In2.Cu")
		(net 184)
	)
	(segment
		(start 93.272492 131.997252)
		(end 93.265096 132.018388)
		(width 0.1)
		(layer "In2.Cu")
		(net 184)
	)
	(segment
		(start 93.453941 133.675)
		(end 93.096059 133.675)
		(width 0.1)
		(layer "In2.Cu")
		(net 184)
	)
	(segment
		(start 93.284904 134.131611)
		(end 93.277508 134.152747)
		(width 0.1)
		(layer "In2.Cu")
		(net 184)
	)
	(segment
		(start 93.544038 132.418388)
		(end 93.532125 132.437348)
		(width 0.1)
		(layer "In2.Cu")
		(net 184)
	)
	(segment
		(start 93.453941 134.075)
		(end 93.375 134.075)
		(width 0.1)
		(layer "In2.Cu")
		(net 184)
	)
	(segment
		(start 93.551434 132.352747)
		(end 93.553941 132.375)
		(width 0.1)
		(layer "In2.Cu")
		(net 184)
	)
	(segment
		(start 93.05267 132.265096)
		(end 93.073806 132.272492)
		(width 0.1)
		(layer "In2.Cu")
		(net 184)
	)
	(segment
		(start 93.532125 132.837348)
		(end 93.51629 132.853183)
		(width 0.1)
		(layer "In2.Cu")
		(net 184)
	)
	(segment
		(start 93.096059 133.075)
		(end 93.453941 133.075)
		(width 0.1)
		(layer "In2.Cu")
		(net 184)
	)
	(segment
		(start 93.175 132.075)
		(end 93.096059 132.075)
		(width 0.1)
		(layer "In2.Cu")
		(net 184)
	)
	(segment
		(start 93.532125 133.637348)
		(end 93.51629 133.653183)
		(width 0.1)
		(layer "In2.Cu")
		(net 184)
	)
	(segment
		(start 93.49733 133.265096)
		(end 93.476194 133.272492)
		(width 0.1)
		(layer "In2.Cu")
		(net 184)
	)
	(segment
		(start 93.005962 132.931611)
		(end 92.998566 132.952747)
		(width 0.1)
		(layer "In2.Cu")
		(net 184)
	)
	(segment
		(start 92.996059 133.375)
		(end 92.998566 133.397252)
		(width 0.1)
		(layer "In2.Cu")
		(net 184)
	)
	(segment
		(start 93.476194 133.672492)
		(end 93.453941 133.675)
		(width 0.1)
		(layer "In2.Cu")
		(net 184)
	)
	(segment
		(start 93.553941 133.575)
		(end 93.551434 133.597252)
		(width 0.1)
		(layer "In2.Cu")
		(net 184)
	)
	(segment
		(start 93.312652 134.096816)
		(end 93.296817 134.112651)
		(width 0.1)
		(layer "In2.Cu")
		(net 184)
	)
	(segment
		(start 93.476194 133.877507)
		(end 93.49733 133.884903)
		(width 0.1)
		(layer "In2.Cu")
		(net 184)
	)
	(segment
		(start 93.05267 133.065096)
		(end 93.073806 133.072492)
		(width 0.1)
		(layer "In2.Cu")
		(net 184)
	)
	(segment
		(start 93.49733 132.865096)
		(end 93.476194 132.872492)
		(width 0.1)
		(layer "In2.Cu")
		(net 184)
	)
	(segment
		(start 93.073806 132.477507)
		(end 93.05267 132.484903)
		(width 0.1)
		(layer "In2.Cu")
		(net 184)
	)
	(segment
		(start 93.51629 133.253183)
		(end 93.49733 133.265096)
		(width 0.1)
		(layer "In2.Cu")
		(net 184)
	)
	(segment
		(start 93.51629 133.496816)
		(end 93.532125 133.512651)
		(width 0.1)
		(layer "In2.Cu")
		(net 184)
	)
	(segment
		(start 92.996059 132.975)
		(end 92.998566 132.997252)
		(width 0.1)
		(layer "In2.Cu")
		(net 184)
	)
	(segment
		(start 93.476194 133.077507)
		(end 93.49733 133.084903)
		(width 0.1)
		(layer "In2.Cu")
		(net 184)
	)
	(segment
		(start 93.51629 133.896816)
		(end 93.532125 133.912651)
		(width 0.1)
		(layer "In2.Cu")
		(net 184)
	)
	(segment
		(start 93.03371 133.453183)
		(end 93.05267 133.465096)
		(width 0.1)
		(layer "In2.Cu")
		(net 184)
	)
	(segment
		(start 93.544038 132.331611)
		(end 93.551434 132.352747)
		(width 0.1)
		(layer "In2.Cu")
		(net 184)
	)
	(segment
		(start 93.096059 133.675)
		(end 93.073806 133.677507)
		(width 0.1)
		(layer "In2.Cu")
		(net 184)
	)
	(segment
		(start 93.544038 132.731611)
		(end 93.551434 132.752747)
		(width 0.1)
		(layer "In2.Cu")
		(net 184)
	)
	(segment
		(start 93.275 134.175)
		(end 93.275 144.775)
		(width 0.1)
		(layer "In2.Cu")
		(net 184)
	)
	(segment
		(start 93.017875 132.112651)
		(end 93.005962 132.131611)
		(width 0.1)
		(layer "In2.Cu")
		(net 184)
	)
	(segment
		(start 93.49733 133.884903)
		(end 93.51629 133.896816)
		(width 0.1)
		(layer "In2.Cu")
		(net 184)
	)
	(segment
		(start 92.998566 132.152747)
		(end 92.996059 132.175)
		(width 0.1)
		(layer "In2.Cu")
		(net 184)
	)
	(segment
		(start 93.532125 132.712651)
		(end 93.544038 132.731611)
		(width 0.1)
		(layer "In2.Cu")
		(net 184)
	)
	(segment
		(start 93.017875 132.637348)
		(end 93.03371 132.653183)
		(width 0.1)
		(layer "In2.Cu")
		(net 184)
	)
	(segment
		(start 93.532125 132.437348)
		(end 93.51629 132.453183)
		(width 0.1)
		(layer "In2.Cu")
		(net 184)
	)
	(segment
		(start 93.49733 132.284903)
		(end 93.51629 132.296816)
		(width 0.1)
		(layer "In2.Cu")
		(net 184)
	)
	(segment
		(start 92.998566 133.352747)
		(end 92.996059 133.375)
		(width 0.1)
		(layer "In2.Cu")
		(net 184)
	)
	(segment
		(start 92.998566 132.197252)
		(end 93.005962 132.218388)
		(width 0.1)
		(layer "In2.Cu")
		(net 184)
	)
	(segment
		(start 93.544038 133.531611)
		(end 93.551434 133.552747)
		(width 0.1)
		(layer "In2.Cu")
		(net 184)
	)
	(segment
		(start 93.476194 132.677507)
		(end 93.49733 132.684903)
		(width 0.1)
		(layer "In2.Cu")
		(net 184)
	)
	(segment
		(start 93.03371 133.696816)
		(end 93.017875 133.712651)
		(width 0.1)
		(layer "In2.Cu")
		(net 184)
	)
	(segment
		(start 93.096059 133.275)
		(end 93.073806 133.277507)
		(width 0.1)
		(layer "In2.Cu")
		(net 184)
	)
	(segment
		(start 93.096059 132.475)
		(end 93.073806 132.477507)
		(width 0.1)
		(layer "In2.Cu")
		(net 184)
	)
	(segment
		(start 93.553941 133.975)
		(end 93.551434 133.997252)
		(width 0.1)
		(layer "In2.Cu")
		(net 184)
	)
	(segment
		(start 93.476194 132.277507)
		(end 93.49733 132.284903)
		(width 0.1)
		(layer "In2.Cu")
		(net 184)
	)
	(segment
		(start 92.996059 133.775)
		(end 92.998566 133.797252)
		(width 0.1)
		(layer "In2.Cu")
		(net 184)
	)
	(segment
		(start 93.017875 132.237348)
		(end 93.03371 132.253183)
		(width 0.1)
		(layer "In2.Cu")
		(net 184)
	)
	(segment
		(start 93.005962 132.531611)
		(end 92.998566 132.552747)
		(width 0.1)
		(layer "In2.Cu")
		(net 184)
	)
	(segment
		(start 93.253183 132.037348)
		(end 93.237348 132.053183)
		(width 0.1)
		(layer "In2.Cu")
		(net 184)
	)
	(segment
		(start 93.237348 132.053183)
		(end 93.218388 132.065096)
		(width 0.1)
		(layer "In2.Cu")
		(net 184)
	)
	(segment
		(start 93.352748 134.077507)
		(end 93.331612 134.084903)
		(width 0.1)
		(layer "In2.Cu")
		(net 184)
	)
	(segment
		(start 93.551434 132.797252)
		(end 93.544038 132.818388)
		(width 0.1)
		(layer "In2.Cu")
		(net 184)
	)
	(segment
		(start 93.553941 132.775)
		(end 93.551434 132.797252)
		(width 0.1)
		(layer "In2.Cu")
		(net 184)
	)
	(segment
		(start 93.544038 133.131611)
		(end 93.551434 133.152747)
		(width 0.1)
		(layer "In2.Cu")
		(net 184)
	)
	(segment
		(start 93.532125 134.037348)
		(end 93.51629 134.053183)
		(width 0.1)
		(layer "In2.Cu")
		(net 184)
	)
	(segment
		(start 93.532125 133.112651)
		(end 93.544038 133.131611)
		(width 0.1)
		(layer "In2.Cu")
		(net 184)
	)
	(segment
		(start 93.331612 134.084903)
		(end 93.312652 134.096816)
		(width 0.1)
		(layer "In2.Cu")
		(net 184)
	)
	(segment
		(start 93.017875 133.037348)
		(end 93.03371 133.053183)
		(width 0.1)
		(layer "In2.Cu")
		(net 184)
	)
	(segment
		(start 93.073806 132.272492)
		(end 93.096059 132.275)
		(width 0.1)
		(layer "In2.Cu")
		(net 184)
	)
	(segment
		(start 93.544038 133.931611)
		(end 93.551434 133.952747)
		(width 0.1)
		(layer "In2.Cu")
		(net 184)
	)
	(segment
		(start 93.005962 133.018388)
		(end 93.017875 133.037348)
		(width 0.1)
		(layer "In2.Cu")
		(net 184)
	)
	(segment
		(start 93.05267 133.465096)
		(end 93.073806 133.472492)
		(width 0.1)
		(layer "In2.Cu")
		(net 184)
	)
	(segment
		(start 92.998566 133.752747)
		(end 92.996059 133.775)
		(width 0.1)
		(layer "In2.Cu")
		(net 184)
	)
	(segment
		(start 93.51629 132.853183)
		(end 93.49733 132.865096)
		(width 0.1)
		(layer "In2.Cu")
		(net 184)
	)
	(segment
		(start 93.275 129.675)
		(end 93.275 131.975)
		(width 0.1)
		(layer "In2.Cu")
		(net 184)
	)
	(segment
		(start 93.096059 132.675)
		(end 93.453941 132.675)
		(width 0.1)
		(layer "In2.Cu")
		(net 184)
	)
	(segment
		(start 93.197252 132.072492)
		(end 93.175 132.075)
		(width 0.1)
		(layer "In2.Cu")
		(net 184)
	)
	(segment
		(start 93.551434 133.152747)
		(end 93.553941 133.175)
		(width 0.1)
		(layer "In2.Cu")
		(net 184)
	)
	(segment
		(start 93.553941 132.375)
		(end 93.551434 132.397252)
		(width 0.1)
		(layer "In2.Cu")
		(net 184)
	)
	(segment
		(start 93.03371 132.653183)
		(end 93.05267 132.665096)
		(width 0.1)
		(layer "In2.Cu")
		(net 184)
	)
	(segment
		(start 93.03371 132.496816)
		(end 93.017875 132.512651)
		(width 0.1)
		(layer "In2.Cu")
		(net 184)
	)
	(segment
		(start 93.073806 133.072492)
		(end 93.096059 133.075)
		(width 0.1)
		(layer "In2.Cu")
		(net 184)
	)
	(segment
		(start 93.453941 133.475)
		(end 93.476194 133.477507)
		(width 0.1)
		(layer "In2.Cu")
		(net 184)
	)
	(segment
		(start 93.005962 132.218388)
		(end 93.017875 132.237348)
		(width 0.1)
		(layer "In2.Cu")
		(net 184)
	)
	(segment
		(start 93.49733 134.065096)
		(end 93.476194 134.072492)
		(width 0.1)
		(layer "In2.Cu")
		(net 184)
	)
	(segment
		(start 93.532125 133.512651)
		(end 93.544038 133.531611)
		(width 0.1)
		(layer "In2.Cu")
		(net 184)
	)
	(segment
		(start 93.017875 133.837348)
		(end 93.03371 133.853183)
		(width 0.1)
		(layer "In2.Cu")
		(net 184)
	)
	(segment
		(start 93.073806 133.677507)
		(end 93.05267 133.684903)
		(width 0.1)
		(layer "In2.Cu")
		(net 184)
	)
	(segment
		(start 92.574987 145.475013)
		(end 93.275 144.775)
		(width 0.1)
		(layer "In2.Cu")
		(net 184)
	)
	(segment
		(start 93.551434 133.597252)
		(end 93.544038 133.618388)
		(width 0.1)
		(layer "In2.Cu")
		(net 184)
	)
	(segment
		(start 92.996059 132.175)
		(end 92.998566 132.197252)
		(width 0.1)
		(layer "In2.Cu")
		(net 184)
	)
	(segment
		(start 93.073806 132.672492)
		(end 93.096059 132.675)
		(width 0.1)
		(layer "In2.Cu")
		(net 184)
	)
	(segment
		(start 93.453941 132.275)
		(end 93.476194 132.277507)
		(width 0.1)
		(layer "In2.Cu")
		(net 184)
	)
	(segment
		(start 93.551434 132.752747)
		(end 93.553941 132.775)
		(width 0.1)
		(layer "In2.Cu")
		(net 184)
	)
	(segment
		(start 93.03371 132.896816)
		(end 93.017875 132.912651)
		(width 0.1)
		(layer "In2.Cu")
		(net 184)
	)
	(segment
		(start 93.49733 133.665096)
		(end 93.476194 133.672492)
		(width 0.1)
		(layer "In2.Cu")
		(net 184)
	)
	(segment
		(start 93.275 131.975)
		(end 93.272492 131.997252)
		(width 0.1)
		(layer "In2.Cu")
		(net 184)
	)
	(segment
		(start 93.476194 132.472492)
		(end 93.453941 132.475)
		(width 0.1)
		(layer "In2.Cu")
		(net 184)
	)
	(segment
		(start 93.49733 132.465096)
		(end 93.476194 132.472492)
		(width 0.1)
		(layer "In2.Cu")
		(net 184)
	)
	(segment
		(start 93.03371 133.853183)
		(end 93.05267 133.865096)
		(width 0.1)
		(layer "In2.Cu")
		(net 184)
	)
	(segment
		(start 93.005962 133.331611)
		(end 92.998566 133.352747)
		(width 0.1)
		(layer "In2.Cu")
		(net 184)
	)
	(segment
		(start 93.532125 133.237348)
		(end 93.51629 133.253183)
		(width 0.1)
		(layer "In2.Cu")
		(net 184)
	)
	(segment
		(start 93.005962 133.731611)
		(end 92.998566 133.752747)
		(width 0.1)
		(layer "In2.Cu")
		(net 184)
	)
	(segment
		(start 93.453941 133.875)
		(end 93.476194 133.877507)
		(width 0.1)
		(layer "In2.Cu")
		(net 184)
	)
	(segment
		(start 92.996059 132.575)
		(end 92.998566 132.597252)
		(width 0.1)
		(layer "In2.Cu")
		(net 184)
	)
	(segment
		(start 93.017875 132.512651)
		(end 93.005962 132.531611)
		(width 0.1)
		(layer "In2.Cu")
		(net 184)
	)
	(segment
		(start 92.998566 133.397252)
		(end 93.005962 133.418388)
		(width 0.1)
		(layer "In2.Cu")
		(net 184)
	)
	(segment
		(start 93.073806 133.472492)
		(end 93.096059 133.475)
		(width 0.1)
		(layer "In2.Cu")
		(net 184)
	)
	(segment
		(start 93.277508 134.152747)
		(end 93.275 134.175)
		(width 0.1)
		(layer "In2.Cu")
		(net 184)
	)
	(segment
		(start 93.073806 132.877507)
		(end 93.05267 132.884903)
		(width 0.1)
		(layer "In2.Cu")
		(net 184)
	)
	(segment
		(start 92.998566 132.552747)
		(end 92.996059 132.575)
		(width 0.1)
		(layer "In2.Cu")
		(net 184)
	)
	(segment
		(start 93.544038 134.018388)
		(end 93.532125 134.037348)
		(width 0.1)
		(layer "In2.Cu")
		(net 184)
	)
	(segment
		(start 93.551434 133.552747)
		(end 93.553941 133.575)
		(width 0.1)
		(layer "In2.Cu")
		(net 184)
	)
	(segment
		(start 93.265096 132.018388)
		(end 93.253183 132.037348)
		(width 0.1)
		(layer "In2.Cu")
		(net 184)
	)
	(segment
		(start 93.551434 133.997252)
		(end 93.544038 134.018388)
		(width 0.1)
		(layer "In2.Cu")
		(net 184)
	)
	(segment
		(start 93.03371 133.053183)
		(end 93.05267 133.065096)
		(width 0.1)
		(layer "In2.Cu")
		(net 184)
	)
	(segment
		(start 93.51629 134.053183)
		(end 93.49733 134.065096)
		(width 0.1)
		(layer "In2.Cu")
		(net 184)
	)
	(segment
		(start 93.05267 133.865096)
		(end 93.073806 133.872492)
		(width 0.1)
		(layer "In2.Cu")
		(net 184)
	)
	(segment
		(start 93.017875 133.437348)
		(end 93.03371 133.453183)
		(width 0.1)
		(layer "In2.Cu")
		(net 184)
	)
	(segment
		(start 93.476194 133.477507)
		(end 93.49733 133.484903)
		(width 0.1)
		(layer "In2.Cu")
		(net 184)
	)
	(segment
		(start 93.05267 132.484903)
		(end 93.03371 132.496816)
		(width 0.1)
		(layer "In2.Cu")
		(net 184)
	)
	(segment
		(start 92.998566 132.997252)
		(end 93.005962 133.018388)
		(width 0.1)
		(layer "In2.Cu")
		(net 184)
	)
	(segment
		(start 93.553941 133.175)
		(end 93.551434 133.197252)
		(width 0.1)
		(layer "In2.Cu")
		(net 184)
	)
	(segment
		(start 93.544038 133.618388)
		(end 93.532125 133.637348)
		(width 0.1)
		(layer "In2.Cu")
		(net 184)
	)
	(segment
		(start 93.551434 132.397252)
		(end 93.544038 132.418388)
		(width 0.1)
		(layer "In2.Cu")
		(net 184)
	)
	(segment
		(start 92.998566 132.597252)
		(end 93.005962 132.618388)
		(width 0.1)
		(layer "In2.Cu")
		(net 184)
	)
	(segment
		(start 93.005962 132.131611)
		(end 92.998566 132.152747)
		(width 0.1)
		(layer "In2.Cu")
		(net 184)
	)
	(segment
		(start 93.476194 133.272492)
		(end 93.453941 133.275)
		(width 0.1)
		(layer "In2.Cu")
		(net 184)
	)
	(segment
		(start 93.49733 133.484903)
		(end 93.51629 133.496816)
		(width 0.1)
		(layer "In2.Cu")
		(net 184)
	)
	(segment
		(start 93.05267 133.684903)
		(end 93.03371 133.696816)
		(width 0.1)
		(layer "In2.Cu")
		(net 184)
	)
	(segment
		(start 93.49733 132.684903)
		(end 93.51629 132.696816)
		(width 0.1)
		(layer "In2.Cu")
		(net 184)
	)
	(segment
		(start 92.574987 146.874987)
		(end 93.375 147.675)
		(width 0.1)
		(layer "In2.Cu")
		(net 184)
	)
	(segment
		(start 93.005962 133.418388)
		(end 93.017875 133.437348)
		(width 0.1)
		(layer "In2.Cu")
		(net 184)
	)
	(segment
		(start 93.551434 133.952747)
		(end 93.553941 133.975)
		(width 0.1)
		(layer "In2.Cu")
		(net 184)
	)
	(segment
		(start 93.51629 132.453183)
		(end 93.49733 132.465096)
		(width 0.1)
		(layer "In2.Cu")
		(net 184)
	)
	(segment
		(start 93.05267 132.884903)
		(end 93.03371 132.896816)
		(width 0.1)
		(layer "In2.Cu")
		(net 184)
	)
	(segment
		(start 93.017875 133.712651)
		(end 93.005962 133.731611)
		(width 0.1)
		(layer "In2.Cu")
		(net 184)
	)
	(segment
		(start 93.096059 133.475)
		(end 93.453941 133.475)
		(width 0.1)
		(layer "In2.Cu")
		(net 184)
	)
	(segment
		(start 93.532125 132.312651)
		(end 93.544038 132.331611)
		(width 0.1)
		(layer "In2.Cu")
		(net 184)
	)
	(segment
		(start 93.532125 133.912651)
		(end 93.544038 133.931611)
		(width 0.1)
		(layer "In2.Cu")
		(net 184)
	)
	(segment
		(start 93.096059 132.875)
		(end 93.073806 132.877507)
		(width 0.1)
		(layer "In2.Cu")
		(net 184)
	)
	(segment
		(start 93.05267 132.084903)
		(end 93.03371 132.096816)
		(width 0.1)
		(layer "In2.Cu")
		(net 184)
	)
	(segment
		(start 93.51629 132.296816)
		(end 93.532125 132.312651)
		(width 0.1)
		(layer "In2.Cu")
		(net 184)
	)
	(segment
		(start 93.453941 132.675)
		(end 93.476194 132.677507)
		(width 0.1)
		(layer "In2.Cu")
		(net 184)
	)
	(segment
		(start 93.375 134.075)
		(end 93.352748 134.077507)
		(width 0.1)
		(layer "In2.Cu")
		(net 184)
	)
	(segment
		(start 93.453941 132.875)
		(end 93.096059 132.875)
		(width 0.1)
		(layer "In2.Cu")
		(net 184)
	)
	(segment
		(start 93.073806 133.277507)
		(end 93.05267 133.284903)
		(width 0.1)
		(layer "In2.Cu")
		(net 184)
	)
	(segment
		(start 93.296817 134.112651)
		(end 93.284904 134.131611)
		(width 0.1)
		(layer "In2.Cu")
		(net 184)
	)
	(segment
		(start 98.775 126.175)
		(end 98.275 126.675)
		(width 0.15)
		(layer "F.Cu")
		(net 185)
	)
	(segment
		(start 97.775 145.575)
		(end 97.775 146.174998)
		(width 0.1)
		(layer "F.Cu")
		(net 185)
	)
	(via blind
		(at 97.775 146.174998)
		(size 0.5)
		(drill 0.2)
		(layers "F.Cu" "In5.Cu")
		(net 185)
	)
	(via blind
		(at 98.275 126.675)
		(size 0.5)
		(drill 0.2)
		(layers "F.Cu" "In5.Cu")
		(net 185)
	)
	(segment
		(start 98.285891 144.577507)
		(end 98.263639 144.575)
		(width 0.1)
		(layer "In5.Cu")
		(net 185)
	)
	(segment
		(start 98.325987 144.196816)
		(end 98.307027 144.184903)
		(width 0.1)
		(layer "In5.Cu")
		(net 185)
	)
	(segment
		(start 96.786361 144.475)
		(end 96.788869 144.452747)
		(width 0.1)
		(layer "In5.Cu")
		(net 185)
	)
	(segment
		(start 98.307027 144.765096)
		(end 98.325987 144.753183)
		(width 0.1)
		(layer "In5.Cu")
		(net 185)
	)
	(segment
		(start 98.341822 144.337348)
		(end 98.353735 144.318388)
		(width 0.1)
		(layer "In5.Cu")
		(net 185)
	)
	(segment
		(start 96.842973 144.565096)
		(end 96.824013 144.553183)
		(width 0.1)
		(layer "In5.Cu")
		(net 185)
	)
	(segment
		(start 98.353735 144.631611)
		(end 98.341822 144.612651)
		(width 0.1)
		(layer "In5.Cu")
		(net 185)
	)
	(segment
		(start 98.263639 144.575)
		(end 96.886361 144.575)
		(width 0.1)
		(layer "In5.Cu")
		(net 185)
	)
	(segment
		(start 97.875 144.775)
		(end 98.263639 144.775)
		(width 0.1)
		(layer "In5.Cu")
		(net 185)
	)
	(segment
		(start 96.796265 144.518388)
		(end 96.788869 144.497252)
		(width 0.1)
		(layer "In5.Cu")
		(net 185)
	)
	(segment
		(start 98.325987 144.353183)
		(end 98.341822 144.337348)
		(width 0.1)
		(layer "In5.Cu")
		(net 185)
	)
	(segment
		(start 97.784903 144.831611)
		(end 97.796816 144.812651)
		(width 0.1)
		(layer "In5.Cu")
		(net 185)
	)
	(segment
		(start 96.824013 144.553183)
		(end 96.808178 144.537348)
		(width 0.1)
		(layer "In5.Cu")
		(net 185)
	)
	(segment
		(start 96.824013 144.396816)
		(end 96.842973 144.384903)
		(width 0.1)
		(layer "In5.Cu")
		(net 185)
	)
	(segment
		(start 96.808178 144.537348)
		(end 96.796265 144.518388)
		(width 0.1)
		(layer "In5.Cu")
		(net 185)
	)
	(segment
		(start 98.341822 144.737348)
		(end 98.353735 144.718388)
		(width 0.1)
		(layer "In5.Cu")
		(net 185)
	)
	(segment
		(start 98.263639 144.375)
		(end 98.285891 144.372492)
		(width 0.1)
		(layer "In5.Cu")
		(net 185)
	)
	(segment
		(start 97.777507 144.852747)
		(end 97.784903 144.831611)
		(width 0.1)
		(layer "In5.Cu")
		(net 185)
	)
	(segment
		(start 97.775 127.175)
		(end 98.275 126.675)
		(width 0.1)
		(layer "In5.Cu")
		(net 185)
	)
	(segment
		(start 97.852747 144.172492)
		(end 97.831611 144.165096)
		(width 0.1)
		(layer "In5.Cu")
		(net 185)
	)
	(segment
		(start 98.353735 144.718388)
		(end 98.361131 144.697252)
		(width 0.1)
		(layer "In5.Cu")
		(net 185)
	)
	(segment
		(start 97.777507 144.097252)
		(end 97.775 144.075)
		(width 0.1)
		(layer "In5.Cu")
		(net 185)
	)
	(segment
		(start 98.361131 144.297252)
		(end 98.363639 144.275)
		(width 0.1)
		(layer "In5.Cu")
		(net 185)
	)
	(segment
		(start 96.864109 144.572492)
		(end 96.842973 144.565096)
		(width 0.1)
		(layer "In5.Cu")
		(net 185)
	)
	(segment
		(start 97.812651 144.796816)
		(end 97.831611 144.784903)
		(width 0.1)
		(layer "In5.Cu")
		(net 185)
	)
	(segment
		(start 98.325987 144.753183)
		(end 98.341822 144.737348)
		(width 0.1)
		(layer "In5.Cu")
		(net 185)
	)
	(segment
		(start 97.875 144.175)
		(end 97.852747 144.172492)
		(width 0.1)
		(layer "In5.Cu")
		(net 185)
	)
	(segment
		(start 98.307027 144.365096)
		(end 98.325987 144.353183)
		(width 0.1)
		(layer "In5.Cu")
		(net 185)
	)
	(segment
		(start 96.788869 144.497252)
		(end 96.786361 144.475)
		(width 0.1)
		(layer "In5.Cu")
		(net 185)
	)
	(segment
		(start 98.285891 144.372492)
		(end 98.307027 144.365096)
		(width 0.1)
		(layer "In5.Cu")
		(net 185)
	)
	(segment
		(start 96.886361 144.375)
		(end 98.263639 144.375)
		(width 0.1)
		(layer "In5.Cu")
		(net 185)
	)
	(segment
		(start 96.788869 144.452747)
		(end 96.796265 144.431611)
		(width 0.1)
		(layer "In5.Cu")
		(net 185)
	)
	(segment
		(start 96.864109 144.377507)
		(end 96.886361 144.375)
		(width 0.1)
		(layer "In5.Cu")
		(net 185)
	)
	(segment
		(start 97.831611 144.165096)
		(end 97.812651 144.153183)
		(width 0.1)
		(layer "In5.Cu")
		(net 185)
	)
	(segment
		(start 97.812651 144.153183)
		(end 97.796816 144.137348)
		(width 0.1)
		(layer "In5.Cu")
		(net 185)
	)
	(segment
		(start 97.796816 144.137348)
		(end 97.784903 144.118388)
		(width 0.1)
		(layer "In5.Cu")
		(net 185)
	)
	(segment
		(start 98.341822 144.212651)
		(end 98.325987 144.196816)
		(width 0.1)
		(layer "In5.Cu")
		(net 185)
	)
	(segment
		(start 97.775 144.075)
		(end 97.775 127.175)
		(width 0.1)
		(layer "In5.Cu")
		(net 185)
	)
	(segment
		(start 97.831611 144.784903)
		(end 97.852747 144.777507)
		(width 0.1)
		(layer "In5.Cu")
		(net 185)
	)
	(segment
		(start 98.353735 144.318388)
		(end 98.361131 144.297252)
		(width 0.1)
		(layer "In5.Cu")
		(net 185)
	)
	(segment
		(start 98.361131 144.697252)
		(end 98.363639 144.675)
		(width 0.1)
		(layer "In5.Cu")
		(net 185)
	)
	(segment
		(start 98.285891 144.177507)
		(end 98.263639 144.175)
		(width 0.1)
		(layer "In5.Cu")
		(net 185)
	)
	(segment
		(start 98.285891 144.772492)
		(end 98.307027 144.765096)
		(width 0.1)
		(layer "In5.Cu")
		(net 185)
	)
	(segment
		(start 98.263639 144.175)
		(end 97.875 144.175)
		(width 0.1)
		(layer "In5.Cu")
		(net 185)
	)
	(segment
		(start 97.852747 144.777507)
		(end 97.875 144.775)
		(width 0.1)
		(layer "In5.Cu")
		(net 185)
	)
	(segment
		(start 97.796816 144.812651)
		(end 97.812651 144.796816)
		(width 0.1)
		(layer "In5.Cu")
		(net 185)
	)
	(segment
		(start 98.325987 144.596816)
		(end 98.307027 144.584903)
		(width 0.1)
		(layer "In5.Cu")
		(net 185)
	)
	(segment
		(start 98.263639 144.775)
		(end 98.285891 144.772492)
		(width 0.1)
		(layer "In5.Cu")
		(net 185)
	)
	(segment
		(start 97.784903 144.118388)
		(end 97.777507 144.097252)
		(width 0.1)
		(layer "In5.Cu")
		(net 185)
	)
	(segment
		(start 98.341822 144.612651)
		(end 98.325987 144.596816)
		(width 0.1)
		(layer "In5.Cu")
		(net 185)
	)
	(segment
		(start 97.775 144.875)
		(end 97.777507 144.852747)
		(width 0.1)
		(layer "In5.Cu")
		(net 185)
	)
	(segment
		(start 96.808178 144.412651)
		(end 96.824013 144.396816)
		(width 0.1)
		(layer "In5.Cu")
		(net 185)
	)
	(segment
		(start 97.775 146.174998)
		(end 97.775 144.875)
		(width 0.1)
		(layer "In5.Cu")
		(net 185)
	)
	(segment
		(start 98.363639 144.275)
		(end 98.361131 144.252747)
		(width 0.1)
		(layer "In5.Cu")
		(net 185)
	)
	(segment
		(start 98.353735 144.231611)
		(end 98.341822 144.212651)
		(width 0.1)
		(layer "In5.Cu")
		(net 185)
	)
	(segment
		(start 96.886361 144.575)
		(end 96.864109 144.572492)
		(width 0.1)
		(layer "In5.Cu")
		(net 185)
	)
	(segment
		(start 98.361131 144.252747)
		(end 98.353735 144.231611)
		(width 0.1)
		(layer "In5.Cu")
		(net 185)
	)
	(segment
		(start 98.363639 144.675)
		(end 98.361131 144.652747)
		(width 0.1)
		(layer "In5.Cu")
		(net 185)
	)
	(segment
		(start 98.361131 144.652747)
		(end 98.353735 144.631611)
		(width 0.1)
		(layer "In5.Cu")
		(net 185)
	)
	(segment
		(start 98.307027 144.584903)
		(end 98.285891 144.577507)
		(width 0.1)
		(layer "In5.Cu")
		(net 185)
	)
	(segment
		(start 96.796265 144.431611)
		(end 96.808178 144.412651)
		(width 0.1)
		(layer "In5.Cu")
		(net 185)
	)
	(segment
		(start 98.307027 144.184903)
		(end 98.285891 144.177507)
		(width 0.1)
		(layer "In5.Cu")
		(net 185)
	)
	(segment
		(start 96.842973 144.384903)
		(end 96.864109 144.377507)
		(width 0.1)
		(layer "In5.Cu")
		(net 185)
	)
	(segment
		(start 97.775 128.175)
		(end 97.275 128.675)
		(width 0.15)
		(layer "F.Cu")
		(net 186)
	)
	(segment
		(start 97.375 144.375)
		(end 97.375 143.375)
		(width 0.1)
		(layer "F.Cu")
		(net 186)
	)
	(segment
		(start 97.775 144.775)
		(end 97.375 144.375)
		(width 0.1)
		(layer "F.Cu")
		(net 186)
	)
	(via blind
		(at 97.275 128.675)
		(size 0.5)
		(drill 0.2)
		(layers "F.Cu" "In2.Cu")
		(net 186)
	)
	(via blind
		(at 97.375 143.375)
		(size 0.5)
		(drill 0.2)
		(layers "F.Cu" "In2.Cu")
		(net 186)
	)
	(segment
		(start 97.13713 141.753212)
		(end 97.152943 141.737399)
		(width 0.1)
		(layer "In2.Cu")
		(net 186)
	)
	(segment
		(start 96.831805 139.16511)
		(end 96.81287 139.153212)
		(width 0.1)
		(layer "In2.Cu")
		(net 186)
	)
	(segment
		(start 96.785159 141.918464)
		(end 96.777773 141.897357)
		(width 0.1)
		(layer "In2.Cu")
		(net 186)
	)
	(segment
		(start 96.797057 138.337399)
		(end 96.785159 138.318464)
		(width 0.1)
		(layer "In2.Cu")
		(net 186)
	)
	(segment
		(start 97.152943 139.337399)
		(end 97.164841 139.318464)
		(width 0.1)
		(layer "In2.Cu")
		(net 186)
	)
	(segment
		(start 97.152943 137.737399)
		(end 97.164841 137.718464)
		(width 0.1)
		(layer "In2.Cu")
		(net 186)
	)
	(segment
		(start 97.118195 141.184889)
		(end 97.097088 141.177503)
		(width 0.1)
		(layer "In2.Cu")
		(net 186)
	)
	(segment
		(start 96.831805 141.16511)
		(end 96.81287 141.153212)
		(width 0.1)
		(layer "In2.Cu")
		(net 186)
	)
	(segment
		(start 97.118195 137.76511)
		(end 97.13713 137.753212)
		(width 0.1)
		(layer "In2.Cu")
		(net 186)
	)
	(segment
		(start 96.852912 138.372496)
		(end 96.831805 138.36511)
		(width 0.1)
		(layer "In2.Cu")
		(net 186)
	)
	(segment
		(start 96.852912 142.177503)
		(end 96.875134 142.175)
		(width 0.1)
		(layer "In2.Cu")
		(net 186)
	)
	(segment
		(start 97.074866 141.375)
		(end 97.097088 141.372496)
		(width 0.1)
		(layer "In2.Cu")
		(net 186)
	)
	(segment
		(start 97.118195 139.184889)
		(end 97.097088 139.177503)
		(width 0.1)
		(layer "In2.Cu")
		(net 186)
	)
	(segment
		(start 97.074866 141.775)
		(end 97.097088 141.772496)
		(width 0.1)
		(layer "In2.Cu")
		(net 186)
	)
	(segment
		(start 96.852912 139.572496)
		(end 96.831805 139.56511)
		(width 0.1)
		(layer "In2.Cu")
		(net 186)
	)
	(segment
		(start 96.775269 138.674865)
		(end 96.777773 138.652642)
		(width 0.1)
		(layer "In2.Cu")
		(net 186)
	)
	(segment
		(start 97.118195 140.16511)
		(end 97.13713 140.153212)
		(width 0.1)
		(layer "In2.Cu")
		(net 186)
	)
	(segment
		(start 96.777773 142.297357)
		(end 96.775269 142.275135)
		(width 0.1)
		(layer "In2.Cu")
		(net 186)
	)
	(segment
		(start 96.852912 141.572496)
		(end 96.831805 141.56511)
		(width 0.1)
		(layer "In2.Cu")
		(net 186)
	)
	(segment
		(start 97.152943 139.6126)
		(end 97.13713 139.596787)
		(width 0.1)
		(layer "In2.Cu")
		(net 186)
	)
	(segment
		(start 97.152943 138.937399)
		(end 97.164841 138.918464)
		(width 0.1)
		(layer "In2.Cu")
		(net 186)
	)
	(segment
		(start 97.097088 138.972496)
		(end 97.118195 138.96511)
		(width 0.1)
		(layer "In2.Cu")
		(net 186)
	)
	(segment
		(start 96.775269 138.275135)
		(end 96.775269 138.274865)
		(width 0.1)
		(layer "In2.Cu")
		(net 186)
	)
	(segment
		(start 97.164841 137.718464)
		(end 97.172227 137.697357)
		(width 0.1)
		(layer "In2.Cu")
		(net 186)
	)
	(segment
		(start 97.097088 142.572631)
		(end 97.118195 142.565245)
		(width 0.1)
		(layer "In2.Cu")
		(net 186)
	)
	(segment
		(start 97.074866 138.975)
		(end 97.097088 138.972496)
		(width 0.1)
		(layer "In2.Cu")
		(net 186)
	)
	(segment
		(start 97.13713 140.553212)
		(end 97.152943 140.537399)
		(width 0.1)
		(layer "In2.Cu")
		(net 186)
	)
	(segment
		(start 97.172227 139.697357)
		(end 97.174731 139.675135)
		(width 0.1)
		(layer "In2.Cu")
		(net 186)
	)
	(segment
		(start 96.785159 141.118464)
		(end 96.777773 141.097357)
		(width 0.1)
		(layer "In2.Cu")
		(net 186)
	)
	(segment
		(start 96.81287 139.153212)
		(end 96.797057 139.137399)
		(width 0.1)
		(layer "In2.Cu")
		(net 186)
	)
	(segment
		(start 97.164841 141.631535)
		(end 97.152943 141.6126)
		(width 0.1)
		(layer "In2.Cu")
		(net 186)
	)
	(segment
		(start 97.174731 140.474865)
		(end 97.172227 140.452642)
		(width 0.1)
		(layer "In2.Cu")
		(net 186)
	)
	(segment
		(start 96.785159 139.031535)
		(end 96.797057 139.0126)
		(width 0.1)
		(layer "In2.Cu")
		(net 186)
	)
	(segment
		(start 96.775269 141.474865)
		(end 96.777773 141.452642)
		(width 0.1)
		(layer "In2.Cu")
		(net 186)
	)
	(segment
		(start 97.118195 140.784889)
		(end 97.097088 140.777503)
		(width 0.1)
		(layer "In2.Cu")
		(net 186)
	)
	(segment
		(start 96.831805 138.36511)
		(end 96.81287 138.353212)
		(width 0.1)
		(layer "In2.Cu")
		(net 186)
	)
	(segment
		(start 97.13713 142.153212)
		(end 97.152943 142.137399)
		(width 0.1)
		(layer "In2.Cu")
		(net 186)
	)
	(segment
		(start 97.13713 140.953212)
		(end 97.152943 140.937399)
		(width 0.1)
		(layer "In2.Cu")
		(net 186)
	)
	(segment
		(start 97.172227 140.497357)
		(end 97.174731 140.475135)
		(width 0.1)
		(layer "In2.Cu")
		(net 186)
	)
	(segment
		(start 96.785159 138.718464)
		(end 96.777773 138.697357)
		(width 0.1)
		(layer "In2.Cu")
		(net 186)
	)
	(segment
		(start 96.852912 137.972496)
		(end 96.831805 137.96511)
		(width 0.1)
		(layer "In2.Cu")
		(net 186)
	)
	(segment
		(start 97.118195 139.36511)
		(end 97.13713 139.353212)
		(width 0.1)
		(layer "In2.Cu")
		(net 186)
	)
	(segment
		(start 97.0126 142.596922)
		(end 97.031535 142.585024)
		(width 0.1)
		(layer "In2.Cu")
		(net 186)
	)
	(segment
		(start 96.831805 140.76511)
		(end 96.81287 140.753212)
		(width 0.1)
		(layer "In2.Cu")
		(net 186)
	)
	(segment
		(start 96.81287 140.353212)
		(end 96.797057 140.337399)
		(width 0.1)
		(layer "In2.Cu")
		(net 186)
	)
	(segment
		(start 97.174731 141.674865)
		(end 97.172227 141.652642)
		(width 0.1)
		(layer "In2.Cu")
		(net 186)
	)
	(segment
		(start 97.164841 140.518464)
		(end 97.172227 140.497357)
		(width 0.1)
		(layer "In2.Cu")
		(net 186)
	)
	(segment
		(start 97.164841 140.031535)
		(end 97.152943 140.0126)
		(width 0.1)
		(layer "In2.Cu")
		(net 186)
	)
	(segment
		(start 97.118195 140.96511)
		(end 97.13713 140.953212)
		(width 0.1)
		(layer "In2.Cu")
		(net 186)
	)
	(segment
		(start 97.074866 138.375)
		(end 96.875134 138.375)
		(width 0.1)
		(layer "In2.Cu")
		(net 186)
	)
	(segment
		(start 96.785159 142.231535)
		(end 96.797057 142.2126)
		(width 0.1)
		(layer "In2.Cu")
		(net 186)
	)
	(segment
		(start 96.785159 139.118464)
		(end 96.777773 139.097357)
		(width 0.1)
		(layer "In2.Cu")
		(net 186)
	)
	(segment
		(start 97.097088 141.577503)
		(end 97.074866 141.575)
		(width 0.1)
		(layer "In2.Cu")
		(net 186)
	)
	(segment
		(start 96.785159 138.631535)
		(end 96.797057 138.6126)
		(width 0.1)
		(layer "In2.Cu")
		(net 186)
	)
	(segment
		(start 97.152943 138.137399)
		(end 97.164841 138.118464)
		(width 0.1)
		(layer "In2.Cu")
		(net 186)
	)
	(segment
		(start 97.074866 138.575)
		(end 97.097088 138.572496)
		(width 0.1)
		(layer "In2.Cu")
		(net 186)
	)
	(segment
		(start 96.81287 141.553212)
		(end 96.797057 141.537399)
		(width 0.1)
		(layer "In2.Cu")
		(net 186)
	)
	(segment
		(start 97.152943 142.412735)
		(end 97.13713 142.396922)
		(width 0.1)
		(layer "In2.Cu")
		(net 186)
	)
	(segment
		(start 96.785159 140.631535)
		(end 96.797057 140.6126)
		(width 0.1)
		(layer "In2.Cu")
		(net 186)
	)
	(segment
		(start 97.152943 142.537534)
		(end 97.164841 142.518599)
		(width 0.1)
		(layer "In2.Cu")
		(net 186)
	)
	(segment
		(start 97.174731 140.874865)
		(end 97.172227 140.852642)
		(width 0.1)
		(layer "In2.Cu")
		(net 186)
	)
	(segment
		(start 96.81287 139.953212)
		(end 96.797057 139.937399)
		(width 0.1)
		(layer "In2.Cu")
		(net 186)
	)
	(segment
		(start 96.975 137.475135)
		(end 96.975 128.975)
		(width 0.1)
		(layer "In2.Cu")
		(net 186)
	)
	(segment
		(start 96.81287 139.396787)
		(end 96.831805 139.384889)
		(width 0.1)
		(layer "In2.Cu")
		(net 186)
	)
	(segment
		(start 96.775269 139.474865)
		(end 96.777773 139.452642)
		(width 0.1)
		(layer "In2.Cu")
		(net 186)
	)
	(segment
		(start 97.164841 138.118464)
		(end 97.172227 138.097357)
		(width 0.1)
		(layer "In2.Cu")
		(net 186)
	)
	(segment
		(start 97.152943 141.2126)
		(end 97.13713 141.196787)
		(width 0.1)
		(layer "In2.Cu")
		(net 186)
	)
	(segment
		(start 97.172227 139.297357)
		(end 97.174731 139.275135)
		(width 0.1)
		(layer "In2.Cu")
		(net 186)
	)
	(segment
		(start 96.852912 141.172496)
		(end 96.831805 141.16511)
		(width 0.1)
		(layer "In2.Cu")
		(net 186)
	)
	(segment
		(start 97.074866 137.775)
		(end 97.097088 137.772496)
		(width 0.1)
		(layer "In2.Cu")
		(net 186)
	)
	(segment
		(start 97.152943 137.6126)
		(end 97.13713 137.596787)
		(width 0.1)
		(layer "In2.Cu")
		(net 186)
	)
	(segment
		(start 97.172227 138.897357)
		(end 97.174731 138.875135)
		(width 0.1)
		(layer "In2.Cu")
		(net 186)
	)
	(segment
		(start 97.152943 140.137399)
		(end 97.164841 140.118464)
		(width 0.1)
		(layer "In2.Cu")
		(net 186)
	)
	(segment
		(start 96.785159 137.918464)
		(end 96.777773 137.897357)
		(width 0.1)
		(layer "In2.Cu")
		(net 186)
	)
	(segment
		(start 96.777773 141.497357)
		(end 96.775269 141.475135)
		(width 0.1)
		(layer "In2.Cu")
		(net 186)
	)
	(segment
		(start 97.097088 141.977503)
		(end 97.074866 141.975)
		(width 0.1)
		(layer "In2.Cu")
		(net 186)
	)
	(segment
		(start 96.831805 140.36511)
		(end 96.81287 140.353212)
		(width 0.1)
		(layer "In2.Cu")
		(net 186)
	)
	(segment
		(start 97.13713 139.753212)
		(end 97.152943 139.737399)
		(width 0.1)
		(layer "In2.Cu")
		(net 186)
	)
	(segment
		(start 97.097088 141.772496)
		(end 97.118195 141.76511)
		(width 0.1)
		(layer "In2.Cu")
		(net 186)
	)
	(segment
		(start 97.152943 138.8126)
		(end 97.13713 138.796787)
		(width 0.1)
		(layer "In2.Cu")
		(net 186)
	)
	(segment
		(start 96.775269 141.875135)
		(end 96.775269 141.874865)
		(width 0.1)
		(layer "In2.Cu")
		(net 186)
	)
	(segment
		(start 96.797057 137.937399)
		(end 96.785159 137.918464)
		(width 0.1)
		(layer "In2.Cu")
		(net 186)
	)
	(segment
		(start 96.996787 142.612735)
		(end 97.0126 142.596922)
		(width 0.1)
		(layer "In2.Cu")
		(net 186)
	)
	(segment
		(start 97.174731 139.674865)
		(end 97.172227 139.652642)
		(width 0.1)
		(layer "In2.Cu")
		(net 186)
	)
	(segment
		(start 97.152943 142.0126)
		(end 97.13713 141.996787)
		(width 0.1)
		(layer "In2.Cu")
		(net 186)
	)
	(segment
		(start 96.797057 141.137399)
		(end 96.785159 141.118464)
		(width 0.1)
		(layer "In2.Cu")
		(net 186)
	)
	(segment
		(start 96.797057 141.0126)
		(end 96.81287 140.996787)
		(width 0.1)
		(layer "In2.Cu")
		(net 186)
	)
	(segment
		(start 97.118195 141.984889)
		(end 97.097088 141.977503)
		(width 0.1)
		(layer "In2.Cu")
		(net 186)
	)
	(segment
		(start 96.775269 138.675135)
		(end 96.775269 138.674865)
		(width 0.1)
		(layer "In2.Cu")
		(net 186)
	)
	(segment
		(start 96.875134 138.775)
		(end 96.852912 138.772496)
		(width 0.1)
		(layer "In2.Cu")
		(net 186)
	)
	(segment
		(start 97.164841 139.631535)
		(end 97.152943 139.6126)
		(width 0.1)
		(layer "In2.Cu")
		(net 186)
	)
	(segment
		(start 96.996787 137.537399)
		(end 96.984889 137.518464)
		(width 0.1)
		(layer "In2.Cu")
		(net 186)
	)
	(segment
		(start 97.164841 139.231535)
		(end 97.152943 139.2126)
		(width 0.1)
		(layer "In2.Cu")
		(net 186)
	)
	(segment
		(start 97.052642 142.577638)
		(end 97.097088 142.572631)
		(width 0.1)
		(layer "In2.Cu")
		(net 186)
	)
	(segment
		(start 96.785159 140.231535)
		(end 96.797057 140.2126)
		(width 0.1)
		(layer "In2.Cu")
		(net 186)
	)
	(segment
		(start 96.777773 141.852642)
		(end 96.785159 141.831535)
		(width 0.1)
		(layer "In2.Cu")
		(net 186)
	)
	(segment
		(start 97.13713 137.596787)
		(end 97.118195 137.584889)
		(width 0.1)
		(layer "In2.Cu")
		(net 186)
	)
	(segment
		(start 97.174731 142.074865)
		(end 97.172227 142.052642)
		(width 0.1)
		(layer "In2.Cu")
		(net 186)
	)
	(segment
		(start 97.13713 142.553347)
		(end 97.152943 142.537534)
		(width 0.1)
		(layer "In2.Cu")
		(net 186)
	)
	(segment
		(start 97.097088 138.572496)
		(end 97.118195 138.56511)
		(width 0.1)
		(layer "In2.Cu")
		(net 186)
	)
	(segment
		(start 96.775269 140.275135)
		(end 96.775269 140.274865)
		(width 0.1)
		(layer "In2.Cu")
		(net 186)
	)
	(segment
		(start 96.775269 139.075135)
		(end 96.775269 139.074865)
		(width 0.1)
		(layer "In2.Cu")
		(net 186)
	)
	(segment
		(start 96.785159 141.031535)
		(end 96.797057 141.0126)
		(width 0.1)
		(layer "In2.Cu")
		(net 186)
	)
	(segment
		(start 96.81287 140.753212)
		(end 96.797057 140.737399)
		(width 0.1)
		(layer "In2.Cu")
		(net 186)
	)
	(segment
		(start 96.875134 138.175)
		(end 97.074866 138.175)
		(width 0.1)
		(layer "In2.Cu")
		(net 186)
	)
	(segment
		(start 96.975 142.675)
		(end 96.977503 142.652777)
		(width 0.1)
		(layer "In2.Cu")
		(net 186)
	)
	(segment
		(start 97.118195 137.984889)
		(end 97.097088 137.977503)
		(width 0.1)
		(layer "In2.Cu")
		(net 186)
	)
	(segment
		(start 97.074866 142.175)
		(end 97.097088 142.172496)
		(width 0.1)
		(layer "In2.Cu")
		(net 186)
	)
	(segment
		(start 96.785159 142.318464)
		(end 96.777773 142.297357)
		(width 0.1)
		(layer "In2.Cu")
		(net 186)
	)
	(segment
		(start 97.097088 139.177503)
		(end 97.074866 139.175)
		(width 0.1)
		(layer "In2.Cu")
		(net 186)
	)
	(segment
		(start 96.785159 138.231535)
		(end 96.797057 138.2126)
		(width 0.1)
		(layer "In2.Cu")
		(net 186)
	)
	(segment
		(start 97.13713 138.796787)
		(end 97.118195 138.784889)
		(width 0.1)
		(layer "In2.Cu")
		(net 186)
	)
	(segment
		(start 96.777773 138.297357)
		(end 96.775269 138.275135)
		(width 0.1)
		(layer "In2.Cu")
		(net 186)
	)
	(segment
		(start 97.164841 140.831535)
		(end 97.152943 140.8126)
		(width 0.1)
		(layer "In2.Cu")
		(net 186)
	)
	(segment
		(start 96.852912 139.972496)
		(end 96.831805 139.96511)
		(width 0.1)
		(layer "In2.Cu")
		(net 186)
	)
	(segment
		(start 97.13713 140.396787)
		(end 97.118195 140.384889)
		(width 0.1)
		(layer "In2.Cu")
		(net 186)
	)
	(segment
		(start 96.777773 139.897357)
		(end 96.775269 139.875135)
		(width 0.1)
		(layer "In2.Cu")
		(net 186)
	)
	(segment
		(start 97.174731 139.274865)
		(end 97.172227 139.252642)
		(width 0.1)
		(layer "In2.Cu")
		(net 186)
	)
	(segment
		(start 97.164841 140.918464)
		(end 97.172227 140.897357)
		(width 0.1)
		(layer "In2.Cu")
		(net 186)
	)
	(segment
		(start 97.152943 138.0126)
		(end 97.13713 137.996787)
		(width 0.1)
		(layer "In2.Cu")
		(net 186)
	)
	(segment
		(start 96.852912 138.977503)
		(end 96.875134 138.975)
		(width 0.1)
		(layer "In2.Cu")
		(net 186)
	)
	(segment
		(start 96.831805 138.184889)
		(end 96.852912 138.177503)
		(width 0.1)
		(layer "In2.Cu")
		(net 186)
	)
	(segment
		(start 97.074866 139.775)
		(end 97.097088 139.772496)
		(width 0.1)
		(layer "In2.Cu")
		(net 186)
	)
	(segment
		(start 96.797057 142.337399)
		(end 96.785159 142.318464)
		(width 0.1)
		(layer "In2.Cu")
		(net 186)
	)
	(segment
		(start 96.797057 137.8126)
		(end 96.81287 137.796787)
		(width 0.1)
		(layer "In2.Cu")
		(net 186)
	)
	(segment
		(start 96.831805 139.96511)
		(end 96.81287 139.953212)
		(width 0.1)
		(layer "In2.Cu")
		(net 186)
	)
	(segment
		(start 96.852912 139.777503)
		(end 96.875134 139.775)
		(width 0.1)
		(layer "In2.Cu")
		(net 186)
	)
	(segment
		(start 96.831805 141.384889)
		(end 96.852912 141.377503)
		(width 0.1)
		(layer "In2.Cu")
		(net 186)
	)
	(segment
		(start 97.074866 138.175)
		(end 97.097088 138.172496)
		(width 0.1)
		(layer "In2.Cu")
		(net 186)
	)
	(segment
		(start 97.152943 139.2126)
		(end 97.13713 139.196787)
		(width 0.1)
		(layer "In2.Cu")
		(net 186)
	)
	(segment
		(start 97.172227 142.097357)
		(end 97.174731 142.075135)
		(width 0.1)
		(layer "In2.Cu")
		(net 186)
	)
	(segment
		(start 97.118195 139.984889)
		(end 97.097088 139.977503)
		(width 0.1)
		(layer "In2.Cu")
		(net 186)
	)
	(segment
		(start 97.074866 139.575)
		(end 96.875134 139.575)
		(width 0.1)
		(layer "In2.Cu")
		(net 186)
	)
	(segment
		(start 97.164841 141.231535)
		(end 97.152943 141.2126)
		(width 0.1)
		(layer "In2.Cu")
		(net 186)
	)
	(segment
		(start 97.13713 140.796787)
		(end 97.118195 140.784889)
		(width 0.1)
		(layer "In2.Cu")
		(net 186)
	)
	(segment
		(start 97.074866 140.975)
		(end 97.097088 140.972496)
		(width 0.1)
		(layer "In2.Cu")
		(net 186)
	)
	(segment
		(start 96.81287 137.796787)
		(end 96.831805 137.784889)
		(width 0.1)
		(layer "In2.Cu")
		(net 186)
	)
	(segment
		(start 96.797057 140.6126)
		(end 96.81287 140.596787)
		(width 0.1)
		(layer "In2.Cu")
		(net 186)
	)
	(segment
		(start 96.775269 142.275135)
		(end 96.775269 142.274865)
		(width 0.1)
		(layer "In2.Cu")
		(net 186)
	)
	(segment
		(start 96.775269 137.874865)
		(end 96.777773 137.852642)
		(width 0.1)
		(layer "In2.Cu")
		(net 186)
	)
	(segment
		(start 96.852912 137.777503)
		(end 96.875134 137.775)
		(width 0.1)
		(layer "In2.Cu")
		(net 186)
	)
	(segment
		(start 97.13713 138.396787)
		(end 97.118195 138.384889)
		(width 0.1)
		(layer "In2.Cu")
		(net 186)
	)
	(segment
		(start 97.152943 139.737399)
		(end 97.164841 139.718464)
		(width 0.1)
		(layer "In2.Cu")
		(net 186)
	)
	(segment
		(start 97.097088 141.177503)
		(end 97.074866 141.175)
		(width 0.1)
		(layer "In2.Cu")
		(net 186)
	)
	(segment
		(start 96.777773 141.897357)
		(end 96.775269 141.875135)
		(width 0.1)
		(layer "In2.Cu")
		(net 186)
	)
	(segment
		(start 96.875134 138.575)
		(end 97.074866 138.575)
		(width 0.1)
		(layer "In2.Cu")
		(net 186)
	)
	(segment
		(start 96.975 128.975)
		(end 97.275 128.675)
		(width 0.1)
		(layer "In2.Cu")
		(net 186)
	)
	(segment
		(start 97.172227 138.852642)
		(end 97.164841 138.831535)
		(width 0.1)
		(layer "In2.Cu")
		(net 186)
	)
	(segment
		(start 96.852912 139.172496)
		(end 96.831805 139.16511)
		(width 0.1)
		(layer "In2.Cu")
		(net 186)
	)
	(segment
		(start 97.118195 138.96511)
		(end 97.13713 138.953212)
		(width 0.1)
		(layer "In2.Cu")
		(net 186)
	)
	(segment
		(start 96.875134 138.975)
		(end 97.074866 138.975)
		(width 0.1)
		(layer "In2.Cu")
		(net 186)
	)
	(segment
		(start 96.81287 141.796787)
		(end 96.831805 141.784889)
		(width 0.1)
		(layer "In2.Cu")
		(net 186)
	)
	(segment
		(start 97.052642 137.572496)
		(end 97.031535 137.56511)
		(width 0.1)
		(layer "In2.Cu")
		(net 186)
	)
	(segment
		(start 96.875134 140.775)
		(end 96.852912 140.772496)
		(width 0.1)
		(layer "In2.Cu")
		(net 186)
	)
	(segment
		(start 96.975 142.975)
		(end 96.975 142.675)
		(width 0.1)
		(layer "In2.Cu")
		(net 186)
	)
	(segment
		(start 96.831805 137.784889)
		(end 96.852912 137.777503)
		(width 0.1)
		(layer "In2.Cu")
		(net 186)
	)
	(segment
		(start 97.13713 139.996787)
		(end 97.118195 139.984889)
		(width 0.1)
		(layer "In2.Cu")
		(net 186)
	)
	(segment
		(start 97.074865 142.375135)
		(end 96.975 142.375135)
		(width 0.1)
		(layer "In2.Cu")
		(net 186)
	)
	(segment
		(start 97.097088 137.977503)
		(end 97.074866 137.975)
		(width 0.1)
		(layer "In2.Cu")
		(net 186)
	)
	(segment
		(start 96.831805 139.384889)
		(end 96.852912 139.377503)
		(width 0.1)
		(layer "In2.Cu")
		(net 186)
	)
	(segment
		(start 96.875134 140.975)
		(end 97.074866 140.975)
		(width 0.1)
		(layer "In2.Cu")
		(net 186)
	)
	(segment
		(start 97.097088 142.172496)
		(end 97.118195 142.16511)
		(width 0.1)
		(layer "In2.Cu")
		(net 186)
	)
	(segment
		(start 97.13713 139.596787)
		(end 97.118195 139.584889)
		(width 0.1)
		(layer "In2.Cu")
		(net 186)
	)
	(segment
		(start 97.097088 137.577503)
		(end 97.052642 137.572496)
		(width 0.1)
		(layer "In2.Cu")
		(net 186)
	)
	(segment
		(start 96.977503 137.497357)
		(end 96.975 137.475135)
		(width 0.1)
		(layer "In2.Cu")
		(net 186)
	)
	(segment
		(start 97.097088 138.777503)
		(end 97.074866 138.775)
		(width 0.1)
		(layer "In2.Cu")
		(net 186)
	)
	(segment
		(start 97.118195 137.584889)
		(end 97.097088 137.577503)
		(width 0.1)
		(layer "In2.Cu")
		(net 186)
	)
	(segment
		(start 97.172227 138.497357)
		(end 97.174731 138.475135)
		(width 0.1)
		(layer "In2.Cu")
		(net 186)
	)
	(segment
		(start 96.797057 139.137399)
		(end 96.785159 139.118464)
		(width 0.1)
		(layer "In2.Cu")
		(net 186)
	)
	(segment
		(start 97.031535 142.585024)
		(end 97.052642 142.577638)
		(width 0.1)
		(layer "In2.Cu")
		(net 186)
	)
	(segment
		(start 97.074866 137.975)
		(end 96.875134 137.975)
		(width 0.1)
		(layer "In2.Cu")
		(net 186)
	)
	(segment
		(start 96.81287 138.596787)
		(end 96.831805 138.584889)
		(width 0.1)
		(layer "In2.Cu")
		(net 186)
	)
	(segment
		(start 96.785159 139.431535)
		(end 96.797057 139.4126)
		(width 0.1)
		(layer "In2.Cu")
		(net 186)
	)
	(segment
		(start 97.174731 137.675135)
		(end 97.174731 137.674865)
		(width 0.1)
		(layer "In2.Cu")
		(net 186)
	)
	(segment
		(start 97.164841 142.518599)
		(end 97.172227 142.497492)
		(width 0.1)
		(layer "In2.Cu")
		(net 186)
	)
	(segment
		(start 96.852912 141.972496)
		(end 96.831805 141.96511)
		(width 0.1)
		(layer "In2.Cu")
		(net 186)
	)
	(segment
		(start 97.172227 139.652642)
		(end 97.164841 139.631535)
		(width 0.1)
		(layer "In2.Cu")
		(net 186)
	)
	(segment
		(start 97.172227 139.252642)
		(end 97.164841 139.231535)
		(width 0.1)
		(layer "In2.Cu")
		(net 186)
	)
	(segment
		(start 96.797057 139.537399)
		(end 96.785159 139.518464)
		(width 0.1)
		(layer "In2.Cu")
		(net 186)
	)
	(segment
		(start 97.174731 139.675135)
		(end 97.174731 139.674865)
		(width 0.1)
		(layer "In2.Cu")
		(net 186)
	)
	(segment
		(start 96.852912 142.372496)
		(end 96.831805 142.36511)
		(width 0.1)
		(layer "In2.Cu")
		(net 186)
	)
	(segment
		(start 96.831805 141.56511)
		(end 96.81287 141.553212)
		(width 0.1)
		(layer "In2.Cu")
		(net 186)
	)
	(segment
		(start 96.797057 140.337399)
		(end 96.785159 140.318464)
		(width 0.1)
		(layer "In2.Cu")
		(net 186)
	)
	(segment
		(start 96.831805 142.184889)
		(end 96.852912 142.177503)
		(width 0.1)
		(layer "In2.Cu")
		(net 186)
	)
	(segment
		(start 96.831805 138.76511)
		(end 96.81287 138.753212)
		(width 0.1)
		(layer "In2.Cu")
		(net 186)
	)
	(segment
		(start 96.875134 139.975)
		(end 96.852912 139.972496)
		(width 0.1)
		(layer "In2.Cu")
		(net 186)
	)
	(segment
		(start 97.174731 138.875135)
		(end 97.174731 138.874865)
		(width 0.1)
		(layer "In2.Cu")
		(net 186)
	)
	(segment
		(start 97.074866 140.775)
		(end 96.875134 140.775)
		(width 0.1)
		(layer "In2.Cu")
		(net 186)
	)
	(segment
		(start 97.172227 138.052642)
		(end 97.164841 138.031535)
		(width 0.1)
		(layer "In2.Cu")
		(net 186)
	)
	(segment
		(start 97.164841 139.718464)
		(end 97.172227 139.697357)
		(width 0.1)
		(layer "In2.Cu")
		(net 186)
	)
	(segment
		(start 97.174731 140.074865)
		(end 97.172227 140.052642)
		(width 0.1)
		(layer "In2.Cu")
		(net 186)
	)
	(segment
		(start 97.164841 141.718464)
		(end 97.172227 141.697357)
		(width 0.1)
		(layer "In2.Cu")
		(net 186)
	)
	(segment
		(start 97.174731 140.875135)
		(end 97.174731 140.874865)
		(width 0.1)
		(layer "In2.Cu")
		(net 186)
	)
	(segment
		(start 96.777773 139.052642)
		(end 96.785159 139.031535)
		(width 0.1)
		(layer "In2.Cu")
		(net 186)
	)
	(segment
		(start 97.152943 140.937399)
		(end 97.164841 140.918464)
		(width 0.1)
		(layer "In2.Cu")
		(net 186)
	)
	(segment
		(start 97.13713 141.996787)
		(end 97.118195 141.984889)
		(width 0.1)
		(layer "In2.Cu")
		(net 186)
	)
	(segment
		(start 96.984889 137.518464)
		(end 96.977503 137.497357)
		(width 0.1)
		(layer "In2.Cu")
		(net 186)
	)
	(segment
		(start 97.172227 141.652642)
		(end 97.164841 141.631535)
		(width 0.1)
		(layer "In2.Cu")
		(net 186)
	)
	(segment
		(start 97.097088 140.972496)
		(end 97.118195 140.96511)
		(width 0.1)
		(layer "In2.Cu")
		(net 186)
	)
	(segment
		(start 97.152943 140.0126)
		(end 97.13713 139.996787)
		(width 0.1)
		(layer "In2.Cu")
		(net 186)
	)
	(segment
		(start 97.13713 141.596787)
		(end 97.118195 141.584889)
		(width 0.1)
		(layer "In2.Cu")
		(net 186)
	)
	(segment
		(start 97.152943 141.6126)
		(end 97.13713 141.596787)
		(width 0.1)
		(layer "In2.Cu")
		(net 186)
	)
	(segment
		(start 96.797057 141.8126)
		(end 96.81287 141.796787)
		(width 0.1)
		(layer "In2.Cu")
		(net 186)
	)
	(segment
		(start 97.174731 141.274865)
		(end 97.172227 141.252642)
		(width 0.1)
		(layer "In2.Cu")
		(net 186)
	)
	(segment
		(start 96.777773 138.252642)
		(end 96.785159 138.231535)
		(width 0.1)
		(layer "In2.Cu")
		(net 186)
	)
	(segment
		(start 97.152943 140.8126)
		(end 97.13713 140.796787)
		(width 0.1)
		(layer "In2.Cu")
		(net 186)
	)
	(segment
		(start 97.118195 138.16511)
		(end 97.13713 138.153212)
		(width 0.1)
		(layer "In2.Cu")
		(net 186)
	)
	(segment
		(start 96.81287 139.553212)
		(end 96.797057 139.537399)
		(width 0.1)
		(layer "In2.Cu")
		(net 186)
	)
	(segment
		(start 97.074866 138.775)
		(end 96.875134 138.775)
		(width 0.1)
		(layer "In2.Cu")
		(net 186)
	)
	(segment
		(start 96.777773 141.097357)
		(end 96.775269 141.075135)
		(width 0.1)
		(layer "In2.Cu")
		(net 186)
	)
	(segment
		(start 96.852912 140.577503)
		(end 96.875134 140.575)
		(width 0.1)
		(layer "In2.Cu")
		(net 186)
	)
	(segment
		(start 96.785159 141.518464)
		(end 96.777773 141.497357)
		(width 0.1)
		(layer "In2.Cu")
		(net 186)
	)
	(segment
		(start 96.81287 141.153212)
		(end 96.797057 141.137399)
		(width 0.1)
		(layer "In2.Cu")
		(net 186)
	)
	(segment
		(start 97.172227 141.252642)
		(end 97.164841 141.231535)
		(width 0.1)
		(layer "In2.Cu")
		(net 186)
	)
	(segment
		(start 97.375 143.375)
		(end 96.975 142.975)
		(width 0.1)
		(layer "In2.Cu")
		(net 186)
	)
	(segment
		(start 97.097088 141.372496)
		(end 97.118195 141.36511)
		(width 0.1)
		(layer "In2.Cu")
		(net 186)
	)
	(segment
		(start 97.164841 138.831535)
		(end 97.152943 138.8126)
		(width 0.1)
		(layer "In2.Cu")
		(net 186)
	)
	(segment
		(start 96.785159 140.318464)
		(end 96.777773 140.297357)
		(width 0.1)
		(layer "In2.Cu")
		(net 186)
	)
	(segment
		(start 96.775269 139.475135)
		(end 96.775269 139.474865)
		(width 0.1)
		(layer "In2.Cu")
		(net 186)
	)
	(segment
		(start 97.097088 138.172496)
		(end 97.118195 138.16511)
		(width 0.1)
		(layer "In2.Cu")
		(net 186)
	)
	(segment
		(start 97.172227 141.297357)
		(end 97.174731 141.275135)
		(width 0.1)
		(layer "In2.Cu")
		(net 186)
	)
	(segment
		(start 96.875134 139.375)
		(end 97.074866 139.375)
		(width 0.1)
		(layer "In2.Cu")
		(net 186)
	)
	(segment
		(start 97.097088 140.777503)
		(end 97.074866 140.775)
		(width 0.1)
		(layer "In2.Cu")
		(net 186)
	)
	(segment
		(start 97.152943 140.4126)
		(end 97.13713 140.396787)
		(width 0.1)
		(layer "In2.Cu")
		(net 186)
	)
	(segment
		(start 96.831805 137.96511)
		(end 96.81287 137.953212)
		(width 0.1)
		(layer "In2.Cu")
		(net 186)
	)
	(segment
		(start 96.81287 138.196787)
		(end 96.831805 138.184889)
		(width 0.1)
		(layer "In2.Cu")
		(net 186)
	)
	(segment
		(start 96.797057 140.2126)
		(end 96.81287 140.196787)
		(width 0.1)
		(layer "In2.Cu")
		(net 186)
	)
	(segment
		(start 96.797057 140.737399)
		(end 96.785159 140.718464)
		(width 0.1)
		(layer "In2.Cu")
		(net 186)
	)
	(segment
		(start 96.797057 139.937399)
		(end 96.785159 139.918464)
		(width 0.1)
		(layer "In2.Cu")
		(net 186)
	)
	(segment
		(start 96.875134 140.375)
		(end 96.852912 140.372496)
		(width 0.1)
		(layer "In2.Cu")
		(net 186)
	)
	(segment
		(start 96.875134 138.375)
		(end 96.852912 138.372496)
		(width 0.1)
		(layer "In2.Cu")
		(net 186)
	)
	(segment
		(start 97.174731 142.47527)
		(end 97.174731 142.475)
		(width 0.1)
		(layer "In2.Cu")
		(net 186)
	)
	(segment
		(start 96.777773 139.452642)
		(end 96.785159 139.431535)
		(width 0.1)
		(layer "In2.Cu")
		(net 186)
	)
	(segment
		(start 97.074866 139.975)
		(end 96.875134 139.975)
		(width 0.1)
		(layer "In2.Cu")
		(net 186)
	)
	(segment
		(start 96.875134 141.175)
		(end 96.852912 141.172496)
		(width 0.1)
		(layer "In2.Cu")
		(net 186)
	)
	(segment
		(start 96.775269 140.674865)
		(end 96.777773 140.652642)
		(width 0.1)
		(layer "In2.Cu")
		(net 186)
	)
	(segment
		(start 96.852912 139.377503)
		(end 96.875134 139.375)
		(width 0.1)
		(layer "In2.Cu")
		(net 186)
	)
	(segment
		(start 96.81287 137.953212)
		(end 96.797057 137.937399)
		(width 0.1)
		(layer "In2.Cu")
		(net 186)
	)
	(segment
		(start 97.13713 138.553212)
		(end 97.152943 138.537399)
		(width 0.1)
		(layer "In2.Cu")
		(net 186)
	)
	(segment
		(start 96.852912 140.772496)
		(end 96.831805 140.76511)
		(width 0.1)
		(layer "In2.Cu")
		(net 186)
	)
	(segment
		(start 97.13713 141.353212)
		(end 97.152943 141.337399)
		(width 0.1)
		(layer "In2.Cu")
		(net 186)
	)
	(segment
		(start 96.785159 138.318464)
		(end 96.777773 138.297357)
		(width 0.1)
		(layer "In2.Cu")
		(net 186)
	)
	(segment
		(start 96.775269 140.675135)
		(end 96.775269 140.674865)
		(width 0.1)
		(layer "In2.Cu")
		(net 186)
	)
	(segment
		(start 96.81287 140.196787)
		(end 96.831805 140.184889)
		(width 0.1)
		(layer "In2.Cu")
		(net 186)
	)
	(segment
		(start 97.097088 142.377638)
		(end 97.074865 142.375135)
		(width 0.1)
		(layer "In2.Cu")
		(net 186)
	)
	(segment
		(start 97.174731 139.275135)
		(end 97.174731 139.274865)
		(width 0.1)
		(layer "In2.Cu")
		(net 186)
	)
	(segment
		(start 97.118195 142.565245)
		(end 97.13713 142.553347)
		(width 0.1)
		(layer "In2.Cu")
		(net 186)
	)
	(segment
		(start 96.775269 139.875135)
		(end 96.775269 139.874865)
		(width 0.1)
		(layer "In2.Cu")
		(net 186)
	)
	(segment
		(start 96.875134 139.175)
		(end 96.852912 139.172496)
		(width 0.1)
		(layer "In2.Cu")
		(net 186)
	)
	(segment
		(start 96.875134 140.575)
		(end 97.074866 140.575)
		(width 0.1)
		(layer "In2.Cu")
		(net 186)
	)
	(segment
		(start 96.777773 140.252642)
		(end 96.785159 140.231535)
		(width 0.1)
		(layer "In2.Cu")
		(net 186)
	)
	(segment
		(start 97.13713 139.353212)
		(end 97.152943 139.337399)
		(width 0.1)
		(layer "In2.Cu")
		(net 186)
	)
	(segment
		(start 96.797057 138.2126)
		(end 96.81287 138.196787)
		(width 0.1)
		(layer "In2.Cu")
		(net 186)
	)
	(segment
		(start 97.118195 138.56511)
		(end 97.13713 138.553212)
		(width 0.1)
		(layer "In2.Cu")
		(net 186)
	)
	(segment
		(start 96.975 142.375)
		(end 96.875134 142.375)
		(width 0.1)
		(layer "In2.Cu")
		(net 186)
	)
	(segment
		(start 96.785159 141.831535)
		(end 96.797057 141.8126)
		(width 0.1)
		(layer "In2.Cu")
		(net 186)
	)
	(segment
		(start 97.097088 139.977503)
		(end 97.074866 139.975)
		(width 0.1)
		(layer "In2.Cu")
		(net 186)
	)
	(segment
		(start 97.172227 138.097357)
		(end 97.174731 138.075135)
		(width 0.1)
		(layer "In2.Cu")
		(net 186)
	)
	(segment
		(start 97.174731 142.475)
		(end 97.172227 142.452777)
		(width 0.1)
		(layer "In2.Cu")
		(net 186)
	)
	(segment
		(start 96.777773 140.297357)
		(end 96.775269 140.275135)
		(width 0.1)
		(layer "In2.Cu")
		(net 186)
	)
	(segment
		(start 97.097088 140.572496)
		(end 97.118195 140.56511)
		(width 0.1)
		(layer "In2.Cu")
		(net 186)
	)
	(segment
		(start 96.777773 140.697357)
		(end 96.775269 140.675135)
		(width 0.1)
		(layer "In2.Cu")
		(net 186)
	)
	(segment
		(start 96.777773 141.052642)
		(end 96.785159 141.031535)
		(width 0.1)
		(layer "In2.Cu")
		(net 186)
	)
	(segment
		(start 96.852912 141.777503)
		(end 96.875134 141.775)
		(width 0.1)
		(layer "In2.Cu")
		(net 186)
	)
	(segment
		(start 97.174731 140.475135)
		(end 97.174731 140.474865)
		(width 0.1)
		(layer "In2.Cu")
		(net 186)
	)
	(segment
		(start 96.875134 142.175)
		(end 97.074866 142.175)
		(width 0.1)
		(layer "In2.Cu")
		(net 186)
	)
	(segment
		(start 97.118195 141.36511)
		(end 97.13713 141.353212)
		(width 0.1)
		(layer "In2.Cu")
		(net 186)
	)
	(segment
		(start 97.172227 142.497492)
		(end 97.174731 142.47527)
		(width 0.1)
		(layer "In2.Cu")
		(net 186)
	)
	(segment
		(start 96.777773 140.652642)
		(end 96.785159 140.631535)
		(width 0.1)
		(layer "In2.Cu")
		(net 186)
	)
	(segment
		(start 97.074866 139.375)
		(end 97.097088 139.372496)
		(width 0.1)
		(layer "In2.Cu")
		(net 186)
	)
	(segment
		(start 97.164841 138.431535)
		(end 97.152943 138.4126)
		(width 0.1)
		(layer "In2.Cu")
		(net 186)
	)
	(segment
		(start 96.875134 137.975)
		(end 96.852912 137.972496)
		(width 0.1)
		(layer "In2.Cu")
		(net 186)
	)
	(segment
		(start 97.118195 138.384889)
		(end 97.097088 138.377503)
		(width 0.1)
		(layer "In2.Cu")
		(net 186)
	)
	(segment
		(start 96.797057 142.2126)
		(end 96.81287 142.196787)
		(width 0.1)
		(layer "In2.Cu")
		(net 186)
	)
	(segment
		(start 97.074866 141.175)
		(end 96.875134 141.175)
		(width 0.1)
		(layer "In2.Cu")
		(net 186)
	)
	(segment
		(start 96.777773 137.852642)
		(end 96.785159 137.831535)
		(width 0.1)
		(layer "In2.Cu")
		(net 186)
	)
	(segment
		(start 96.775269 138.274865)
		(end 96.777773 138.252642)
		(width 0.1)
		(layer "In2.Cu")
		(net 186)
	)
	(segment
		(start 96.797057 141.937399)
		(end 96.785159 141.918464)
		(width 0.1)
		(layer "In2.Cu")
		(net 186)
	)
	(segment
		(start 97.13713 140.153212)
		(end 97.152943 140.137399)
		(width 0.1)
		(layer "In2.Cu")
		(net 186)
	)
	(segment
		(start 97.097088 140.172496)
		(end 97.118195 140.16511)
		(width 0.1)
		(layer "In2.Cu")
		(net 186)
	)
	(segment
		(start 97.118195 139.584889)
		(end 97.097088 139.577503)
		(width 0.1)
		(layer "In2.Cu")
		(net 186)
	)
	(segment
		(start 96.785159 139.918464)
		(end 96.777773 139.897357)
		(width 0.1)
		(layer "In2.Cu")
		(net 186)
	)
	(segment
		(start 96.775269 142.274865)
		(end 96.777773 142.252642)
		(width 0.1)
		(layer "In2.Cu")
		(net 186)
	)
	(segment
		(start 96.977503 142.652777)
		(end 96.984889 142.63167)
		(width 0.1)
		(layer "In2.Cu")
		(net 186)
	)
	(segment
		(start 97.097088 139.577503)
		(end 97.074866 139.575)
		(width 0.1)
		(layer "In2.Cu")
		(net 186)
	)
	(segment
		(start 96.785159 139.831535)
		(end 96.797057 139.8126)
		(width 0.1)
		(layer "In2.Cu")
		(net 186)
	)
	(segment
		(start 96.875134 141.375)
		(end 97.074866 141.375)
		(width 0.1)
		(layer "In2.Cu")
		(net 186)
	)
	(segment
		(start 96.831805 142.36511)
		(end 96.81287 142.353212)
		(width 0.1)
		(layer "In2.Cu")
		(net 186)
	)
	(segment
		(start 96.875134 142.375)
		(end 96.852912 142.372496)
		(width 0.1)
		(layer "In2.Cu")
		(net 186)
	)
	(segment
		(start 96.875134 141.775)
		(end 97.074866 141.775)
		(width 0.1)
		(layer "In2.Cu")
		(net 186)
	)
	(segment
		(start 96.797057 141.4126)
		(end 96.81287 141.396787)
		(width 0.1)
		(layer "In2.Cu")
		(net 186)
	)
	(segment
		(start 97.118195 140.384889)
		(end 97.097088 140.377503)
		(width 0.1)
		(layer "In2.Cu")
		(net 186)
	)
	(segment
		(start 96.875134 141.575)
		(end 96.852912 141.572496)
		(width 0.1)
		(layer "In2.Cu")
		(net 186)
	)
	(segment
		(start 96.975 142.375135)
		(end 96.975 142.375)
		(width 0.1)
		(layer "In2.Cu")
		(net 186)
	)
	(segment
		(start 97.118195 141.76511)
		(end 97.13713 141.753212)
		(width 0.1)
		(layer "In2.Cu")
		(net 186)
	)
	(segment
		(start 96.831805 139.56511)
		(end 96.81287 139.553212)
		(width 0.1)
		(layer "In2.Cu")
		(net 186)
	)
	(segment
		(start 96.775269 140.274865)
		(end 96.777773 140.252642)
		(width 0.1)
		(layer "In2.Cu")
		(net 186)
	)
	(segment
		(start 97.174731 138.475135)
		(end 97.174731 138.474865)
		(width 0.1)
		(layer "In2.Cu")
		(net 186)
	)
	(segment
		(start 96.831805 139.784889)
		(end 96.852912 139.777503)
		(width 0.1)
		(layer "In2.Cu")
		(net 186)
	)
	(segment
		(start 96.831805 140.184889)
		(end 96.852912 140.177503)
		(width 0.1)
		(layer "In2.Cu")
		(net 186)
	)
	(segment
		(start 96.81287 140.596787)
		(end 96.831805 140.584889)
		(width 0.1)
		(layer "In2.Cu")
		(net 186)
	)
	(segment
		(start 96.785159 141.431535)
		(end 96.797057 141.4126)
		(width 0.1)
		(layer "In2.Cu")
		(net 186)
	)
	(segment
		(start 96.81287 138.753212)
		(end 96.797057 138.737399)
		(width 0.1)
		(layer "In2.Cu")
		(net 186)
	)
	(segment
		(start 96.777773 142.252642)
		(end 96.785159 142.231535)
		(width 0.1)
		(layer "In2.Cu")
		(net 186)
	)
	(segment
		(start 97.174731 138.474865)
		(end 97.172227 138.452642)
		(width 0.1)
		(layer "In2.Cu")
		(net 186)
	)
	(segment
		(start 96.797057 139.0126)
		(end 96.81287 138.996787)
		(width 0.1)
		(layer "In2.Cu")
		(net 186)
	)
	(segment
		(start 96.785159 140.718464)
		(end 96.777773 140.697357)
		(width 0.1)
		(layer "In2.Cu")
		(net 186)
	)
	(segment
		(start 97.164841 138.918464)
		(end 97.172227 138.897357)
		(width 0.1)
		(layer "In2.Cu")
		(net 186)
	)
	(segment
		(start 96.831805 140.584889)
		(end 96.852912 140.577503)
		(width 0.1)
		(layer "In2.Cu")
		(net 186)
	)
	(segment
		(start 97.074866 140.575)
		(end 97.097088 140.572496)
		(width 0.1)
		(layer "In2.Cu")
		(net 186)
	)
	(segment
		(start 97.172227 140.452642)
		(end 97.164841 140.431535)
		(width 0.1)
		(layer "In2.Cu")
		(net 186)
	)
	(segment
		(start 97.174731 142.075135)
		(end 97.174731 142.074865)
		(width 0.1)
		(layer "In2.Cu")
		(net 186)
	)
	(segment
		(start 96.831805 140.984889)
		(end 96.852912 140.977503)
		(width 0.1)
		(layer "In2.Cu")
		(net 186)
	)
	(segment
		(start 97.164841 138.518464)
		(end 97.172227 138.497357)
		(width 0.1)
		(layer "In2.Cu")
		(net 186)
	)
	(segment
		(start 97.174731 141.675135)
		(end 97.174731 141.674865)
		(width 0.1)
		(layer "In2.Cu")
		(net 186)
	)
	(segment
		(start 96.777773 141.452642)
		(end 96.785159 141.431535)
		(width 0.1)
		(layer "In2.Cu")
		(net 186)
	)
	(segment
		(start 97.097088 139.372496)
		(end 97.118195 139.36511)
		(width 0.1)
		(layer "In2.Cu")
		(net 186)
	)
	(segment
		(start 97.164841 142.43167)
		(end 97.152943 142.412735)
		(width 0.1)
		(layer "In2.Cu")
		(net 186)
	)
	(segment
		(start 97.172227 140.097357)
		(end 97.174731 140.075135)
		(width 0.1)
		(layer "In2.Cu")
		(net 186)
	)
	(segment
		(start 96.797057 139.8126)
		(end 96.81287 139.796787)
		(width 0.1)
		(layer "In2.Cu")
		(net 186)
	)
	(segment
		(start 96.81287 140.996787)
		(end 96.831805 140.984889)
		(width 0.1)
		(layer "In2.Cu")
		(net 186)
	)
	(segment
		(start 96.785159 137.831535)
		(end 96.797057 137.8126)
		(width 0.1)
		(layer "In2.Cu")
		(net 186)
	)
	(segment
		(start 97.152943 138.4126)
		(end 97.13713 138.396787)
		(width 0.1)
		(layer "In2.Cu")
		(net 186)
	)
	(segment
		(start 96.875134 139.575)
		(end 96.852912 139.572496)
		(width 0.1)
		(layer "In2.Cu")
		(net 186)
	)
	(segment
		(start 97.172227 141.697357)
		(end 97.174731 141.675135)
		(width 0.1)
		(layer "In2.Cu")
		(net 186)
	)
	(segment
		(start 97.172227 140.052642)
		(end 97.164841 140.031535)
		(width 0.1)
		(layer "In2.Cu")
		(net 186)
	)
	(segment
		(start 97.118195 140.56511)
		(end 97.13713 140.553212)
		(width 0.1)
		(layer "In2.Cu")
		(net 186)
	)
	(segment
		(start 96.852912 141.377503)
		(end 96.875134 141.375)
		(width 0.1)
		(layer "In2.Cu")
		(net 186)
	)
	(segment
		(start 97.13713 139.196787)
		(end 97.118195 139.184889)
		(width 0.1)
		(layer "In2.Cu")
		(net 186)
	)
	(segment
		(start 96.852912 140.372496)
		(end 96.831805 140.36511)
		(width 0.1)
		(layer "In2.Cu")
		(net 186)
	)
	(segment
		(start 97.0126 137.553212)
		(end 96.996787 137.537399)
		(width 0.1)
		(layer "In2.Cu")
		(net 186)
	)
	(segment
		(start 96.775269 141.074865)
		(end 96.777773 141.052642)
		(width 0.1)
		(layer "In2.Cu")
		(net 186)
	)
	(segment
		(start 96.81287 141.396787)
		(end 96.831805 141.384889)
		(width 0.1)
		(layer "In2.Cu")
		(net 186)
	)
	(segment
		(start 97.097088 138.377503)
		(end 97.074866 138.375)
		(width 0.1)
		(layer "In2.Cu")
		(net 186)
	)
	(segment
		(start 97.118195 142.385024)
		(end 97.097088 142.377638)
		(width 0.1)
		(layer "In2.Cu")
		(net 186)
	)
	(segment
		(start 97.097088 139.772496)
		(end 97.118195 139.76511)
		(width 0.1)
		(layer "In2.Cu")
		(net 186)
	)
	(segment
		(start 96.775269 141.075135)
		(end 96.775269 141.074865)
		(width 0.1)
		(layer "In2.Cu")
		(net 186)
	)
	(segment
		(start 97.152943 140.537399)
		(end 97.164841 140.518464)
		(width 0.1)
		(layer "In2.Cu")
		(net 186)
	)
	(segment
		(start 96.81287 138.996787)
		(end 96.831805 138.984889)
		(width 0.1)
		(layer "In2.Cu")
		(net 186)
	)
	(segment
		(start 97.152943 141.337399)
		(end 97.164841 141.318464)
		(width 0.1)
		(layer "In2.Cu")
		(net 186)
	)
	(segment
		(start 96.777773 139.097357)
		(end 96.775269 139.075135)
		(width 0.1)
		(layer "In2.Cu")
		(net 186)
	)
	(segment
		(start 97.164841 138.031535)
		(end 97.152943 138.0126)
		(width 0.1)
		(layer "In2.Cu")
		(net 186)
	)
	(segment
		(start 96.984889 142.63167)
		(end 96.996787 142.612735)
		(width 0.1)
		(layer "In2.Cu")
		(net 186)
	)
	(segment
		(start 96.797057 138.6126)
		(end 96.81287 138.596787)
		(width 0.1)
		(layer "In2.Cu")
		(net 186)
	)
	(segment
		(start 96.852912 138.577503)
		(end 96.875134 138.575)
		(width 0.1)
		(layer "In2.Cu")
		(net 186)
	)
	(segment
		(start 96.775269 137.875135)
		(end 96.775269 137.874865)
		(width 0.1)
		(layer "In2.Cu")
		(net 186)
	)
	(segment
		(start 96.852912 140.177503)
		(end 96.875134 140.175)
		(width 0.1)
		(layer "In2.Cu")
		(net 186)
	)
	(segment
		(start 97.118195 141.584889)
		(end 97.097088 141.577503)
		(width 0.1)
		(layer "In2.Cu")
		(net 186)
	)
	(segment
		(start 96.875134 137.775)
		(end 97.074866 137.775)
		(width 0.1)
		(layer "In2.Cu")
		(net 186)
	)
	(segment
		(start 97.13713 137.753212)
		(end 97.152943 137.737399)
		(width 0.1)
		(layer "In2.Cu")
		(net 186)
	)
	(segment
		(start 97.118195 139.76511)
		(end 97.13713 139.753212)
		(width 0.1)
		(layer "In2.Cu")
		(net 186)
	)
	(segment
		(start 97.174731 140.075135)
		(end 97.174731 140.074865)
		(width 0.1)
		(layer "In2.Cu")
		(net 186)
	)
	(segment
		(start 96.81287 138.353212)
		(end 96.797057 138.337399)
		(width 0.1)
		(layer "In2.Cu")
		(net 186)
	)
	(segment
		(start 96.777773 139.852642)
		(end 96.785159 139.831535)
		(width 0.1)
		(layer "In2.Cu")
		(net 186)
	)
	(segment
		(start 96.775269 139.074865)
		(end 96.777773 139.052642)
		(width 0.1)
		(layer "In2.Cu")
		(net 186)
	)
	(segment
		(start 97.097088 140.377503)
		(end 97.074866 140.375)
		(width 0.1)
		(layer "In2.Cu")
		(net 186)
	)
	(segment
		(start 97.164841 139.318464)
		(end 97.172227 139.297357)
		(width 0.1)
		(layer "In2.Cu")
		(net 186)
	)
	(segment
		(start 96.777773 138.652642)
		(end 96.785159 138.631535)
		(width 0.1)
		(layer "In2.Cu")
		(net 186)
	)
	(segment
		(start 97.118195 138.784889)
		(end 97.097088 138.777503)
		(width 0.1)
		(layer "In2.Cu")
		(net 186)
	)
	(segment
		(start 97.13713 138.953212)
		(end 97.152943 138.937399)
		(width 0.1)
		(layer "In2.Cu")
		(net 186)
	)
	(segment
		(start 97.074866 140.175)
		(end 97.097088 140.172496)
		(width 0.1)
		(layer "In2.Cu")
		(net 186)
	)
	(segment
		(start 97.172227 138.452642)
		(end 97.164841 138.431535)
		(width 0.1)
		(layer "In2.Cu")
		(net 186)
	)
	(segment
		(start 97.031535 137.56511)
		(end 97.0126 137.553212)
		(width 0.1)
		(layer "In2.Cu")
		(net 186)
	)
	(segment
		(start 96.775269 141.874865)
		(end 96.777773 141.852642)
		(width 0.1)
		(layer "In2.Cu")
		(net 186)
	)
	(segment
		(start 97.172227 137.652642)
		(end 97.164841 137.631535)
		(width 0.1)
		(layer "In2.Cu")
		(net 186)
	)
	(segment
		(start 97.164841 137.631535)
		(end 97.152943 137.6126)
		(width 0.1)
		(layer "In2.Cu")
		(net 186)
	)
	(segment
		(start 97.172227 140.897357)
		(end 97.174731 140.875135)
		(width 0.1)
		(layer "In2.Cu")
		(net 186)
	)
	(segment
		(start 96.797057 139.4126)
		(end 96.81287 139.396787)
		(width 0.1)
		(layer "In2.Cu")
		(net 186)
	)
	(segment
		(start 97.172227 142.052642)
		(end 97.164841 142.031535)
		(width 0.1)
		(layer "In2.Cu")
		(net 186)
	)
	(segment
		(start 97.172227 142.452777)
		(end 97.164841 142.43167)
		(width 0.1)
		(layer "In2.Cu")
		(net 186)
	)
	(segment
		(start 96.831805 138.584889)
		(end 96.852912 138.577503)
		(width 0.1)
		(layer "In2.Cu")
		(net 186)
	)
	(segment
		(start 96.875134 140.175)
		(end 97.074866 140.175)
		(width 0.1)
		(layer "In2.Cu")
		(net 186)
	)
	(segment
		(start 97.074866 139.175)
		(end 96.875134 139.175)
		(width 0.1)
		(layer "In2.Cu")
		(net 186)
	)
	(segment
		(start 96.775269 139.874865)
		(end 96.777773 139.852642)
		(width 0.1)
		(layer "In2.Cu")
		(net 186)
	)
	(segment
		(start 97.164841 141.318464)
		(end 97.172227 141.297357)
		(width 0.1)
		(layer "In2.Cu")
		(net 186)
	)
	(segment
		(start 97.164841 142.031535)
		(end 97.152943 142.0126)
		(width 0.1)
		(layer "In2.Cu")
		(net 186)
	)
	(segment
		(start 96.777773 138.697357)
		(end 96.775269 138.675135)
		(width 0.1)
		(layer "In2.Cu")
		(net 186)
	)
	(segment
		(start 97.152943 141.737399)
		(end 97.164841 141.718464)
		(width 0.1)
		(layer "In2.Cu")
		(net 186)
	)
	(segment
		(start 97.164841 140.431535)
		(end 97.152943 140.4126)
		(width 0.1)
		(layer "In2.Cu")
		(net 186)
	)
	(segment
		(start 96.81287 142.196787)
		(end 96.831805 142.184889)
		(width 0.1)
		(layer "In2.Cu")
		(net 186)
	)
	(segment
		(start 97.174731 137.674865)
		(end 97.172227 137.652642)
		(width 0.1)
		(layer "In2.Cu")
		(net 186)
	)
	(segment
		(start 97.13713 141.196787)
		(end 97.118195 141.184889)
		(width 0.1)
		(layer "In2.Cu")
		(net 186)
	)
	(segment
		(start 96.777773 139.497357)
		(end 96.775269 139.475135)
		(width 0.1)
		(layer "In2.Cu")
		(net 186)
	)
	(segment
		(start 96.797057 138.737399)
		(end 96.785159 138.718464)
		(width 0.1)
		(layer "In2.Cu")
		(net 186)
	)
	(segment
		(start 97.172227 137.697357)
		(end 97.174731 137.675135)
		(width 0.1)
		(layer "In2.Cu")
		(net 186)
	)
	(segment
		(start 97.118195 142.16511)
		(end 97.13713 142.153212)
		(width 0.1)
		(layer "In2.Cu")
		(net 186)
	)
	(segment
		(start 97.074866 140.375)
		(end 96.875134 140.375)
		(width 0.1)
		(layer "In2.Cu")
		(net 186)
	)
	(segment
		(start 96.831805 141.96511)
		(end 96.81287 141.953212)
		(width 0.1)
		(layer "In2.Cu")
		(net 186)
	)
	(segment
		(start 97.152943 142.137399)
		(end 97.164841 142.118464)
		(width 0.1)
		(layer "In2.Cu")
		(net 186)
	)
	(segment
		(start 97.097088 137.772496)
		(end 97.118195 137.76511)
		(width 0.1)
		(layer "In2.Cu")
		(net 186)
	)
	(segment
		(start 97.174731 138.075135)
		(end 97.174731 138.074865)
		(width 0.1)
		(layer "In2.Cu")
		(net 186)
	)
	(segment
		(start 96.81287 141.953212)
		(end 96.797057 141.937399)
		(width 0.1)
		(layer "In2.Cu")
		(net 186)
	)
	(segment
		(start 96.875134 141.975)
		(end 96.852912 141.972496)
		(width 0.1)
		(layer "In2.Cu")
		(net 186)
	)
	(segment
		(start 96.852912 138.772496)
		(end 96.831805 138.76511)
		(width 0.1)
		(layer "In2.Cu")
		(net 186)
	)
	(segment
		(start 96.81287 139.796787)
		(end 96.831805 139.784889)
		(width 0.1)
		(layer "In2.Cu")
		(net 186)
	)
	(segment
		(start 97.074866 141.975)
		(end 96.875134 141.975)
		(width 0.1)
		(layer "In2.Cu")
		(net 186)
	)
	(segment
		(start 96.777773 137.897357)
		(end 96.775269 137.875135)
		(width 0.1)
		(layer "In2.Cu")
		(net 186)
	)
	(segment
		(start 97.13713 137.996787)
		(end 97.118195 137.984889)
		(width 0.1)
		(layer "In2.Cu")
		(net 186)
	)
	(segment
		(start 97.13713 142.396922)
		(end 97.118195 142.385024)
		(width 0.1)
		(layer "In2.Cu")
		(net 186)
	)
	(segment
		(start 96.797057 141.537399)
		(end 96.785159 141.518464)
		(width 0.1)
		(layer "In2.Cu")
		(net 186)
	)
	(segment
		(start 96.852912 138.177503)
		(end 96.875134 138.175)
		(width 0.1)
		(layer "In2.Cu")
		(net 186)
	)
	(segment
		(start 96.785159 139.518464)
		(end 96.777773 139.497357)
		(width 0.1)
		(layer "In2.Cu")
		(net 186)
	)
	(segment
		(start 96.831805 141.784889)
		(end 96.852912 141.777503)
		(width 0.1)
		(layer "In2.Cu")
		(net 186)
	)
	(segment
		(start 96.875134 139.775)
		(end 97.074866 139.775)
		(width 0.1)
		(layer "In2.Cu")
		(net 186)
	)
	(segment
		(start 97.164841 142.118464)
		(end 97.172227 142.097357)
		(width 0.1)
		(layer "In2.Cu")
		(net 186)
	)
	(segment
		(start 97.152943 138.537399)
		(end 97.164841 138.518464)
		(width 0.1)
		(layer "In2.Cu")
		(net 186)
	)
	(segment
		(start 97.164841 140.118464)
		(end 97.172227 140.097357)
		(width 0.1)
		(layer "In2.Cu")
		(net 186)
	)
	(segment
		(start 97.13713 138.153212)
		(end 97.152943 138.137399)
		(width 0.1)
		(layer "In2.Cu")
		(net 186)
	)
	(segment
		(start 97.172227 140.852642)
		(end 97.164841 140.831535)
		(width 0.1)
		(layer "In2.Cu")
		(net 186)
	)
	(segment
		(start 96.775269 141.475135)
		(end 96.775269 141.474865)
		(width 0.1)
		(layer "In2.Cu")
		(net 186)
	)
	(segment
		(start 97.174731 138.874865)
		(end 97.172227 138.852642)
		(width 0.1)
		(layer "In2.Cu")
		(net 186)
	)
	(segment
		(start 97.074866 141.575)
		(end 96.875134 141.575)
		(width 0.1)
		(layer "In2.Cu")
		(net 186)
	)
	(segment
		(start 97.174731 141.275135)
		(end 97.174731 141.274865)
		(width 0.1)
		(layer "In2.Cu")
		(net 186)
	)
	(segment
		(start 96.852912 140.977503)
		(end 96.875134 140.975)
		(width 0.1)
		(layer "In2.Cu")
		(net 186)
	)
	(segment
		(start 97.174731 138.074865)
		(end 97.172227 138.052642)
		(width 0.1)
		(layer "In2.Cu")
		(net 186)
	)
	(segment
		(start 96.831805 138.984889)
		(end 96.852912 138.977503)
		(width 0.1)
		(layer "In2.Cu")
		(net 186)
	)
	(segment
		(start 96.81287 142.353212)
		(end 96.797057 142.337399)
		(width 0.1)
		(layer "In2.Cu")
		(net 186)
	)
	(segment
		(start 97.775 126.175)
		(end 97.275 126.675)
		(width 0.15)
		(layer "F.Cu")
		(net 187)
	)
	(segment
		(start 96.175 149.575)
		(end 95.775 149.175)
		(width 0.1)
		(layer "F.Cu")
		(net 187)
	)
	(segment
		(start 95.775 149.175)
		(end 95.775 147.675)
		(width 0.1)
		(layer "F.Cu")
		(net 187)
	)
	(via blind
		(at 95.775 147.675)
		(size 0.5)
		(drill 0.2)
		(layers "F.Cu" "In5.Cu")
		(net 187)
	)
	(via blind
		(at 97.275 126.675)
		(size 0.5)
		(drill 0.2)
		(layers "F.Cu" "In5.Cu")
		(net 187)
	)
	(segment
		(start 95.964455 146.675)
		(end 95.875 146.675)
		(width 0.1)
		(layer "In5.Cu")
		(net 187)
	)
	(segment
		(start 96.042638 146.712651)
		(end 96.026803 146.696816)
		(width 0.1)
		(layer "In5.Cu")
		(net 187)
	)
	(segment
		(start 95.777507 146.952747)
		(end 95.784903 146.931611)
		(width 0.1)
		(layer "In5.Cu")
		(net 187)
	)
	(segment
		(start 95.775 146.575)
		(end 95.775 128.775)
		(width 0.1)
		(layer "In5.Cu")
		(net 187)
	)
	(segment
		(start 96.007843 146.684903)
		(end 95.986707 146.677507)
		(width 0.1)
		(layer "In5.Cu")
		(net 187)
	)
	(segment
		(start 95.775 128.775)
		(end 97.275 127.275)
		(width 0.1)
		(layer "In5.Cu")
		(net 187)
	)
	(segment
		(start 95.875 146.875)
		(end 95.964455 146.875)
		(width 0.1)
		(layer "In5.Cu")
		(net 187)
	)
	(segment
		(start 96.026803 146.696816)
		(end 96.007843 146.684903)
		(width 0.1)
		(layer "In5.Cu")
		(net 187)
	)
	(segment
		(start 96.026803 146.853183)
		(end 96.042638 146.837348)
		(width 0.1)
		(layer "In5.Cu")
		(net 187)
	)
	(segment
		(start 95.986707 146.872492)
		(end 96.007843 146.865096)
		(width 0.1)
		(layer "In5.Cu")
		(net 187)
	)
	(segment
		(start 97.275 127.275)
		(end 97.275 126.675)
		(width 0.1)
		(layer "In5.Cu")
		(net 187)
	)
	(segment
		(start 95.875 146.675)
		(end 95.852747 146.672492)
		(width 0.1)
		(layer "In5.Cu")
		(net 187)
	)
	(segment
		(start 95.986707 146.677507)
		(end 95.964455 146.675)
		(width 0.1)
		(layer "In5.Cu")
		(net 187)
	)
	(segment
		(start 95.775 146.975)
		(end 95.777507 146.952747)
		(width 0.1)
		(layer "In5.Cu")
		(net 187)
	)
	(segment
		(start 95.831611 146.884903)
		(end 95.852747 146.877507)
		(width 0.1)
		(layer "In5.Cu")
		(net 187)
	)
	(segment
		(start 96.064455 146.775)
		(end 96.061947 146.752747)
		(width 0.1)
		(layer "In5.Cu")
		(net 187)
	)
	(segment
		(start 96.042638 146.837348)
		(end 96.054551 146.818388)
		(width 0.1)
		(layer "In5.Cu")
		(net 187)
	)
	(segment
		(start 96.061947 146.797252)
		(end 96.064455 146.775)
		(width 0.1)
		(layer "In5.Cu")
		(net 187)
	)
	(segment
		(start 95.796816 146.637348)
		(end 95.784903 146.618388)
		(width 0.1)
		(layer "In5.Cu")
		(net 187)
	)
	(segment
		(start 96.061947 146.752747)
		(end 96.054551 146.731611)
		(width 0.1)
		(layer "In5.Cu")
		(net 187)
	)
	(segment
		(start 96.054551 146.818388)
		(end 96.061947 146.797252)
		(width 0.1)
		(layer "In5.Cu")
		(net 187)
	)
	(segment
		(start 95.831611 146.665096)
		(end 95.812651 146.653183)
		(width 0.1)
		(layer "In5.Cu")
		(net 187)
	)
	(segment
		(start 95.775 147.675)
		(end 95.775 146.975)
		(width 0.1)
		(layer "In5.Cu")
		(net 187)
	)
	(segment
		(start 95.852747 146.672492)
		(end 95.831611 146.665096)
		(width 0.1)
		(layer "In5.Cu")
		(net 187)
	)
	(segment
		(start 95.784903 146.618388)
		(end 95.777507 146.597252)
		(width 0.1)
		(layer "In5.Cu")
		(net 187)
	)
	(segment
		(start 95.812651 146.896816)
		(end 95.831611 146.884903)
		(width 0.1)
		(layer "In5.Cu")
		(net 187)
	)
	(segment
		(start 96.007843 146.865096)
		(end 96.026803 146.853183)
		(width 0.1)
		(layer "In5.Cu")
		(net 187)
	)
	(segment
		(start 95.852747 146.877507)
		(end 95.875 146.875)
		(width 0.1)
		(layer "In5.Cu")
		(net 187)
	)
	(segment
		(start 95.777507 146.597252)
		(end 95.775 146.575)
		(width 0.1)
		(layer "In5.Cu")
		(net 187)
	)
	(segment
		(start 95.964455 146.875)
		(end 95.986707 146.872492)
		(width 0.1)
		(layer "In5.Cu")
		(net 187)
	)
	(segment
		(start 95.784903 146.931611)
		(end 95.796816 146.912651)
		(width 0.1)
		(layer "In5.Cu")
		(net 187)
	)
	(segment
		(start 95.812651 146.653183)
		(end 95.796816 146.637348)
		(width 0.1)
		(layer "In5.Cu")
		(net 187)
	)
	(segment
		(start 95.796816 146.912651)
		(end 95.812651 146.896816)
		(width 0.1)
		(layer "In5.Cu")
		(net 187)
	)
	(segment
		(start 96.054551 146.731611)
		(end 96.042638 146.712651)
		(width 0.1)
		(layer "In5.Cu")
		(net 187)
	)
	(segment
		(start 96.175 145.575)
		(end 96.175 146.175)
		(width 0.1)
		(layer "F.Cu")
		(net 188)
	)
	(segment
		(start 97.775 127.175)
		(end 97.275 127.675)
		(width 0.15)
		(layer "F.Cu")
		(net 188)
	)
	(via blind
		(at 96.175 146.175)
		(size 0.5)
		(drill 0.2)
		(layers "F.Cu" "In2.Cu")
		(net 188)
	)
	(via blind
		(at 97.275 127.675)
		(size 0.5)
		(drill 0.2)
		(layers "F.Cu" "In2.Cu")
		(net 188)
	)
	(segment
		(start 96.646695 135.979951)
		(end 96.656175 135.985908)
		(width 0.1)
		(layer "In2.Cu")
		(net 188)
	)
	(segment
		(start 96.40089 135.93821)
		(end 96.416362 135.953682)
		(width 0.1)
		(layer "In2.Cu")
		(net 188)
	)
	(segment
		(start 96.646695 134.170048)
		(end 96.636127 134.173746)
		(width 0.1)
		(layer "In2.Cu")
		(net 188)
	)
	(segment
		(start 96.673747 135.213873)
		(end 96.675 135.225)
		(width 0.1)
		(layer "In2.Cu")
		(net 188)
	)
	(segment
		(start 96.675 135.725)
		(end 96.673747 135.736126)
		(width 0.1)
		(layer "In2.Cu")
		(net 188)
	)
	(segment
		(start 96.636127 137.373746)
		(end 96.625 137.375)
		(width 0.1)
		(layer "In2.Cu")
		(net 188)
	)
	(segment
		(start 96.40089 134.211789)
		(end 96.389249 134.230316)
		(width 0.1)
		(layer "In2.Cu")
		(net 188)
	)
	(segment
		(start 96.646695 135.370048)
		(end 96.636127 135.373746)
		(width 0.1)
		(layer "In2.Cu")
		(net 188)
	)
	(segment
		(start 96.477286 135.975)
		(end 96.625 135.975)
		(width 0.1)
		(layer "In2.Cu")
		(net 188)
	)
	(segment
		(start 96.675 136.925)
		(end 96.673747 136.936126)
		(width 0.1)
		(layer "In2.Cu")
		(net 188)
	)
	(segment
		(start 96.416362 136.753682)
		(end 96.434889 136.765323)
		(width 0.1)
		(layer "In2.Cu")
		(net 188)
	)
	(segment
		(start 96.40089 133.811789)
		(end 96.389249 133.830316)
		(width 0.1)
		(layer "In2.Cu")
		(net 188)
	)
	(segment
		(start 96.40089 136.33821)
		(end 96.416362 136.353682)
		(width 0.1)
		(layer "In2.Cu")
		(net 188)
	)
	(segment
		(start 96.57255 137.650969)
		(end 96.575 137.672713)
		(width 0.1)
		(layer "In2.Cu")
		(net 188)
	)
	(segment
		(start 96.664092 133.593825)
		(end 96.670049 133.603305)
		(width 0.1)
		(layer "In2.Cu")
		(net 188)
	)
	(segment
		(start 96.379573 136.277287)
		(end 96.382022 136.29903)
		(width 0.1)
		(layer "In2.Cu")
		(net 188)
	)
	(segment
		(start 96.382022 137.09903)
		(end 96.389249 137.119683)
		(width 0.1)
		(layer "In2.Cu")
		(net 188)
	)
	(segment
		(start 96.379573 134.672713)
		(end 96.379573 134.677287)
		(width 0.1)
		(layer "In2.Cu")
		(net 188)
	)
	(segment
		(start 96.389249 135.830316)
		(end 96.382022 135.850969)
		(width 0.1)
		(layer "In2.Cu")
		(net 188)
	)
	(segment
		(start 96.675 134.125)
		(end 96.673747 134.136126)
		(width 0.1)
		(layer "In2.Cu")
		(net 188)
	)
	(segment
		(start 96.382022 137.49903)
		(end 96.389249 137.519683)
		(width 0.1)
		(layer "In2.Cu")
		(net 188)
	)
	(segment
		(start 96.434889 135.384676)
		(end 96.416362 135.396317)
		(width 0.1)
		(layer "In2.Cu")
		(net 188)
	)
	(segment
		(start 96.416362 135.953682)
		(end 96.434889 135.965323)
		(width 0.1)
		(layer "In2.Cu")
		(net 188)
	)
	(segment
		(start 96.656175 135.185908)
		(end 96.664092 135.193825)
		(width 0.1)
		(layer "In2.Cu")
		(net 188)
	)
	(segment
		(start 96.379573 134.277287)
		(end 96.382022 134.29903)
		(width 0.1)
		(layer "In2.Cu")
		(net 188)
	)
	(segment
		(start 96.477286 136.775)
		(end 96.625 136.775)
		(width 0.1)
		(layer "In2.Cu")
		(net 188)
	)
	(segment
		(start 96.656175 136.164091)
		(end 96.646695 136.170048)
		(width 0.1)
		(layer "In2.Cu")
		(net 188)
	)
	(segment
		(start 96.455542 134.977449)
		(end 96.434889 134.984676)
		(width 0.1)
		(layer "In2.Cu")
		(net 188)
	)
	(segment
		(start 96.625 136.975)
		(end 96.477286 136.975)
		(width 0.1)
		(layer "In2.Cu")
		(net 188)
	)
	(segment
		(start 96.382022 136.650969)
		(end 96.379573 136.672713)
		(width 0.1)
		(layer "In2.Cu")
		(net 188)
	)
	(segment
		(start 96.416362 137.396317)
		(end 96.40089 137.411789)
		(width 0.1)
		(layer "In2.Cu")
		(net 188)
	)
	(segment
		(start 96.434889 136.184676)
		(end 96.416362 136.196317)
		(width 0.1)
		(layer "In2.Cu")
		(net 188)
	)
	(segment
		(start 96.389249 135.430316)
		(end 96.382022 135.450969)
		(width 0.1)
		(layer "In2.Cu")
		(net 188)
	)
	(segment
		(start 96.670049 136.803305)
		(end 96.673747 136.813873)
		(width 0.1)
		(layer "In2.Cu")
		(net 188)
	)
	(segment
		(start 96.416362 134.753682)
		(end 96.434889 134.765323)
		(width 0.1)
		(layer "In2.Cu")
		(net 188)
	)
	(segment
		(start 96.646695 137.179951)
		(end 96.656175 137.185908)
		(width 0.1)
		(layer "In2.Cu")
		(net 188)
	)
	(segment
		(start 96.40089 137.411789)
		(end 96.389249 137.430316)
		(width 0.1)
		(layer "In2.Cu")
		(net 188)
	)
	(segment
		(start 96.477287 133.572713)
		(end 96.575 133.572713)
		(width 0.1)
		(layer "In2.Cu")
		(net 188)
	)
	(segment
		(start 96.53821 137.596317)
		(end 96.553682 137.611789)
		(width 0.1)
		(layer "In2.Cu")
		(net 188)
	)
	(segment
		(start 96.670049 135.603305)
		(end 96.673747 135.613873)
		(width 0.1)
		(layer "In2.Cu")
		(net 188)
	)
	(segment
		(start 96.477286 136.975)
		(end 96.455542 136.977449)
		(width 0.1)
		(layer "In2.Cu")
		(net 188)
	)
	(segment
		(start 96.625 135.975)
		(end 96.636127 135.976253)
		(width 0.1)
		(layer "In2.Cu")
		(net 188)
	)
	(segment
		(start 96.389249 137.519683)
		(end 96.40089 137.53821)
		(width 0.1)
		(layer "In2.Cu")
		(net 188)
	)
	(segment
		(start 96.664092 136.393825)
		(end 96.670049 136.403305)
		(width 0.1)
		(layer "In2.Cu")
		(net 188)
	)
	(segment
		(start 96.656175 135.364091)
		(end 96.646695 135.370048)
		(width 0.1)
		(layer "In2.Cu")
		(net 188)
	)
	(segment
		(start 96.382022 135.09903)
		(end 96.389249 135.119683)
		(width 0.1)
		(layer "In2.Cu")
		(net 188)
	)
	(segment
		(start 96.416362 134.596317)
		(end 96.40089 134.611789)
		(width 0.1)
		(layer "In2.Cu")
		(net 188)
	)
	(segment
		(start 96.664092 134.956174)
		(end 96.656175 134.964091)
		(width 0.1)
		(layer "In2.Cu")
		(net 188)
	)
	(segment
		(start 96.455542 134.77255)
		(end 96.477286 134.775)
		(width 0.1)
		(layer "In2.Cu")
		(net 188)
	)
	(segment
		(start 96.670049 134.146694)
		(end 96.664092 134.156174)
		(width 0.1)
		(layer "In2.Cu")
		(net 188)
	)
	(segment
		(start 96.675 135.225)
		(end 96.675 135.325)
		(width 0.1)
		(layer "In2.Cu")
		(net 188)
	)
	(segment
		(start 96.389249 137.030316)
		(end 96.382022 137.050969)
		(width 0.1)
		(layer "In2.Cu")
		(net 188)
	)
	(segment
		(start 96.625 134.575)
		(end 96.477286 134.575)
		(width 0.1)
		(layer "In2.Cu")
		(net 188)
	)
	(segment
		(start 96.455542 134.177449)
		(end 96.434889 134.184676)
		(width 0.1)
		(layer "In2.Cu")
		(net 188)
	)
	(segment
		(start 96.389249 134.630316)
		(end 96.382022 134.650969)
		(width 0.1)
		(layer "In2.Cu")
		(net 188)
	)
	(segment
		(start 96.416362 134.196317)
		(end 96.40089 134.211789)
		(width 0.1)
		(layer "In2.Cu")
		(net 188)
	)
	(segment
		(start 96.646695 133.579951)
		(end 96.656175 133.585908)
		(width 0.1)
		(layer "In2.Cu")
		(net 188)
	)
	(segment
		(start 96.434889 135.165323)
		(end 96.455542 135.17255)
		(width 0.1)
		(layer "In2.Cu")
		(net 188)
	)
	(segment
		(start 96.673747 136.536126)
		(end 96.670049 136.546694)
		(width 0.1)
		(layer "In2.Cu")
		(net 188)
	)
	(segment
		(start 96.416362 135.396317)
		(end 96.40089 135.411789)
		(width 0.1)
		(layer "In2.Cu")
		(net 188)
	)
	(segment
		(start 96.670049 134.403305)
		(end 96.673747 134.413873)
		(width 0.1)
		(layer "In2.Cu")
		(net 188)
	)
	(segment
		(start 96.389249 133.428029)
		(end 96.382022 133.448682)
		(width 0.1)
		(layer "In2.Cu")
		(net 188)
	)
	(segment
		(start 96.382022 133.89903)
		(end 96.389249 133.919683)
		(width 0.1)
		(layer "In2.Cu")
		(net 188)
	)
	(segment
		(start 96.455542 136.577449)
		(end 96.434889 136.584676)
		(width 0.1)
		(layer "In2.Cu")
		(net 188)
	)
	(segment
		(start 96.40089 133.93821)
		(end 96.416362 133.953682)
		(width 0.1)
		(layer "In2.Cu")
		(net 188)
	)
	(segment
		(start 96.40089 136.611789)
		(end 96.389249 136.630316)
		(width 0.1)
		(layer "In2.Cu")
		(net 188)
	)
	(segment
		(start 96.382022 137.050969)
		(end 96.379573 137.072713)
		(width 0.1)
		(layer "In2.Cu")
		(net 188)
	)
	(segment
		(start 96.636127 136.573746)
		(end 96.625 136.575)
		(width 0.1)
		(layer "In2.Cu")
		(net 188)
	)
	(segment
		(start 96.416362 133.551395)
		(end 96.434889 133.563036)
		(width 0.1)
		(layer "In2.Cu")
		(net 188)
	)
	(segment
		(start 96.379573 134.272713)
		(end 96.379573 134.277287)
		(width 0.1)
		(layer "In2.Cu")
		(net 188)
	)
	(segment
		(start 96.670049 137.203305)
		(end 96.673747 137.213873)
		(width 0.1)
		(layer "In2.Cu")
		(net 188)
	)
	(segment
		(start 96.40089 135.13821)
		(end 96.416362 135.153682)
		(width 0.1)
		(layer "In2.Cu")
		(net 188)
	)
	(segment
		(start 96.434889 136.984676)
		(end 96.416362 136.996317)
		(width 0.1)
		(layer "In2.Cu")
		(net 188)
	)
	(segment
		(start 96.670049 134.946694)
		(end 96.664092 134.956174)
		(width 0.1)
		(layer "In2.Cu")
		(net 188)
	)
	(segment
		(start 96.434889 137.384676)
		(end 96.416362 137.396317)
		(width 0.1)
		(layer "In2.Cu")
		(net 188)
	)
	(segment
		(start 96.675 136.425)
		(end 96.675 136.525)
		(width 0.1)
		(layer "In2.Cu")
		(net 188)
	)
	(segment
		(start 96.455542 135.57255)
		(end 96.477286 135.575)
		(width 0.1)
		(layer "In2.Cu")
		(net 188)
	)
	(segment
		(start 96.670049 134.546694)
		(end 96.664092 134.556174)
		(width 0.1)
		(layer "In2.Cu")
		(net 188)
	)
	(segment
		(start 96.675 134.925)
		(end 96.673747 134.936126)
		(width 0.1)
		(layer "In2.Cu")
		(net 188)
	)
	(segment
		(start 96.40089 137.53821)
		(end 96.416362 137.553682)
		(width 0.1)
		(layer "In2.Cu")
		(net 188)
	)
	(segment
		(start 96.382022 136.29903)
		(end 96.389249 136.319683)
		(width 0.1)
		(layer "In2.Cu")
		(net 188)
	)
	(segment
		(start 96.673747 134.936126)
		(end 96.670049 134.946694)
		(width 0.1)
		(layer "In2.Cu")
		(net 188)
	)
	(segment
		(start 96.434889 135.784676)
		(end 96.416362 135.796317)
		(width 0.1)
		(layer "In2.Cu")
		(net 188)
	)
	(segment
		(start 96.455542 133.375162)
		(end 96.434889 133.382389)
		(width 0.1)
		(layer "In2.Cu")
		(net 188)
	)
	(segment
		(start 96.455542 136.177449)
		(end 96.434889 136.184676)
		(width 0.1)
		(layer "In2.Cu")
		(net 188)
	)
	(segment
		(start 96.656175 134.564091)
		(end 96.646695 134.570048)
		(width 0.1)
		(layer "In2.Cu")
		(net 188)
	)
	(segment
		(start 96.673747 136.813873)
		(end 96.675 136.825)
		(width 0.1)
		(layer "In2.Cu")
		(net 188)
	)
	(segment
		(start 96.673747 135.736126)
		(end 96.670049 135.746694)
		(width 0.1)
		(layer "In2.Cu")
		(net 188)
	)
	(segment
		(start 96.664092 136.793825)
		(end 96.670049 136.803305)
		(width 0.1)
		(layer "In2.Cu")
		(net 188)
	)
	(segment
		(start 96.636127 135.176253)
		(end 96.646695 135.179951)
		(width 0.1)
		(layer "In2.Cu")
		(net 188)
	)
	(segment
		(start 96.434889 134.584676)
		(end 96.416362 134.596317)
		(width 0.1)
		(layer "In2.Cu")
		(net 188)
	)
	(segment
		(start 96.455542 135.17255)
		(end 96.477286 135.175)
		(width 0.1)
		(layer "In2.Cu")
		(net 188)
	)
	(segment
		(start 96.40089 134.73821)
		(end 96.416362 134.753682)
		(width 0.1)
		(layer "In2.Cu")
		(net 188)
	)
	(segment
		(start 96.434889 133.965323)
		(end 96.455542 133.97255)
		(width 0.1)
		(layer "In2.Cu")
		(net 188)
	)
	(segment
		(start 96.477286 134.975)
		(end 96.455542 134.977449)
		(width 0.1)
		(layer "In2.Cu")
		(net 188)
	)
	(segment
		(start 96.625 135.575)
		(end 96.636127 135.576253)
		(width 0.1)
		(layer "In2.Cu")
		(net 188)
	)
	(segment
		(start 96.389249 135.030316)
		(end 96.382022 135.050969)
		(width 0.1)
		(layer "In2.Cu")
		(net 188)
	)
	(segment
		(start 96.455542 133.570263)
		(end 96.477287 133.572713)
		(width 0.1)
		(layer "In2.Cu")
		(net 188)
	)
	(segment
		(start 96.636127 134.573746)
		(end 96.625 134.575)
		(width 0.1)
		(layer "In2.Cu")
		(net 188)
	)
	(segment
		(start 96.664092 137.356174)
		(end 96.656175 137.364091)
		(width 0.1)
		(layer "In2.Cu")
		(net 188)
	)
	(segment
		(start 96.664092 133.756174)
		(end 96.656175 133.764091)
		(width 0.1)
		(layer "In2.Cu")
		(net 188)
	)
	(segment
		(start 96.675 135.625)
		(end 96.675 135.725)
		(width 0.1)
		(layer "In2.Cu")
		(net 188)
	)
	(segment
		(start 96.434889 133.382389)
		(end 96.416362 133.39403)
		(width 0.1)
		(layer "In2.Cu")
		(net 188)
	)
	(segment
		(start 96.416362 134.996317)
		(end 96.40089 135.011789)
		(width 0.1)
		(layer "In2.Cu")
		(net 188)
	)
	(segment
		(start 96.625 134.175)
		(end 96.477286 134.175)
		(width 0.1)
		(layer "In2.Cu")
		(net 188)
	)
	(segment
		(start 96.670049 136.403305)
		(end 96.673747 136.413873)
		(width 0.1)
		(layer "In2.Cu")
		(net 188)
	)
	(segment
		(start 96.670049 137.346694)
		(end 96.664092 137.356174)
		(width 0.1)
		(layer "In2.Cu")
		(net 188)
	)
	(segment
		(start 96.477286 135.375)
		(end 96.455542 135.377449)
		(width 0.1)
		(layer "In2.Cu")
		(net 188)
	)
	(segment
		(start 96.575 133.575)
		(end 96.625 133.575)
		(width 0.1)
		(layer "In2.Cu")
		(net 188)
	)
	(segment
		(start 96.673747 134.013873)
		(end 96.675 134.025)
		(width 0.1)
		(layer "In2.Cu")
		(net 188)
	)
	(segment
		(start 96.670049 134.803305)
		(end 96.673747 134.813873)
		(width 0.1)
		(layer "In2.Cu")
		(net 188)
	)
	(segment
		(start 96.664092 137.193825)
		(end 96.670049 137.203305)
		(width 0.1)
		(layer "In2.Cu")
		(net 188)
	)
	(segment
		(start 96.389249 136.230316)
		(end 96.382022 136.250969)
		(width 0.1)
		(layer "In2.Cu")
		(net 188)
	)
	(segment
		(start 96.389249 135.519683)
		(end 96.40089 135.53821)
		(width 0.1)
		(layer "In2.Cu")
		(net 188)
	)
	(segment
		(start 96.389249 136.630316)
		(end 96.382022 136.650969)
		(width 0.1)
		(layer "In2.Cu")
		(net 188)
	)
	(segment
		(start 96.656175 134.385908)
		(end 96.664092 134.393825)
		(width 0.1)
		(layer "In2.Cu")
		(net 188)
	)
	(segment
		(start 96.664092 135.993825)
		(end 96.670049 136.003305)
		(width 0.1)
		(layer "In2.Cu")
		(net 188)
	)
	(segment
		(start 96.670049 135.346694)
		(end 96.664092 135.356174)
		(width 0.1)
		(layer "In2.Cu")
		(net 188)
	)
	(segment
		(start 96.477286 136.575)
		(end 96.455542 136.577449)
		(width 0.1)
		(layer "In2.Cu")
		(net 188)
	)
	(segment
		(start 96.40089 133.535923)
		(end 96.416362 133.551395)
		(width 0.1)
		(layer "In2.Cu")
		(net 188)
	)
	(segment
		(start 96.646695 135.579951)
		(end 96.656175 135.585908)
		(width 0.1)
		(layer "In2.Cu")
		(net 188)
	)
	(segment
		(start 96.625 137.375)
		(end 96.477286 137.375)
		(width 0.1)
		(layer "In2.Cu")
		(net 188)
	)
	(segment
		(start 96.670049 136.146694)
		(end 96.664092 136.156174)
		(width 0.1)
		(layer "In2.Cu")
		(net 188)
	)
	(segment
		(start 96.477286 133.975)
		(end 96.625 133.975)
		(width 0.1)
		(layer "In2.Cu")
		(net 188)
	)
	(segment
		(start 96.636127 133.773746)
		(end 96.625 133.775)
		(width 0.1)
		(layer "In2.Cu")
		(net 188)
	)
	(segment
		(start 96.675 135.325)
		(end 96.673747 135.336126)
		(width 0.1)
		(layer "In2.Cu")
		(net 188)
	)
	(segment
		(start 96.389249 137.430316)
		(end 96.382022 137.450969)
		(width 0.1)
		(layer "In2.Cu")
		(net 188)
	)
	(segment
		(start 96.636127 133.976253)
		(end 96.646695 133.979951)
		(width 0.1)
		(layer "In2.Cu")
		(net 188)
	)
	(segment
		(start 96.416362 134.353682)
		(end 96.434889 134.365323)
		(width 0.1)
		(layer "In2.Cu")
		(net 188)
	)
	(segment
		(start 96.656175 133.764091)
		(end 96.646695 133.770048)
		(width 0.1)
		(layer "In2.Cu")
		(net 188)
	)
	(segment
		(start 96.646695 136.570048)
		(end 96.636127 136.573746)
		(width 0.1)
		(layer "In2.Cu")
		(net 188)
	)
	(segment
		(start 96.382022 135.850969)
		(end 96.379573 135.872713)
		(width 0.1)
		(layer "In2.Cu")
		(net 188)
	)
	(segment
		(start 96.434889 136.365323)
		(end 96.455542 136.37255)
		(width 0.1)
		(layer "In2.Cu")
		(net 188)
	)
	(segment
		(start 96.434889 134.765323)
		(end 96.455542 134.77255)
		(width 0.1)
		(layer "In2.Cu")
		(net 188)
	)
	(segment
		(start 96.455542 134.37255)
		(end 96.477286 134.375)
		(width 0.1)
		(layer "In2.Cu")
		(net 188)
	)
	(segment
		(start 96.625 134.375)
		(end 96.636127 134.376253)
		(width 0.1)
		(layer "In2.Cu")
		(net 188)
	)
	(segment
		(start 96.379573 135.877287)
		(end 96.382022 135.89903)
		(width 0.1)
		(layer "In2.Cu")
		(net 188)
	)
	(segment
		(start 96.656175 134.164091)
		(end 96.646695 134.170048)
		(width 0.1)
		(layer "In2.Cu")
		(net 188)
	)
	(segment
		(start 96.382022 134.69903)
		(end 96.389249 134.719683)
		(width 0.1)
		(layer "In2.Cu")
		(net 188)
	)
	(segment
		(start 96.382022 133.850969)
		(end 96.379573 133.872713)
		(width 0.1)
		(layer "In2.Cu")
		(net 188)
	)
	(segment
		(start 96.434889 134.184676)
		(end 96.416362 134.196317)
		(width 0.1)
		(layer "In2.Cu")
		(net 188)
	)
	(segment
		(start 96.646695 136.970048)
		(end 96.636127 136.973746)
		(width 0.1)
		(layer "In2.Cu")
		(net 188)
	)
	(segment
		(start 96.656175 135.764091)
		(end 96.646695 135.770048)
		(width 0.1)
		(layer "In2.Cu")
		(net 188)
	)
	(segment
		(start 96.434889 136.584676)
		(end 96.416362 136.596317)
		(width 0.1)
		(layer "In2.Cu")
		(net 188)
	)
	(segment
		(start 96.40089 135.811789)
		(end 96.389249 135.830316)
		(width 0.1)
		(layer "In2.Cu")
		(net 188)
	)
	(segment
		(start 96.664092 134.156174)
		(end 96.656175 134.164091)
		(width 0.1)
		(layer "In2.Cu")
		(net 188)
	)
	(segment
		(start 96.416362 136.996317)
		(end 96.40089 137.011789)
		(width 0.1)
		(layer "In2.Cu")
		(net 188)
	)
	(segment
		(start 96.477286 134.175)
		(end 96.455542 134.177449)
		(width 0.1)
		(layer "In2.Cu")
		(net 188)
	)
	(segment
		(start 96.382022 135.450969)
		(end 96.379573 135.472713)
		(width 0.1)
		(layer "In2.Cu")
		(net 188)
	)
	(segment
		(start 96.40089 135.53821)
		(end 96.416362 135.553682)
		(width 0.1)
		(layer "In2.Cu")
		(net 188)
	)
	(segment
		(start 96.455542 133.777449)
		(end 96.434889 133.784676)
		(width 0.1)
		(layer "In2.Cu")
		(net 188)
	)
	(segment
		(start 96.656175 133.985908)
		(end 96.664092 133.993825)
		(width 0.1)
		(layer "In2.Cu")
		(net 188)
	)
	(segment
		(start 96.656175 136.785908)
		(end 96.664092 136.793825)
		(width 0.1)
		(layer "In2.Cu")
		(net 188)
	)
	(segment
		(start 96.625 137.175)
		(end 96.636127 137.176253)
		(width 0.1)
		(layer "In2.Cu")
		(net 188)
	)
	(segment
		(start 96.477286 133.775)
		(end 96.455542 133.777449)
		(width 0.1)
		(layer "In2.Cu")
		(net 188)
	)
	(segment
		(start 96.664092 136.556174)
		(end 96.656175 136.564091)
		(width 0.1)
		(layer "In2.Cu")
		(net 188)
	)
	(segment
		(start 96.389249 133.919683)
		(end 96.40089 133.93821)
		(width 0.1)
		(layer "In2.Cu")
		(net 188)
	)
	(segment
		(start 96.416362 133.796317)
		(end 96.40089 133.811789)
		(width 0.1)
		(layer "In2.Cu")
		(net 188)
	)
	(segment
		(start 96.575 128.375)
		(end 96.575 133.275)
		(width 0.1)
		(layer "In2.Cu")
		(net 188)
	)
	(segment
		(start 96.379573 135.872713)
		(end 96.379573 135.877287)
		(width 0.1)
		(layer "In2.Cu")
		(net 188)
	)
	(segment
		(start 96.49903 137.577449)
		(end 96.519683 137.584676)
		(width 0.1)
		(layer "In2.Cu")
		(net 188)
	)
	(segment
		(start 96.675 136.525)
		(end 96.673747 136.536126)
		(width 0.1)
		(layer "In2.Cu")
		(net 188)
	)
	(segment
		(start 96.455542 137.377449)
		(end 96.434889 137.384676)
		(width 0.1)
		(layer "In2.Cu")
		(net 188)
	)
	(segment
		(start 96.40089 134.611789)
		(end 96.389249 134.630316)
		(width 0.1)
		(layer "In2.Cu")
		(net 188)
	)
	(segment
		(start 96.670049 136.003305)
		(end 96.673747 136.013873)
		(width 0.1)
		(layer "In2.Cu")
		(net 188)
	)
	(segment
		(start 96.379573 137.477287)
		(end 96.382022 137.49903)
		(width 0.1)
		(layer "In2.Cu")
		(net 188)
	)
	(segment
		(start 96.553682 137.611789)
		(end 96.565323 137.630316)
		(width 0.1)
		(layer "In2.Cu")
		(net 188)
	)
	(segment
		(start 96.636127 133.576253)
		(end 96.646695 133.579951)
		(width 0.1)
		(layer "In2.Cu")
		(net 188)
	)
	(segment
		(start 96.416362 136.596317)
		(end 96.40089 136.611789)
		(width 0.1)
		(layer "In2.Cu")
		(net 188)
	)
	(segment
		(start 96.656175 134.964091)
		(end 96.646695 134.970048)
		(width 0.1)
		(layer "In2.Cu")
		(net 188)
	)
	(segment
		(start 96.664092 136.156174)
		(end 96.656175 136.164091)
		(width 0.1)
		(layer "In2.Cu")
		(net 188)
	)
	(segment
		(start 96.434889 137.565323)
		(end 96.455542 137.57255)
		(width 0.1)
		(layer "In2.Cu")
		(net 188)
	)
	(segment
		(start 96.40089 136.73821)
		(end 96.416362 136.753682)
		(width 0.1)
		(layer "In2.Cu")
		(net 188)
	)
	(segment
		(start 96.382022 133.496743)
		(end 96.389249 133.517396)
		(width 0.1)
		(layer "In2.Cu")
		(net 188)
	)
	(segment
		(start 96.379573 137.072713)
		(end 96.379573 137.077287)
		(width 0.1)
		(layer "In2.Cu")
		(net 188)
	)
	(segment
		(start 96.670049 136.546694)
		(end 96.664092 136.556174)
		(width 0.1)
		(layer "In2.Cu")
		(net 188)
	)
	(segment
		(start 96.673747 134.136126)
		(end 96.670049 134.146694)
		(width 0.1)
		(layer "In2.Cu")
		(net 188)
	)
	(segment
		(start 96.416362 137.553682)
		(end 96.434889 137.565323)
		(width 0.1)
		(layer "In2.Cu")
		(net 188)
	)
	(segment
		(start 96.673747 137.336126)
		(end 96.670049 137.346694)
		(width 0.1)
		(layer "In2.Cu")
		(net 188)
	)
	(segment
		(start 96.656175 137.185908)
		(end 96.664092 137.193825)
		(width 0.1)
		(layer "In2.Cu")
		(net 188)
	)
	(segment
		(start 96.664092 135.356174)
		(end 96.656175 135.364091)
		(width 0.1)
		(layer "In2.Cu")
		(net 188)
	)
	(segment
		(start 96.625 136.175)
		(end 96.477286 136.175)
		(width 0.1)
		(layer "In2.Cu")
		(net 188)
	)
	(segment
		(start 97.275 127.675)
		(end 96.575 128.375)
		(width 0.1)
		(layer "In2.Cu")
		(net 188)
	)
	(segment
		(start 96.382022 134.250969)
		(end 96.379573 134.272713)
		(width 0.1)
		(layer "In2.Cu")
		(net 188)
	)
	(segment
		(start 96.382022 134.650969)
		(end 96.379573 134.672713)
		(width 0.1)
		(layer "In2.Cu")
		(net 188)
	)
	(segment
		(start 96.636127 135.773746)
		(end 96.625 135.775)
		(width 0.1)
		(layer "In2.Cu")
		(net 188)
	)
	(segment
		(start 96.477286 136.175)
		(end 96.455542 136.177449)
		(width 0.1)
		(layer "In2.Cu")
		(net 188)
	)
	(segment
		(start 96.673747 134.813873)
		(end 96.675 134.825)
		(width 0.1)
		(layer "In2.Cu")
		(net 188)
	)
	(segment
		(start 96.379573 133.475)
		(end 96.382022 133.496743)
		(width 0.1)
		(layer "In2.Cu")
		(net 188)
	)
	(segment
		(start 96.379573 137.077287)
		(end 96.382022 137.09903)
		(width 0.1)
		(layer "In2.Cu")
		(net 188)
	)
	(segment
		(start 96.477286 134.775)
		(end 96.625 134.775)
		(width 0.1)
		(layer "In2.Cu")
		(net 188)
	)
	(segment
		(start 96.646695 136.170048)
		(end 96.636127 136.173746)
		(width 0.1)
		(layer "In2.Cu")
		(net 188)
	)
	(segment
		(start 96.670049 133.603305)
		(end 96.673747 133.613873)
		(width 0.1)
		(layer "In2.Cu")
		(net 188)
	)
	(segment
		(start 96.636127 136.776253)
		(end 96.646695 136.779951)
		(width 0.1)
		(layer "In2.Cu")
		(net 188)
	)
	(segment
		(start 96.57255 133.296743)
		(end 96.565323 133.317396)
		(width 0.1)
		(layer "In2.Cu")
		(net 188)
	)
	(segment
		(start 96.477286 136.375)
		(end 96.625 136.375)
		(width 0.1)
		(layer "In2.Cu")
		(net 188)
	)
	(segment
		(start 96.575 133.275)
		(end 96.57255 133.296743)
		(width 0.1)
		(layer "In2.Cu")
		(net 188)
	)
	(segment
		(start 96.636127 134.376253)
		(end 96.646695 134.379951)
		(width 0.1)
		(layer "In2.Cu")
		(net 188)
	)
	(segment
		(start 96.416362 135.153682)
		(end 96.434889 135.165323)
		(width 0.1)
		(layer "In2.Cu")
		(net 188)
	)
	(segment
		(start 96.379573 135.072713)
		(end 96.379573 135.077287)
		(width 0.1)
		(layer "In2.Cu")
		(net 188)
	)
	(segment
		(start 96.636127 135.976253)
		(end 96.646695 135.979951)
		(width 0.1)
		(layer "In2.Cu")
		(net 188)
	)
	(segment
		(start 96.455542 136.977449)
		(end 96.434889 136.984676)
		(width 0.1)
		(layer "In2.Cu")
		(net 188)
	)
	(segment
		(start 96.673747 137.213873)
		(end 96.675 137.225)
		(width 0.1)
		(layer "In2.Cu")
		(net 188)
	)
	(segment
		(start 96.625 136.375)
		(end 96.636127 136.376253)
		(width 0.1)
		(layer "In2.Cu")
		(net 188)
	)
	(segment
		(start 96.656175 135.985908)
		(end 96.664092 135.993825)
		(width 0.1)
		(layer "In2.Cu")
		(net 188)
	)
	(segment
		(start 96.379573 135.077287)
		(end 96.382022 135.09903)
		(width 0.1)
		(layer "In2.Cu")
		(net 188)
	)
	(segment
		(start 96.670049 135.746694)
		(end 96.664092 135.756174)
		(width 0.1)
		(layer "In2.Cu")
		(net 188)
	)
	(segment
		(start 96.389249 135.919683)
		(end 96.40089 135.93821)
		(width 0.1)
		(layer "In2.Cu")
		(net 188)
	)
	(segment
		(start 96.416362 136.196317)
		(end 96.40089 136.211789)
		(width 0.1)
		(layer "In2.Cu")
		(net 188)
	)
	(segment
		(start 96.40089 136.211789)
		(end 96.389249 136.230316)
		(width 0.1)
		(layer "In2.Cu")
		(net 188)
	)
	(segment
		(start 96.382022 134.29903)
		(end 96.389249 134.319683)
		(width 0.1)
		(layer "In2.Cu")
		(net 188)
	)
	(segment
		(start 96.434889 133.784676)
		(end 96.416362 133.796317)
		(width 0.1)
		(layer "In2.Cu")
		(net 188)
	)
	(segment
		(start 96.455542 134.577449)
		(end 96.434889 134.584676)
		(width 0.1)
		(layer "In2.Cu")
		(net 188)
	)
	(segment
		(start 96.477286 134.575)
		(end 96.455542 134.577449)
		(width 0.1)
		(layer "In2.Cu")
		(net 188)
	)
	(segment
		(start 96.565323 137.630316)
		(end 96.57255 137.650969)
		(width 0.1)
		(layer "In2.Cu")
		(net 188)
	)
	(segment
		(start 96.646695 134.570048)
		(end 96.636127 134.573746)
		(width 0.1)
		(layer "In2.Cu")
		(net 188)
	)
	(segment
		(start 96.670049 135.203305)
		(end 96.673747 135.213873)
		(width 0.1)
		(layer "In2.Cu")
		(net 188)
	)
	(segment
		(start 96.675 137.325)
		(end 96.673747 137.336126)
		(width 0.1)
		(layer "In2.Cu")
		(net 188)
	)
	(segment
		(start 96.646695 136.379951)
		(end 96.656175 136.385908)
		(width 0.1)
		(layer "In2.Cu")
		(net 188)
	)
	(segment
		(start 96.477286 134.375)
		(end 96.625 134.375)
		(width 0.1)
		(layer "In2.Cu")
		(net 188)
	)
	(segment
		(start 96.675 136.125)
		(end 96.673747 136.136126)
		(width 0.1)
		(layer "In2.Cu")
		(net 188)
	)
	(segment
		(start 96.40089 133.409502)
		(end 96.389249 133.428029)
		(width 0.1)
		(layer "In2.Cu")
		(net 188)
	)
	(segment
		(start 96.673747 133.613873)
		(end 96.675 133.625)
		(width 0.1)
		(layer "In2.Cu")
		(net 188)
	)
	(segment
		(start 96.477286 137.175)
		(end 96.625 137.175)
		(width 0.1)
		(layer "In2.Cu")
		(net 188)
	)
	(segment
		(start 96.664092 136.956174)
		(end 96.656175 136.964091)
		(width 0.1)
		(layer "In2.Cu")
		(net 188)
	)
	(segment
		(start 96.40089 137.011789)
		(end 96.389249 137.030316)
		(width 0.1)
		(layer "In2.Cu")
		(net 188)
	)
	(segment
		(start 96.664092 134.393825)
		(end 96.670049 134.403305)
		(width 0.1)
		(layer "In2.Cu")
		(net 188)
	)
	(segment
		(start 96.673747 134.536126)
		(end 96.670049 134.546694)
		(width 0.1)
		(layer "In2.Cu")
		(net 188)
	)
	(segment
		(start 96.434889 134.365323)
		(end 96.455542 134.37255)
		(width 0.1)
		(layer "In2.Cu")
		(net 188)
	)
	(segment
		(start 96.519683 133.363036)
		(end 96.49903 133.370263)
		(width 0.1)
		(layer "In2.Cu")
		(net 188)
	)
	(segment
		(start 96.646695 135.770048)
		(end 96.636127 135.773746)
		(width 0.1)
		(layer "In2.Cu")
		(net 188)
	)
	(segment
		(start 96.379573 135.477287)
		(end 96.382022 135.49903)
		(width 0.1)
		(layer "In2.Cu")
		(net 188)
	)
	(segment
		(start 96.40089 137.13821)
		(end 96.416362 137.153682)
		(width 0.1)
		(layer "In2.Cu")
		(net 188)
	)
	(segment
		(start 96.434889 133.563036)
		(end 96.455542 133.570263)
		(width 0.1)
		(layer "In2.Cu")
		(net 188)
	)
	(segment
		(start 96.636127 134.173746)
		(end 96.625 134.175)
		(width 0.1)
		(layer "In2.Cu")
		(net 188)
	)
	(segment
		(start 96.455542 136.37255)
		(end 96.477286 136.375)
		(width 0.1)
		(layer "In2.Cu")
		(net 188)
	)
	(segment
		(start 96.455542 135.97255)
		(end 96.477286 135.975)
		(width 0.1)
		(layer "In2.Cu")
		(net 188)
	)
	(segment
		(start 96.673747 136.413873)
		(end 96.675 136.425)
		(width 0.1)
		(layer "In2.Cu")
		(net 188)
	)
	(segment
		(start 96.379573 133.877287)
		(end 96.382022 133.89903)
		(width 0.1)
		(layer "In2.Cu")
		(net 188)
	)
	(segment
		(start 96.656175 134.785908)
		(end 96.664092 134.793825)
		(width 0.1)
		(layer "In2.Cu")
		(net 188)
	)
	(segment
		(start 96.382022 136.69903)
		(end 96.389249 136.719683)
		(width 0.1)
		(layer "In2.Cu")
		(net 188)
	)
	(segment
		(start 96.625 134.775)
		(end 96.636127 134.776253)
		(width 0.1)
		(layer "In2.Cu")
		(net 188)
	)
	(segment
		(start 96.673747 136.136126)
		(end 96.670049 136.146694)
		(width 0.1)
		(layer "In2.Cu")
		(net 188)
	)
	(segment
		(start 96.673747 135.613873)
		(end 96.675 135.625)
		(width 0.1)
		(layer "In2.Cu")
		(net 188)
	)
	(segment
		(start 96.379573 136.272713)
		(end 96.379573 136.277287)
		(width 0.1)
		(layer "In2.Cu")
		(net 188)
	)
	(segment
		(start 96.675 133.625)
		(end 96.675 133.725)
		(width 0.1)
		(layer "In2.Cu")
		(net 188)
	)
	(segment
		(start 96.636127 134.973746)
		(end 96.625 134.975)
		(width 0.1)
		(layer "In2.Cu")
		(net 188)
	)
	(segment
		(start 96.416362 137.153682)
		(end 96.434889 137.165323)
		(width 0.1)
		(layer "In2.Cu")
		(net 188)
	)
	(segment
		(start 96.389249 134.319683)
		(end 96.40089 134.33821)
		(width 0.1)
		(layer "In2.Cu")
		(net 188)
	)
	(segment
		(start 96.382022 135.49903)
		(end 96.389249 135.519683)
		(width 0.1)
		(layer "In2.Cu")
		(net 188)
	)
	(segment
		(start 96.40089 135.411789)
		(end 96.389249 135.430316)
		(width 0.1)
		(layer "In2.Cu")
		(net 188)
	)
	(segment
		(start 96.455542 135.377449)
		(end 96.434889 135.384676)
		(width 0.1)
		(layer "In2.Cu")
		(net 188)
	)
	(segment
		(start 96.477286 135.575)
		(end 96.625 135.575)
		(width 0.1)
		(layer "In2.Cu")
		(net 188)
	)
	(segment
		(start 96.379573 136.672713)
		(end 96.379573 136.677287)
		(width 0.1)
		(layer "In2.Cu")
		(net 188)
	)
	(segment
		(start 96.625 136.775)
		(end 96.636127 136.776253)
		(width 0.1)
		(layer "In2.Cu")
		(net 188)
	)
	(segment
		(start 96.664092 135.193825)
		(end 96.670049 135.203305)
		(width 0.1)
		(layer "In2.Cu")
		(net 188)
	)
	(segment
		(start 96.625 133.775)
		(end 96.477286 133.775)
		(width 0.1)
		(layer "In2.Cu")
		(net 188)
	)
	(segment
		(start 96.670049 134.003305)
		(end 96.673747 134.013873)
		(width 0.1)
		(layer "In2.Cu")
		(net 188)
	)
	(segment
		(start 96.477286 137.375)
		(end 96.455542 137.377449)
		(width 0.1)
		(layer "In2.Cu")
		(net 188)
	)
	(segment
		(start 96.40089 134.33821)
		(end 96.416362 134.353682)
		(width 0.1)
		(layer "In2.Cu")
		(net 188)
	)
	(segment
		(start 96.656175 136.564091)
		(end 96.646695 136.570048)
		(width 0.1)
		(layer "In2.Cu")
		(net 188)
	)
	(segment
		(start 96.646695 137.370048)
		(end 96.636127 137.373746)
		(width 0.1)
		(layer "In2.Cu")
		(net 188)
	)
	(segment
		(start 96.675 134.525)
		(end 96.673747 134.536126)
		(width 0.1)
		(layer "In2.Cu")
		(net 188)
	)
	(segment
		(start 96.565323 133.317396)
		(end 96.553682 133.335923)
		(width 0.1)
		(layer "In2.Cu")
		(net 188)
	)
	(segment
		(start 96.434889 135.965323)
		(end 96.455542 135.97255)
		(width 0.1)
		(layer "In2.Cu")
		(net 188)
	)
	(segment
		(start 96.379573 133.872713)
		(end 96.379573 133.877287)
		(width 0.1)
		(layer "In2.Cu")
		(net 188)
	)
	(segment
		(start 96.625 134.975)
		(end 96.477286 134.975)
		(width 0.1)
		(layer "In2.Cu")
		(net 188)
	)
	(segment
		(start 96.519683 137.584676)
		(end 96.53821 137.596317)
		(width 0.1)
		(layer "In2.Cu")
		(net 188)
	)
	(segment
		(start 96.416362 135.553682)
		(end 96.434889 135.565323)
		(width 0.1)
		(layer "In2.Cu")
		(net 188)
	)
	(segment
		(start 96.553682 133.335923)
		(end 96.53821 133.351395)
		(width 0.1)
		(layer "In2.Cu")
		(net 188)
	)
	(segment
		(start 96.389249 134.719683)
		(end 96.40089 134.73821)
		(width 0.1)
		(layer "In2.Cu")
		(net 188)
	)
	(segment
		(start 96.636127 136.173746)
		(end 96.625 136.175)
		(width 0.1)
		(layer "In2.Cu")
		(net 188)
	)
	(segment
		(start 96.646695 135.179951)
		(end 96.656175 135.185908)
		(width 0.1)
		(layer "In2.Cu")
		(net 188)
	)
	(segment
		(start 96.49903 133.370263)
		(end 96.455542 133.375162)
		(width 0.1)
		(layer "In2.Cu")
		(net 188)
	)
	(segment
		(start 96.455542 136.77255)
		(end 96.477286 136.775)
		(width 0.1)
		(layer "In2.Cu")
		(net 188)
	)
	(segment
		(start 96.575 145.175)
		(end 96.175 145.575)
		(width 0.1)
		(layer "In2.Cu")
		(net 188)
	)
	(segment
		(start 96.455542 135.777449)
		(end 96.434889 135.784676)
		(width 0.1)
		(layer "In2.Cu")
		(net 188)
	)
	(segment
		(start 96.656175 137.364091)
		(end 96.646695 137.370048)
		(width 0.1)
		(layer "In2.Cu")
		(net 188)
	)
	(segment
		(start 96.434889 136.765323)
		(end 96.455542 136.77255)
		(width 0.1)
		(layer "In2.Cu")
		(net 188)
	)
	(segment
		(start 96.455542 133.97255)
		(end 96.477286 133.975)
		(width 0.1)
		(layer "In2.Cu")
		(net 188)
	)
	(segment
		(start 96.382022 135.89903)
		(end 96.389249 135.919683)
		(width 0.1)
		(layer "In2.Cu")
		(net 188)
	)
	(segment
		(start 96.625 133.975)
		(end 96.636127 133.976253)
		(width 0.1)
		(layer "In2.Cu")
		(net 188)
	)
	(segment
		(start 96.636127 134.776253)
		(end 96.646695 134.779951)
		(width 0.1)
		(layer "In2.Cu")
		(net 188)
	)
	(segment
		(start 96.673747 136.936126)
		(end 96.670049 136.946694)
		(width 0.1)
		(layer "In2.Cu")
		(net 188)
	)
	(segment
		(start 96.389249 136.719683)
		(end 96.40089 136.73821)
		(width 0.1)
		(layer "In2.Cu")
		(net 188)
	)
	(segment
		(start 96.455542 137.57255)
		(end 96.49903 137.577449)
		(width 0.1)
		(layer "In2.Cu")
		(net 188)
	)
	(segment
		(start 96.664092 135.756174)
		(end 96.656175 135.764091)
		(width 0.1)
		(layer "In2.Cu")
		(net 188)
	)
	(segment
		(start 96.416362 135.796317)
		(end 96.40089 135.811789)
		(width 0.1)
		(layer "In2.Cu")
		(net 188)
	)
	(segment
		(start 96.636127 137.176253)
		(end 96.646695 137.179951)
		(width 0.1)
		(layer "In2.Cu")
		(net 188)
	)
	(segment
		(start 96.646695 133.979951)
		(end 96.656175 133.985908)
		(width 0.1)
		(layer "In2.Cu")
		(net 188)
	)
	(segment
		(start 96.656175 135.585908)
		(end 96.664092 135.593825)
		(width 0.1)
		(layer "In2.Cu")
		(net 188)
	)
	(segment
		(start 96.477286 135.175)
		(end 96.625 135.175)
		(width 0.1)
		(layer "In2.Cu")
		(net 188)
	)
	(segment
		(start 96.664092 134.556174)
		(end 96.656175 134.564091)
		(width 0.1)
		(layer "In2.Cu")
		(net 188)
	)
	(segment
		(start 96.636127 136.973746)
		(end 96.625 136.975)
		(width 0.1)
		(layer "In2.Cu")
		(net 188)
	)
	(segment
		(start 96.636127 135.373746)
		(end 96.625 135.375)
		(width 0.1)
		(layer "In2.Cu")
		(net 188)
	)
	(segment
		(start 96.646695 133.770048)
		(end 96.636127 133.773746)
		(width 0.1)
		(layer "In2.Cu")
		(net 188)
	)
	(segment
		(start 96.379573 133.470426)
		(end 96.379573 133.475)
		(width 0.1)
		(layer "In2.Cu")
		(net 188)
	)
	(segment
		(start 96.664092 133.993825)
		(end 96.670049 134.003305)
		(width 0.1)
		(layer "In2.Cu")
		(net 188)
	)
	(segment
		(start 96.416362 133.39403)
		(end 96.40089 133.409502)
		(width 0.1)
		(layer "In2.Cu")
		(net 188)
	)
	(segment
		(start 96.675 134.425)
		(end 96.675 134.525)
		(width 0.1)
		(layer "In2.Cu")
		(net 188)
	)
	(segment
		(start 96.675 133.725)
		(end 96.673747 133.736126)
		(width 0.1)
		(layer "In2.Cu")
		(net 188)
	)
	(segment
		(start 96.646695 134.379951)
		(end 96.656175 134.385908)
		(width 0.1)
		(layer "In2.Cu")
		(net 188)
	)
	(segment
		(start 96.625 135.175)
		(end 96.636127 135.176253)
		(width 0.1)
		(layer "In2.Cu")
		(net 188)
	)
	(segment
		(start 96.416362 136.353682)
		(end 96.434889 136.365323)
		(width 0.1)
		(layer "In2.Cu")
		(net 188)
	)
	(segment
		(start 96.175 145.575)
		(end 96.175 146.175)
		(width 0.1)
		(layer "In2.Cu")
		(net 188)
	)
	(segment
		(start 96.646695 134.779951)
		(end 96.656175 134.785908)
		(width 0.1)
		(layer "In2.Cu")
		(net 188)
	)
	(segment
		(start 96.664092 134.793825)
		(end 96.670049 134.803305)
		(width 0.1)
		(layer "In2.Cu")
		(net 188)
	)
	(segment
		(start 96.575 133.572713)
		(end 96.575 133.575)
		(width 0.1)
		(layer "In2.Cu")
		(net 188)
	)
	(segment
		(start 96.636127 135.576253)
		(end 96.646695 135.579951)
		(width 0.1)
		(layer "In2.Cu")
		(net 188)
	)
	(segment
		(start 96.646695 136.779951)
		(end 96.656175 136.785908)
		(width 0.1)
		(layer "In2.Cu")
		(net 188)
	)
	(segment
		(start 96.673747 134.413873)
		(end 96.675 134.425)
		(width 0.1)
		(layer "In2.Cu")
		(net 188)
	)
	(segment
		(start 96.389249 133.517396)
		(end 96.40089 133.535923)
		(width 0.1)
		(layer "In2.Cu")
		(net 188)
	)
	(segment
		(start 96.379573 135.472713)
		(end 96.379573 135.477287)
		(width 0.1)
		(layer "In2.Cu")
		(net 188)
	)
	(segment
		(start 96.675 137.225)
		(end 96.675 137.325)
		(width 0.1)
		(layer "In2.Cu")
		(net 188)
	)
	(segment
		(start 96.389249 136.319683)
		(end 96.40089 136.33821)
		(width 0.1)
		(layer "In2.Cu")
		(net 188)
	)
	(segment
		(start 96.625 135.375)
		(end 96.477286 135.375)
		(width 0.1)
		(layer "In2.Cu")
		(net 188)
	)
	(segment
		(start 96.625 136.575)
		(end 96.477286 136.575)
		(width 0.1)
		(layer "In2.Cu")
		(net 188)
	)
	(segment
		(start 96.382022 133.448682)
		(end 96.379573 133.470426)
		(width 0.1)
		(layer "In2.Cu")
		(net 188)
	)
	(segment
		(start 96.675 134.825)
		(end 96.675 134.925)
		(width 0.1)
		(layer "In2.Cu")
		(net 188)
	)
	(segment
		(start 96.675 134.025)
		(end 96.675 134.125)
		(width 0.1)
		(layer "In2.Cu")
		(net 188)
	)
	(segment
		(start 96.625 133.575)
		(end 96.636127 133.576253)
		(width 0.1)
		(layer "In2.Cu")
		(net 188)
	)
	(segment
		(start 96.40089 135.011789)
		(end 96.389249 135.030316)
		(width 0.1)
		(layer "In2.Cu")
		(net 188)
	)
	(segment
		(start 96.382022 137.450969)
		(end 96.379573 137.472713)
		(width 0.1)
		(layer "In2.Cu")
		(net 188)
	)
	(segment
		(start 96.656175 133.585908)
		(end 96.664092 133.593825)
		(width 0.1)
		(layer "In2.Cu")
		(net 188)
	)
	(segment
		(start 96.389249 137.119683)
		(end 96.40089 137.13821)
		(width 0.1)
		(layer "In2.Cu")
		(net 188)
	)
	(segment
		(start 96.382022 136.250969)
		(end 96.379573 136.272713)
		(width 0.1)
		(layer "In2.Cu")
		(net 188)
	)
	(segment
		(start 96.382022 135.050969)
		(end 96.379573 135.072713)
		(width 0.1)
		(layer "In2.Cu")
		(net 188)
	)
	(segment
		(start 96.670049 133.746694)
		(end 96.664092 133.756174)
		(width 0.1)
		(layer "In2.Cu")
		(net 188)
	)
	(segment
		(start 96.379573 134.677287)
		(end 96.382022 134.69903)
		(width 0.1)
		(layer "In2.Cu")
		(net 188)
	)
	(segment
		(start 96.636127 136.376253)
		(end 96.646695 136.379951)
		(width 0.1)
		(layer "In2.Cu")
		(net 188)
	)
	(segment
		(start 96.664092 135.593825)
		(end 96.670049 135.603305)
		(width 0.1)
		(layer "In2.Cu")
		(net 188)
	)
	(segment
		(start 96.379573 136.677287)
		(end 96.382022 136.69903)
		(width 0.1)
		(layer "In2.Cu")
		(net 188)
	)
	(segment
		(start 96.675 136.825)
		(end 96.675 136.925)
		(width 0.1)
		(layer "In2.Cu")
		(net 188)
	)
	(segment
		(start 96.434889 135.565323)
		(end 96.455542 135.57255)
		(width 0.1)
		(layer "In2.Cu")
		(net 188)
	)
	(segment
		(start 96.675 136.025)
		(end 96.675 136.125)
		(width 0.1)
		(layer "In2.Cu")
		(net 188)
	)
	(segment
		(start 96.434889 134.984676)
		(end 96.416362 134.996317)
		(width 0.1)
		(layer "In2.Cu")
		(net 188)
	)
	(segment
		(start 96.389249 133.830316)
		(end 96.382022 133.850969)
		(width 0.1)
		(layer "In2.Cu")
		(net 188)
	)
	(segment
		(start 96.656175 136.385908)
		(end 96.664092 136.393825)
		(width 0.1)
		(layer "In2.Cu")
		(net 188)
	)
	(segment
		(start 96.379573 137.472713)
		(end 96.379573 137.477287)
		(width 0.1)
		(layer "In2.Cu")
		(net 188)
	)
	(segment
		(start 96.656175 136.964091)
		(end 96.646695 136.970048)
		(width 0.1)
		(layer "In2.Cu")
		(net 188)
	)
	(segment
		(start 96.646695 134.970048)
		(end 96.636127 134.973746)
		(width 0.1)
		(layer "In2.Cu")
		(net 188)
	)
	(segment
		(start 96.455542 137.17255)
		(end 96.477286 137.175)
		(width 0.1)
		(layer "In2.Cu")
		(net 188)
	)
	(segment
		(start 96.670049 136.946694)
		(end 96.664092 136.956174)
		(width 0.1)
		(layer "In2.Cu")
		(net 188)
	)
	(segment
		(start 96.477286 135.775)
		(end 96.455542 135.777449)
		(width 0.1)
		(layer "In2.Cu")
		(net 188)
	)
	(segment
		(start 96.434889 137.165323)
		(end 96.455542 137.17255)
		(width 0.1)
		(layer "In2.Cu")
		(net 188)
	)
	(segment
		(start 96.53821 133.351395)
		(end 96.519683 133.363036)
		(width 0.1)
		(layer "In2.Cu")
		(net 188)
	)
	(segment
		(start 96.416362 133.953682)
		(end 96.434889 133.965323)
		(width 0.1)
		(layer "In2.Cu")
		(net 188)
	)
	(segment
		(start 96.673747 133.736126)
		(end 96.670049 133.746694)
		(width 0.1)
		(layer "In2.Cu")
		(net 188)
	)
	(segment
		(start 96.673747 135.336126)
		(end 96.670049 135.346694)
		(width 0.1)
		(layer "In2.Cu")
		(net 188)
	)
	(segment
		(start 96.389249 134.230316)
		(end 96.382022 134.250969)
		(width 0.1)
		(layer "In2.Cu")
		(net 188)
	)
	(segment
		(start 96.575 137.672713)
		(end 96.575 145.175)
		(width 0.1)
		(layer "In2.Cu")
		(net 188)
	)
	(segment
		(start 96.625 135.775)
		(end 96.477286 135.775)
		(width 0.1)
		(layer "In2.Cu")
		(net 188)
	)
	(segment
		(start 96.389249 135.119683)
		(end 96.40089 135.13821)
		(width 0.1)
		(layer "In2.Cu")
		(net 188)
	)
	(segment
		(start 96.673747 136.013873)
		(end 96.675 136.025)
		(width 0.1)
		(layer "In2.Cu")
		(net 188)
	)
	(segment
		(start 100.074968 130.474968)
		(end 100.074968 130.675)
		(width 0.15)
		(layer "F.Cu")
		(net 189)
	)
	(segment
		(start 97.775 147.875)
		(end 98.275 147.375)
		(width 0.1)
		(layer "F.Cu")
		(net 189)
	)
	(segment
		(start 98.275 147.375)
		(end 99.075 147.375)
		(width 0.1)
		(layer "F.Cu")
		(net 189)
	)
	(segment
		(start 99.675 146.775)
		(end 99.699271 146.750729)
		(width 0.1)
		(layer "F.Cu")
		(net 189)
	)
	(segment
		(start 99.775 130.175)
		(end 100.074968 130.474968)
		(width 0.15)
		(layer "F.Cu")
		(net 189)
	)
	(segment
		(start 97.775 148.775)
		(end 97.775 147.875)
		(width 0.1)
		(layer "F.Cu")
		(net 189)
	)
	(segment
		(start 99.075 147.375)
		(end 99.675 146.775)
		(width 0.1)
		(layer "F.Cu")
		(net 189)
	)
	(via blind
		(at 99.699271 146.750729)
		(size 0.5)
		(drill 0.2)
		(layers "F.Cu" "In2.Cu")
		(net 189)
	)
	(via blind
		(at 100.074968 130.675)
		(size 0.5)
		(drill 0.2)
		(layers "F.Cu" "In2.Cu")
		(net 189)
	)
	(segment
		(start 100.206876 146.340825)
		(end 100.225836 146.328912)
		(width 0.1)
		(layer "In2.Cu")
		(net 189)
	)
	(segment
		(start 99.736922 145.328912)
		(end 99.721087 145.313077)
		(width 0.1)
		(layer "In2.Cu")
		(net 189)
	)
	(segment
		(start 99.701778 146.428476)
		(end 99.709174 146.40734)
		(width 0.1)
		(layer "In2.Cu")
		(net 189)
	)
	(segment
		(start 100.163488 145.350729)
		(end 99.799271 145.350729)
		(width 0.1)
		(layer "In2.Cu")
		(net 189)
	)
	(segment
		(start 100.163488 145.950729)
		(end 100.18574 145.948221)
		(width 0.1)
		(layer "In2.Cu")
		(net 189)
	)
	(segment
		(start 99.799271 145.350729)
		(end 99.777018 145.348221)
		(width 0.1)
		(layer "In2.Cu")
		(net 189)
	)
	(segment
		(start 99.341666 145.740825)
		(end 99.322706 145.728912)
		(width 0.1)
		(layer "In2.Cu")
		(net 189)
	)
	(segment
		(start 100.225836 146.172545)
		(end 100.206876 146.160632)
		(width 0.1)
		(layer "In2.Cu")
		(net 189)
	)
	(segment
		(start 99.799271 146.350729)
		(end 100.163488 146.350729)
		(width 0.1)
		(layer "In2.Cu")
		(net 189)
	)
	(segment
		(start 100.18574 146.153236)
		(end 100.163488 146.150729)
		(width 0.1)
		(layer "In2.Cu")
		(net 189)
	)
	(segment
		(start 100.163488 145.550729)
		(end 100.18574 145.548221)
		(width 0.1)
		(layer "In2.Cu")
		(net 189)
	)
	(segment
		(start 99.362802 146.148221)
		(end 99.341666 146.140825)
		(width 0.1)
		(layer "In2.Cu")
		(net 189)
	)
	(segment
		(start 100.274967 144.275033)
		(end 100.274967 132.124967)
		(width 0.1)
		(layer "In2.Cu")
		(net 189)
	)
	(segment
		(start 100.26098 145.428476)
		(end 100.253584 145.40734)
		(width 0.1)
		(layer "In2.Cu")
		(net 189)
	)
	(segment
		(start 99.362802 145.553236)
		(end 99.385054 145.550729)
		(width 0.1)
		(layer "In2.Cu")
		(net 189)
	)
	(segment
		(start 100.241671 145.513077)
		(end 100.253584 145.494117)
		(width 0.1)
		(layer "In2.Cu")
		(net 189)
	)
	(segment
		(start 99.306871 145.98838)
		(end 99.322706 145.972545)
		(width 0.1)
		(layer "In2.Cu")
		(net 189)
	)
	(segment
		(start 99.322706 145.572545)
		(end 99.341666 145.560632)
		(width 0.1)
		(layer "In2.Cu")
		(net 189)
	)
	(segment
		(start 100.206876 145.540825)
		(end 100.225836 145.528912)
		(width 0.1)
		(layer "In2.Cu")
		(net 189)
	)
	(segment
		(start 100.225836 145.528912)
		(end 100.241671 145.513077)
		(width 0.1)
		(layer "In2.Cu")
		(net 189)
	)
	(segment
		(start 99.777018 145.348221)
		(end 99.755882 145.340825)
		(width 0.1)
		(layer "In2.Cu")
		(net 189)
	)
	(segment
		(start 100.26098 146.228476)
		(end 100.253584 146.20734)
		(width 0.1)
		(layer "In2.Cu")
		(net 189)
	)
	(segment
		(start 99.285054 145.650729)
		(end 99.287562 145.628476)
		(width 0.1)
		(layer "In2.Cu")
		(net 189)
	)
	(segment
		(start 100.18574 145.548221)
		(end 100.206876 145.540825)
		(width 0.1)
		(layer "In2.Cu")
		(net 189)
	)
	(segment
		(start 100.241671 146.313077)
		(end 100.253584 146.294117)
		(width 0.1)
		(layer "In2.Cu")
		(net 189)
	)
	(segment
		(start 99.362802 145.748221)
		(end 99.341666 145.740825)
		(width 0.1)
		(layer "In2.Cu")
		(net 189)
	)
	(segment
		(start 100.206876 146.160632)
		(end 100.18574 146.153236)
		(width 0.1)
		(layer "In2.Cu")
		(net 189)
	)
	(segment
		(start 100.26098 146.272981)
		(end 100.263488 146.250729)
		(width 0.1)
		(layer "In2.Cu")
		(net 189)
	)
	(segment
		(start 100.225836 145.772545)
		(end 100.206876 145.760632)
		(width 0.1)
		(layer "In2.Cu")
		(net 189)
	)
	(segment
		(start 99.341666 145.960632)
		(end 99.362802 145.953236)
		(width 0.1)
		(layer "In2.Cu")
		(net 189)
	)
	(segment
		(start 100.225836 145.372545)
		(end 100.206876 145.360632)
		(width 0.1)
		(layer "In2.Cu")
		(net 189)
	)
	(segment
		(start 99.701778 145.272981)
		(end 99.699271 145.250729)
		(width 0.1)
		(layer "In2.Cu")
		(net 189)
	)
	(segment
		(start 100.253584 145.894117)
		(end 100.26098 145.872981)
		(width 0.1)
		(layer "In2.Cu")
		(net 189)
	)
	(segment
		(start 100.163488 146.350729)
		(end 100.18574 146.348221)
		(width 0.1)
		(layer "In2.Cu")
		(net 189)
	)
	(segment
		(start 99.699271 146.450729)
		(end 99.701778 146.428476)
		(width 0.1)
		(layer "In2.Cu")
		(net 189)
	)
	(segment
		(start 99.294958 146.094117)
		(end 99.287562 146.072981)
		(width 0.1)
		(layer "In2.Cu")
		(net 189)
	)
	(segment
		(start 100.241671 145.913077)
		(end 100.253584 145.894117)
		(width 0.1)
		(layer "In2.Cu")
		(net 189)
	)
	(segment
		(start 100.26098 145.472981)
		(end 100.263488 145.450729)
		(width 0.1)
		(layer "In2.Cu")
		(net 189)
	)
	(segment
		(start 99.287562 145.628476)
		(end 99.294958 145.60734)
		(width 0.1)
		(layer "In2.Cu")
		(net 189)
	)
	(segment
		(start 100.26098 145.872981)
		(end 100.263488 145.850729)
		(width 0.1)
		(layer "In2.Cu")
		(net 189)
	)
	(segment
		(start 99.306871 146.113077)
		(end 99.294958 146.094117)
		(width 0.1)
		(layer "In2.Cu")
		(net 189)
	)
	(segment
		(start 100.253584 145.494117)
		(end 100.26098 145.472981)
		(width 0.1)
		(layer "In2.Cu")
		(net 189)
	)
	(segment
		(start 99.699271 145.250729)
		(end 99.699271 144.850729)
		(width 0.1)
		(layer "In2.Cu")
		(net 189)
	)
	(segment
		(start 99.322706 145.972545)
		(end 99.341666 145.960632)
		(width 0.1)
		(layer "In2.Cu")
		(net 189)
	)
	(segment
		(start 99.755882 146.360632)
		(end 99.777018 146.353236)
		(width 0.1)
		(layer "In2.Cu")
		(net 189)
	)
	(segment
		(start 100.163488 146.150729)
		(end 99.385054 146.150729)
		(width 0.1)
		(layer "In2.Cu")
		(net 189)
	)
	(segment
		(start 99.736922 146.372545)
		(end 99.755882 146.360632)
		(width 0.1)
		(layer "In2.Cu")
		(net 189)
	)
	(segment
		(start 99.385054 145.750729)
		(end 99.362802 145.748221)
		(width 0.1)
		(layer "In2.Cu")
		(net 189)
	)
	(segment
		(start 100.263488 145.850729)
		(end 100.26098 145.828476)
		(width 0.1)
		(layer "In2.Cu")
		(net 189)
	)
	(segment
		(start 99.287562 146.028476)
		(end 99.294958 146.00734)
		(width 0.1)
		(layer "In2.Cu")
		(net 189)
	)
	(segment
		(start 99.287562 146.072981)
		(end 99.285054 146.050729)
		(width 0.1)
		(layer "In2.Cu")
		(net 189)
	)
	(segment
		(start 99.709174 146.40734)
		(end 99.721087 146.38838)
		(width 0.1)
		(layer "In2.Cu")
		(net 189)
	)
	(segment
		(start 99.294958 145.60734)
		(end 99.306871 145.58838)
		(width 0.1)
		(layer "In2.Cu")
		(net 189)
	)
	(segment
		(start 100.263488 145.450729)
		(end 100.26098 145.428476)
		(width 0.1)
		(layer "In2.Cu")
		(net 189)
	)
	(segment
		(start 99.875 130.874968)
		(end 100.074968 130.675)
		(width 0.1)
		(layer "In2.Cu")
		(net 189)
	)
	(segment
		(start 99.287562 145.672981)
		(end 99.285054 145.650729)
		(width 0.1)
		(layer "In2.Cu")
		(net 189)
	)
	(segment
		(start 100.18574 145.353236)
		(end 100.163488 145.350729)
		(width 0.1)
		(layer "In2.Cu")
		(net 189)
	)
	(segment
		(start 100.241671 146.18838)
		(end 100.225836 146.172545)
		(width 0.1)
		(layer "In2.Cu")
		(net 189)
	)
	(segment
		(start 100.253584 145.80734)
		(end 100.241671 145.78838)
		(width 0.1)
		(layer "In2.Cu")
		(net 189)
	)
	(segment
		(start 99.755882 145.340825)
		(end 99.736922 145.328912)
		(width 0.1)
		(layer "In2.Cu")
		(net 189)
	)
	(segment
		(start 99.294958 145.694117)
		(end 99.287562 145.672981)
		(width 0.1)
		(layer "In2.Cu")
		(net 189)
	)
	(segment
		(start 99.341666 145.560632)
		(end 99.362802 145.553236)
		(width 0.1)
		(layer "In2.Cu")
		(net 189)
	)
	(segment
		(start 99.875 131.725)
		(end 99.875 130.874968)
		(width 0.1)
		(layer "In2.Cu")
		(net 189)
	)
	(segment
		(start 100.206876 145.940825)
		(end 100.225836 145.928912)
		(width 0.1)
		(layer "In2.Cu")
		(net 189)
	)
	(segment
		(start 99.322706 146.128912)
		(end 99.306871 146.113077)
		(width 0.1)
		(layer "In2.Cu")
		(net 189)
	)
	(segment
		(start 100.18574 145.753236)
		(end 100.163488 145.750729)
		(width 0.1)
		(layer "In2.Cu")
		(net 189)
	)
	(segment
		(start 99.385054 145.950729)
		(end 100.163488 145.950729)
		(width 0.1)
		(layer "In2.Cu")
		(net 189)
	)
	(segment
		(start 99.285054 146.050729)
		(end 99.287562 146.028476)
		(width 0.1)
		(layer "In2.Cu")
		(net 189)
	)
	(segment
		(start 99.699271 144.850729)
		(end 100.274967 144.275033)
		(width 0.1)
		(layer "In2.Cu")
		(net 189)
	)
	(segment
		(start 100.253584 146.20734)
		(end 100.241671 146.18838)
		(width 0.1)
		(layer "In2.Cu")
		(net 189)
	)
	(segment
		(start 100.253584 146.294117)
		(end 100.26098 146.272981)
		(width 0.1)
		(layer "In2.Cu")
		(net 189)
	)
	(segment
		(start 99.306871 145.58838)
		(end 99.322706 145.572545)
		(width 0.1)
		(layer "In2.Cu")
		(net 189)
	)
	(segment
		(start 100.206876 145.360632)
		(end 100.18574 145.353236)
		(width 0.1)
		(layer "In2.Cu")
		(net 189)
	)
	(segment
		(start 100.253584 145.40734)
		(end 100.241671 145.38838)
		(width 0.1)
		(layer "In2.Cu")
		(net 189)
	)
	(segment
		(start 100.18574 145.948221)
		(end 100.206876 145.940825)
		(width 0.1)
		(layer "In2.Cu")
		(net 189)
	)
	(segment
		(start 99.777018 146.353236)
		(end 99.799271 146.350729)
		(width 0.1)
		(layer "In2.Cu")
		(net 189)
	)
	(segment
		(start 100.225836 146.328912)
		(end 100.241671 146.313077)
		(width 0.1)
		(layer "In2.Cu")
		(net 189)
	)
	(segment
		(start 99.699271 146.750729)
		(end 99.699271 146.450729)
		(width 0.1)
		(layer "In2.Cu")
		(net 189)
	)
	(segment
		(start 100.241671 145.78838)
		(end 100.225836 145.772545)
		(width 0.1)
		(layer "In2.Cu")
		(net 189)
	)
	(segment
		(start 100.18574 146.348221)
		(end 100.206876 146.340825)
		(width 0.1)
		(layer "In2.Cu")
		(net 189)
	)
	(segment
		(start 100.206876 145.760632)
		(end 100.18574 145.753236)
		(width 0.1)
		(layer "In2.Cu")
		(net 189)
	)
	(segment
		(start 100.241671 145.38838)
		(end 100.225836 145.372545)
		(width 0.1)
		(layer "In2.Cu")
		(net 189)
	)
	(segment
		(start 99.306871 145.713077)
		(end 99.294958 145.694117)
		(width 0.1)
		(layer "In2.Cu")
		(net 189)
	)
	(segment
		(start 99.721087 146.38838)
		(end 99.736922 146.372545)
		(width 0.1)
		(layer "In2.Cu")
		(net 189)
	)
	(segment
		(start 100.263488 146.250729)
		(end 100.26098 146.228476)
		(width 0.1)
		(layer "In2.Cu")
		(net 189)
	)
	(segment
		(start 100.274967 132.124967)
		(end 99.875 131.725)
		(width 0.1)
		(layer "In2.Cu")
		(net 189)
	)
	(segment
		(start 99.362802 145.953236)
		(end 99.385054 145.950729)
		(width 0.1)
		(layer "In2.Cu")
		(net 189)
	)
	(segment
		(start 99.294958 146.00734)
		(end 99.306871 145.98838)
		(width 0.1)
		(layer "In2.Cu")
		(net 189)
	)
	(segment
		(start 100.163488 145.750729)
		(end 99.385054 145.750729)
		(width 0.1)
		(layer "In2.Cu")
		(net 189)
	)
	(segment
		(start 99.709174 145.294117)
		(end 99.701778 145.272981)
		(width 0.1)
		(layer "In2.Cu")
		(net 189)
	)
	(segment
		(start 100.26098 145.828476)
		(end 100.253584 145.80734)
		(width 0.1)
		(layer "In2.Cu")
		(net 189)
	)
	(segment
		(start 99.322706 145.728912)
		(end 99.306871 145.713077)
		(width 0.1)
		(layer "In2.Cu")
		(net 189)
	)
	(segment
		(start 99.385054 145.550729)
		(end 100.163488 145.550729)
		(width 0.1)
		(layer "In2.Cu")
		(net 189)
	)
	(segment
		(start 99.385054 146.150729)
		(end 99.362802 146.148221)
		(width 0.1)
		(layer "In2.Cu")
		(net 189)
	)
	(segment
		(start 100.225836 145.928912)
		(end 100.241671 145.913077)
		(width 0.1)
		(layer "In2.Cu")
		(net 189)
	)
	(segment
		(start 99.721087 145.313077)
		(end 99.709174 145.294117)
		(width 0.1)
		(layer "In2.Cu")
		(net 189)
	)
	(segment
		(start 99.341666 146.140825)
		(end 99.322706 146.128912)
		(width 0.1)
		(layer "In2.Cu")
		(net 189)
	)
	(segment
		(start 96.275 147.175)
		(end 98.575 147.175)
		(width 0.1)
		(layer "F.Cu")
		(net 190)
	)
	(segment
		(start 95.775 145.175)
		(end 95.775 146.675)
		(width 0.1)
		(layer "F.Cu")
		(net 190)
	)
	(segment
		(start 95.775 146.675)
		(end 96.275 147.175)
		(width 0.1)
		(layer "F.Cu")
		(net 190)
	)
	(segment
		(start 99.274957 130.674957)
		(end 99.274957 130.675)
		(width 0.15)
		(layer "F.Cu")
		(net 190)
	)
	(segment
		(start 98.775 130.175)
		(end 99.274957 130.674957)
		(width 0.15)
		(layer "F.Cu")
		(net 190)
	)
	(segment
		(start 98.575 147.175)
		(end 98.775 146.975)
		(width 0.1)
		(layer "F.Cu")
		(net 190)
	)
	(segment
		(start 96.175 144.775)
		(end 95.775 145.175)
		(width 0.1)
		(layer "F.Cu")
		(net 190)
	)
	(via blind
		(at 99.274957 130.675)
		(size 0.5)
		(drill 0.2)
		(layers "F.Cu" "In2.Cu")
		(net 190)
	)
	(via blind
		(at 98.775 146.975)
		(size 0.5)
		(drill 0.2)
		(layers "F.Cu" "In2.Cu")
		(net 190)
	)
	(segment
		(start 99.457864 131.820006)
		(end 99.457864 131.8371)
		(width 0.1)
		(layer "In2.Cu")
		(net 190)
	)
	(segment
		(start 99.366411 131.928553)
		(end 98.74205 131.928553)
		(width 0.1)
		(layer "In2.Cu")
		(net 190)
	)
	(segment
		(start 98.663866 131.966204)
		(end 98.651953 131.985164)
		(width 0.1)
		(layer "In2.Cu")
		(net 190)
	)
	(segment
		(start 98.651953 131.271941)
		(end 98.663866 131.290901)
		(width 0.1)
		(layer "In2.Cu")
		(net 190)
	)
	(segment
		(start 99.457864 133.020006)
		(end 99.457864 133.0371)
		(width 0.1)
		(layer "In2.Cu")
		(net 190)
	)
	(segment
		(start 98.74205 133.328553)
		(end 99.174957 133.328553)
		(width 0.1)
		(layer "In2.Cu")
		(net 190)
	)
	(segment
		(start 98.651953 131.985164)
		(end 98.644557 132.0063)
		(width 0.1)
		(layer "In2.Cu")
		(net 190)
	)
	(segment
		(start 99.174957 131.128553)
		(end 98.74205 131.128553)
		(width 0.1)
		(layer "In2.Cu")
		(net 190)
	)
	(segment
		(start 98.663866 131.166204)
		(end 98.651953 131.185164)
		(width 0.1)
		(layer "In2.Cu")
		(net 190)
	)
	(segment
		(start 99.448808 132.276779)
		(end 99.437912 132.29412)
		(width 0.1)
		(layer "In2.Cu")
		(net 190)
	)
	(segment
		(start 99.366411 132.728553)
		(end 98.74205 132.728553)
		(width 0.1)
		(layer "In2.Cu")
		(net 190)
	)
	(segment
		(start 98.64205 132.828553)
		(end 98.644557 132.850805)
		(width 0.1)
		(layer "In2.Cu")
		(net 190)
	)
	(segment
		(start 99.274957 130.675)
		(end 99.274957 131.028553)
		(width 0.1)
		(layer "In2.Cu")
		(net 190)
	)
	(segment
		(start 99.455572 132.599655)
		(end 99.457864 132.620006)
		(width 0.1)
		(layer "In2.Cu")
		(net 190)
	)
	(segment
		(start 99.197209 131.126045)
		(end 99.174957 131.128553)
		(width 0.1)
		(layer "In2.Cu")
		(net 190)
	)
	(segment
		(start 99.174957 133.328553)
		(end 99.197209 133.33106)
		(width 0.1)
		(layer "In2.Cu")
		(net 190)
	)
	(segment
		(start 99.448808 131.780326)
		(end 99.455572 131.799655)
		(width 0.1)
		(layer "In2.Cu")
		(net 190)
	)
	(segment
		(start 99.366411 131.328553)
		(end 99.386762 131.330845)
		(width 0.1)
		(layer "In2.Cu")
		(net 190)
	)
	(segment
		(start 99.237305 131.106736)
		(end 99.218345 131.118649)
		(width 0.1)
		(layer "In2.Cu")
		(net 190)
	)
	(segment
		(start 98.679701 131.306736)
		(end 98.698661 131.318649)
		(width 0.1)
		(layer "In2.Cu")
		(net 190)
	)
	(segment
		(start 98.74205 132.728553)
		(end 98.719797 132.73106)
		(width 0.1)
		(layer "In2.Cu")
		(net 190)
	)
	(segment
		(start 98.663866 133.166204)
		(end 98.651953 133.185164)
		(width 0.1)
		(layer "In2.Cu")
		(net 190)
	)
	(segment
		(start 99.455572 133.05745)
		(end 99.448808 133.076779)
		(width 0.1)
		(layer "In2.Cu")
		(net 190)
	)
	(segment
		(start 98.719797 132.73106)
		(end 98.698661 132.738456)
		(width 0.1)
		(layer "In2.Cu")
		(net 190)
	)
	(segment
		(start 98.74205 132.528553)
		(end 99.366411 132.528553)
		(width 0.1)
		(layer "In2.Cu")
		(net 190)
	)
	(segment
		(start 99.457864 133.0371)
		(end 99.455572 133.05745)
		(width 0.1)
		(layer "In2.Cu")
		(net 190)
	)
	(segment
		(start 98.644557 131.650805)
		(end 98.651953 131.671941)
		(width 0.1)
		(layer "In2.Cu")
		(net 190)
	)
	(segment
		(start 99.455572 131.399655)
		(end 99.457864 131.420006)
		(width 0.1)
		(layer "In2.Cu")
		(net 190)
	)
	(segment
		(start 99.448808 132.676779)
		(end 99.437912 132.69412)
		(width 0.1)
		(layer "In2.Cu")
		(net 190)
	)
	(segment
		(start 98.663866 132.490901)
		(end 98.679701 132.506736)
		(width 0.1)
		(layer "In2.Cu")
		(net 190)
	)
	(segment
		(start 98.74205 131.728553)
		(end 99.366411 131.728553)
		(width 0.1)
		(layer "In2.Cu")
		(net 190)
	)
	(segment
		(start 99.423432 132.3086)
		(end 99.406091 132.319496)
		(width 0.1)
		(layer "In2.Cu")
		(net 190)
	)
	(segment
		(start 98.775 142.775)
		(end 98.775 146.975)
		(width 0.1)
		(layer "In2.Cu")
		(net 190)
	)
	(segment
		(start 98.74205 132.328553)
		(end 98.719797 132.33106)
		(width 0.1)
		(layer "In2.Cu")
		(net 190)
	)
	(segment
		(start 98.644557 133.250805)
		(end 98.651953 133.271941)
		(width 0.1)
		(layer "In2.Cu")
		(net 190)
	)
	(segment
		(start 98.651953 132.785164)
		(end 98.644557 132.8063)
		(width 0.1)
		(layer "In2.Cu")
		(net 190)
	)
	(segment
		(start 99.366411 132.928553)
		(end 99.386762 132.930845)
		(width 0.1)
		(layer "In2.Cu")
		(net 190)
	)
	(segment
		(start 98.64205 131.228553)
		(end 98.644557 131.250805)
		(width 0.1)
		(layer "In2.Cu")
		(net 190)
	)
	(segment
		(start 99.386762 131.730845)
		(end 99.406091 131.737609)
		(width 0.1)
		(layer "In2.Cu")
		(net 190)
	)
	(segment
		(start 98.651953 132.871941)
		(end 98.663866 132.890901)
		(width 0.1)
		(layer "In2.Cu")
		(net 190)
	)
	(segment
		(start 98.719797 131.93106)
		(end 98.698661 131.938456)
		(width 0.1)
		(layer "In2.Cu")
		(net 190)
	)
	(segment
		(start 98.663866 131.690901)
		(end 98.679701 131.706736)
		(width 0.1)
		(layer "In2.Cu")
		(net 190)
	)
	(segment
		(start 99.406091 132.319496)
		(end 99.386762 132.32626)
		(width 0.1)
		(layer "In2.Cu")
		(net 190)
	)
	(segment
		(start 99.423432 132.148505)
		(end 99.437912 132.162985)
		(width 0.1)
		(layer "In2.Cu")
		(net 190)
	)
	(segment
		(start 99.386762 132.32626)
		(end 99.366411 132.328553)
		(width 0.1)
		(layer "In2.Cu")
		(net 190)
	)
	(segment
		(start 98.698661 132.118649)
		(end 98.719797 132.126045)
		(width 0.1)
		(layer "In2.Cu")
		(net 190)
	)
	(segment
		(start 98.644557 132.4063)
		(end 98.64205 132.428553)
		(width 0.1)
		(layer "In2.Cu")
		(net 190)
	)
	(segment
		(start 99.457864 132.220006)
		(end 99.457864 132.2371)
		(width 0.1)
		(layer "In2.Cu")
		(net 190)
	)
	(segment
		(start 98.698661 132.338456)
		(end 98.679701 132.350369)
		(width 0.1)
		(layer "In2.Cu")
		(net 190)
	)
	(segment
		(start 99.437912 132.29412)
		(end 99.423432 132.3086)
		(width 0.1)
		(layer "In2.Cu")
		(net 190)
	)
	(segment
		(start 99.457864 132.620006)
		(end 99.457864 132.6371)
		(width 0.1)
		(layer "In2.Cu")
		(net 190)
	)
	(segment
		(start 99.386762 132.72626)
		(end 99.366411 132.728553)
		(width 0.1)
		(layer "In2.Cu")
		(net 190)
	)
	(segment
		(start 98.651953 133.271941)
		(end 98.663866 133.290901)
		(width 0.1)
		(layer "In2.Cu")
		(net 190)
	)
	(segment
		(start 99.423432 132.948505)
		(end 99.437912 132.962985)
		(width 0.1)
		(layer "In2.Cu")
		(net 190)
	)
	(segment
		(start 99.423432 132.7086)
		(end 99.406091 132.719496)
		(width 0.1)
		(layer "In2.Cu")
		(net 190)
	)
	(segment
		(start 99.448808 132.180326)
		(end 99.455572 132.199655)
		(width 0.1)
		(layer "In2.Cu")
		(net 190)
	)
	(segment
		(start 99.457864 131.420006)
		(end 99.457864 131.4371)
		(width 0.1)
		(layer "In2.Cu")
		(net 190)
	)
	(segment
		(start 99.448808 131.476779)
		(end 99.437912 131.49412)
		(width 0.1)
		(layer "In2.Cu")
		(net 190)
	)
	(segment
		(start 98.644557 132.850805)
		(end 98.651953 132.871941)
		(width 0.1)
		(layer "In2.Cu")
		(net 190)
	)
	(segment
		(start 99.386762 132.930845)
		(end 99.406091 132.937609)
		(width 0.1)
		(layer "In2.Cu")
		(net 190)
	)
	(segment
		(start 98.74205 132.128553)
		(end 99.366411 132.128553)
		(width 0.1)
		(layer "In2.Cu")
		(net 190)
	)
	(segment
		(start 99.406091 132.719496)
		(end 99.386762 132.72626)
		(width 0.1)
		(layer "In2.Cu")
		(net 190)
	)
	(segment
		(start 98.663866 131.566204)
		(end 98.651953 131.585164)
		(width 0.1)
		(layer "In2.Cu")
		(net 190)
	)
	(segment
		(start 98.663866 132.366204)
		(end 98.651953 132.385164)
		(width 0.1)
		(layer "In2.Cu")
		(net 190)
	)
	(segment
		(start 99.406091 131.519496)
		(end 99.386762 131.52626)
		(width 0.1)
		(layer "In2.Cu")
		(net 190)
	)
	(segment
		(start 98.679701 131.950369)
		(end 98.663866 131.966204)
		(width 0.1)
		(layer "In2.Cu")
		(net 190)
	)
	(segment
		(start 99.386762 131.92626)
		(end 99.366411 131.928553)
		(width 0.1)
		(layer "In2.Cu")
		(net 190)
	)
	(segment
		(start 99.423432 133.1086)
		(end 99.406091 133.119496)
		(width 0.1)
		(layer "In2.Cu")
		(net 190)
	)
	(segment
		(start 99.423432 131.9086)
		(end 99.406091 131.919496)
		(width 0.1)
		(layer "In2.Cu")
		(net 190)
	)
	(segment
		(start 99.366411 132.328553)
		(end 98.74205 132.328553)
		(width 0.1)
		(layer "In2.Cu")
		(net 190)
	)
	(segment
		(start 99.218345 131.118649)
		(end 99.197209 131.126045)
		(width 0.1)
		(layer "In2.Cu")
		(net 190)
	)
	(segment
		(start 98.64205 132.028553)
		(end 98.644557 132.050805)
		(width 0.1)
		(layer "In2.Cu")
		(net 190)
	)
	(segment
		(start 99.406091 131.737609)
		(end 99.423432 131.748505)
		(width 0.1)
		(layer "In2.Cu")
		(net 190)
	)
	(segment
		(start 98.679701 131.550369)
		(end 98.663866 131.566204)
		(width 0.1)
		(layer "In2.Cu")
		(net 190)
	)
	(segment
		(start 98.64205 132.428553)
		(end 98.644557 132.450805)
		(width 0.1)
		(layer "In2.Cu")
		(net 190)
	)
	(segment
		(start 99.386762 131.52626)
		(end 99.366411 131.528553)
		(width 0.1)
		(layer "In2.Cu")
		(net 190)
	)
	(segment
		(start 99.366411 131.528553)
		(end 98.74205 131.528553)
		(width 0.1)
		(layer "In2.Cu")
		(net 190)
	)
	(segment
		(start 99.437912 133.09412)
		(end 99.423432 133.1086)
		(width 0.1)
		(layer "In2.Cu")
		(net 190)
	)
	(segment
		(start 98.651953 132.071941)
		(end 98.663866 132.090901)
		(width 0.1)
		(layer "In2.Cu")
		(net 190)
	)
	(segment
		(start 98.719797 131.53106)
		(end 98.698661 131.538456)
		(width 0.1)
		(layer "In2.Cu")
		(net 190)
	)
	(segment
		(start 99.455572 131.45745)
		(end 99.448808 131.476779)
		(width 0.1)
		(layer "In2.Cu")
		(net 190)
	)
	(segment
		(start 98.698661 131.138456)
		(end 98.679701 131.150369)
		(width 0.1)
		(layer "In2.Cu")
		(net 190)
	)
	(segment
		(start 99.272449 133.4063)
		(end 99.274957 133.428553)
		(width 0.1)
		(layer "In2.Cu")
		(net 190)
	)
	(segment
		(start 99.448808 132.980326)
		(end 99.455572 132.999655)
		(width 0.1)
		(layer "In2.Cu")
		(net 190)
	)
	(segment
		(start 99.455572 132.65745)
		(end 99.448808 132.676779)
		(width 0.1)
		(layer "In2.Cu")
		(net 190)
	)
	(segment
		(start 99.457864 132.6371)
		(end 99.455572 132.65745)
		(width 0.1)
		(layer "In2.Cu")
		(net 190)
	)
	(segment
		(start 98.679701 133.150369)
		(end 98.663866 133.166204)
		(width 0.1)
		(layer "In2.Cu")
		(net 190)
	)
	(segment
		(start 99.25314 131.090901)
		(end 99.237305 131.106736)
		(width 0.1)
		(layer "In2.Cu")
		(net 190)
	)
	(segment
		(start 99.197209 133.33106)
		(end 99.218345 133.338456)
		(width 0.1)
		(layer "In2.Cu")
		(net 190)
	)
	(segment
		(start 99.455572 132.199655)
		(end 99.457864 132.220006)
		(width 0.1)
		(layer "In2.Cu")
		(net 190)
	)
	(segment
		(start 98.719797 132.526045)
		(end 98.74205 132.528553)
		(width 0.1)
		(layer "In2.Cu")
		(net 190)
	)
	(segment
		(start 99.274957 133.428553)
		(end 99.274957 142.275043)
		(width 0.1)
		(layer "In2.Cu")
		(net 190)
	)
	(segment
		(start 98.698661 132.918649)
		(end 98.719797 132.926045)
		(width 0.1)
		(layer "In2.Cu")
		(net 190)
	)
	(segment
		(start 99.455572 132.25745)
		(end 99.448808 132.276779)
		(width 0.1)
		(layer "In2.Cu")
		(net 190)
	)
	(segment
		(start 98.719797 132.926045)
		(end 98.74205 132.928553)
		(width 0.1)
		(layer "In2.Cu")
		(net 190)
	)
	(segment
		(start 98.679701 132.750369)
		(end 98.663866 132.766204)
		(width 0.1)
		(layer "In2.Cu")
		(net 190)
	)
	(segment
		(start 99.386762 132.530845)
		(end 99.406091 132.537609)
		(width 0.1)
		(layer "In2.Cu")
		(net 190)
	)
	(segment
		(start 99.366411 133.128553)
		(end 98.74205 133.128553)
		(width 0.1)
		(layer "In2.Cu")
		(net 190)
	)
	(segment
		(start 99.457864 131.4371)
		(end 99.455572 131.45745)
		(width 0.1)
		(layer "In2.Cu")
		(net 190)
	)
	(segment
		(start 98.719797 131.326045)
		(end 98.74205 131.328553)
		(width 0.1)
		(layer "In2.Cu")
		(net 190)
	)
	(segment
		(start 98.74205 131.328553)
		(end 99.366411 131.328553)
		(width 0.1)
		(layer "In2.Cu")
		(net 190)
	)
	(segment
		(start 98.719797 131.13106)
		(end 98.698661 131.138456)
		(width 0.1)
		(layer "In2.Cu")
		(net 190)
	)
	(segment
		(start 99.423432 131.348505)
		(end 99.437912 131.362985)
		(width 0.1)
		(layer "In2.Cu")
		(net 190)
	)
	(segment
		(start 98.663866 131.290901)
		(end 98.679701 131.306736)
		(width 0.1)
		(layer "In2.Cu")
		(net 190)
	)
	(segment
		(start 99.437912 132.562985)
		(end 99.448808 132.580326)
		(width 0.1)
		(layer "In2.Cu")
		(net 190)
	)
	(segment
		(start 99.386762 131.330845)
		(end 99.406091 131.337609)
		(width 0.1)
		(layer "In2.Cu")
		(net 190)
	)
	(segment
		(start 99.406091 132.137609)
		(end 99.423432 132.148505)
		(width 0.1)
		(layer "In2.Cu")
		(net 190)
	)
	(segment
		(start 99.437912 132.162985)
		(end 99.448808 132.180326)
		(width 0.1)
		(layer "In2.Cu")
		(net 190)
	)
	(segment
		(start 99.406091 131.337609)
		(end 99.423432 131.348505)
		(width 0.1)
		(layer "In2.Cu")
		(net 190)
	)
	(segment
		(start 98.644557 131.250805)
		(end 98.651953 131.271941)
		(width 0.1)
		(layer "In2.Cu")
		(net 190)
	)
	(segment
		(start 98.698661 132.738456)
		(end 98.679701 132.750369)
		(width 0.1)
		(layer "In2.Cu")
		(net 190)
	)
	(segment
		(start 98.698661 131.538456)
		(end 98.679701 131.550369)
		(width 0.1)
		(layer "In2.Cu")
		(net 190)
	)
	(segment
		(start 98.679701 133.306736)
		(end 98.698661 133.318649)
		(width 0.1)
		(layer "In2.Cu")
		(net 190)
	)
	(segment
		(start 98.644557 132.0063)
		(end 98.64205 132.028553)
		(width 0.1)
		(layer "In2.Cu")
		(net 190)
	)
	(segment
		(start 99.237305 133.350369)
		(end 99.25314 133.366204)
		(width 0.1)
		(layer "In2.Cu")
		(net 190)
	)
	(segment
		(start 99.272449 131.050805)
		(end 99.265053 131.071941)
		(width 0.1)
		(layer "In2.Cu")
		(net 190)
	)
	(segment
		(start 99.423432 131.748505)
		(end 99.437912 131.762985)
		(width 0.1)
		(layer "In2.Cu")
		(net 190)
	)
	(segment
		(start 98.651953 131.585164)
		(end 98.644557 131.6063)
		(width 0.1)
		(layer "In2.Cu")
		(net 190)
	)
	(segment
		(start 99.437912 132.962985)
		(end 99.448808 132.980326)
		(width 0.1)
		(layer "In2.Cu")
		(net 190)
	)
	(segment
		(start 98.663866 133.290901)
		(end 98.679701 133.306736)
		(width 0.1)
		(layer "In2.Cu")
		(net 190)
	)
	(segment
		(start 98.698661 131.318649)
		(end 98.719797 131.326045)
		(width 0.1)
		(layer "In2.Cu")
		(net 190)
	)
	(segment
		(start 99.406091 131.919496)
		(end 99.386762 131.92626)
		(width 0.1)
		(layer "In2.Cu")
		(net 190)
	)
	(segment
		(start 98.698661 133.318649)
		(end 98.719797 133.326045)
		(width 0.1)
		(layer "In2.Cu")
		(net 190)
	)
	(segment
		(start 99.366411 132.128553)
		(end 99.386762 132.130845)
		(width 0.1)
		(layer "In2.Cu")
		(net 190)
	)
	(segment
		(start 98.698661 131.718649)
		(end 98.719797 131.726045)
		(width 0.1)
		(layer "In2.Cu")
		(net 190)
	)
	(segment
		(start 99.448808 133.076779)
		(end 99.437912 133.09412)
		(width 0.1)
		(layer "In2.Cu")
		(net 190)
	)
	(segment
		(start 98.74205 131.928553)
		(end 98.719797 131.93106)
		(width 0.1)
		(layer "In2.Cu")
		(net 190)
	)
	(segment
		(start 98.651953 133.185164)
		(end 98.644557 133.2063)
		(width 0.1)
		(layer "In2.Cu")
		(net 190)
	)
	(segment
		(start 98.651953 131.671941)
		(end 98.663866 131.690901)
		(width 0.1)
		(layer "In2.Cu")
		(net 190)
	)
	(segment
		(start 98.663866 132.890901)
		(end 98.679701 132.906736)
		(width 0.1)
		(layer "In2.Cu")
		(net 190)
	)
	(segment
		(start 99.423432 131.5086)
		(end 99.406091 131.519496)
		(width 0.1)
		(layer "In2.Cu")
		(net 190)
	)
	(segment
		(start 98.719797 132.33106)
		(end 98.698661 132.338456)
		(width 0.1)
		(layer "In2.Cu")
		(net 190)
	)
	(segment
		(start 98.644557 131.6063)
		(end 98.64205 131.628553)
		(width 0.1)
		(layer "In2.Cu")
		(net 190)
	)
	(segment
		(start 99.406091 132.537609)
		(end 99.423432 132.548505)
		(width 0.1)
		(layer "In2.Cu")
		(net 190)
	)
	(segment
		(start 98.644557 132.450805)
		(end 98.651953 132.471941)
		(width 0.1)
		(layer "In2.Cu")
		(net 190)
	)
	(segment
		(start 99.437912 131.762985)
		(end 99.448808 131.780326)
		(width 0.1)
		(layer "In2.Cu")
		(net 190)
	)
	(segment
		(start 98.644557 131.2063)
		(end 98.64205 131.228553)
		(width 0.1)
		(layer "In2.Cu")
		(net 190)
	)
	(segment
		(start 98.651953 131.185164)
		(end 98.644557 131.2063)
		(width 0.1)
		(layer "In2.Cu")
		(net 190)
	)
	(segment
		(start 99.448808 132.580326)
		(end 99.455572 132.599655)
		(width 0.1)
		(layer "In2.Cu")
		(net 190)
	)
	(segment
		(start 98.651953 132.385164)
		(end 98.644557 132.4063)
		(width 0.1)
		(layer "In2.Cu")
		(net 190)
	)
	(segment
		(start 99.366411 131.728553)
		(end 99.386762 131.730845)
		(width 0.1)
		(layer "In2.Cu")
		(net 190)
	)
	(segment
		(start 99.423432 132.548505)
		(end 99.437912 132.562985)
		(width 0.1)
		(layer "In2.Cu")
		(net 190)
	)
	(segment
		(start 99.265053 133.385164)
		(end 99.272449 133.4063)
		(width 0.1)
		(layer "In2.Cu")
		(net 190)
	)
	(segment
		(start 99.455572 131.799655)
		(end 99.457864 131.820006)
		(width 0.1)
		(layer "In2.Cu")
		(net 190)
	)
	(segment
		(start 98.663866 132.090901)
		(end 98.679701 132.106736)
		(width 0.1)
		(layer "In2.Cu")
		(net 190)
	)
	(segment
		(start 98.644557 132.8063)
		(end 98.64205 132.828553)
		(width 0.1)
		(layer "In2.Cu")
		(net 190)
	)
	(segment
		(start 99.437912 131.362985)
		(end 99.448808 131.380326)
		(width 0.1)
		(layer "In2.Cu")
		(net 190)
	)
	(segment
		(start 98.698661 133.138456)
		(end 98.679701 133.150369)
		(width 0.1)
		(layer "In2.Cu")
		(net 190)
	)
	(segment
		(start 98.719797 132.126045)
		(end 98.74205 132.128553)
		(width 0.1)
		(layer "In2.Cu")
		(net 190)
	)
	(segment
		(start 99.448808 131.876779)
		(end 99.437912 131.89412)
		(width 0.1)
		(layer "In2.Cu")
		(net 190)
	)
	(segment
		(start 98.679701 132.906736)
		(end 98.698661 132.918649)
		(width 0.1)
		(layer "In2.Cu")
		(net 190)
	)
	(segment
		(start 99.386762 132.130845)
		(end 99.406091 132.137609)
		(width 0.1)
		(layer "In2.Cu")
		(net 190)
	)
	(segment
		(start 98.651953 132.471941)
		(end 98.663866 132.490901)
		(width 0.1)
		(layer "In2.Cu")
		(net 190)
	)
	(segment
		(start 99.457864 132.2371)
		(end 99.455572 132.25745)
		(width 0.1)
		(layer "In2.Cu")
		(net 190)
	)
	(segment
		(start 98.679701 131.150369)
		(end 98.663866 131.166204)
		(width 0.1)
		(layer "In2.Cu")
		(net 190)
	)
	(segment
		(start 98.679701 131.706736)
		(end 98.698661 131.718649)
		(width 0.1)
		(layer "In2.Cu")
		(net 190)
	)
	(segment
		(start 98.644557 132.050805)
		(end 98.651953 132.071941)
		(width 0.1)
		(layer "In2.Cu")
		(net 190)
	)
	(segment
		(start 98.698661 132.518649)
		(end 98.719797 132.526045)
		(width 0.1)
		(layer "In2.Cu")
		(net 190)
	)
	(segment
		(start 99.455572 132.999655)
		(end 99.457864 133.020006)
		(width 0.1)
		(layer "In2.Cu")
		(net 190)
	)
	(segment
		(start 99.406091 132.937609)
		(end 99.423432 132.948505)
		(width 0.1)
		(layer "In2.Cu")
		(net 190)
	)
	(segment
		(start 99.265053 131.071941)
		(end 99.25314 131.090901)
		(width 0.1)
		(layer "In2.Cu")
		(net 190)
	)
	(segment
		(start 98.679701 132.506736)
		(end 98.698661 132.518649)
		(width 0.1)
		(layer "In2.Cu")
		(net 190)
	)
	(segment
		(start 99.448808 131.380326)
		(end 99.455572 131.399655)
		(width 0.1)
		(layer "In2.Cu")
		(net 190)
	)
	(segment
		(start 98.74205 132.928553)
		(end 99.366411 132.928553)
		(width 0.1)
		(layer "In2.Cu")
		(net 190)
	)
	(segment
		(start 99.437912 131.49412)
		(end 99.423432 131.5086)
		(width 0.1)
		(layer "In2.Cu")
		(net 190)
	)
	(segment
		(start 98.698661 131.938456)
		(end 98.679701 131.950369)
		(width 0.1)
		(layer "In2.Cu")
		(net 190)
	)
	(segment
		(start 98.64205 131.628553)
		(end 98.644557 131.650805)
		(width 0.1)
		(layer "In2.Cu")
		(net 190)
	)
	(segment
		(start 99.457864 131.8371)
		(end 99.455572 131.85745)
		(width 0.1)
		(layer "In2.Cu")
		(net 190)
	)
	(segment
		(start 99.437912 132.69412)
		(end 99.423432 132.7086)
		(width 0.1)
		(layer "In2.Cu")
		(net 190)
	)
	(segment
		(start 98.719797 133.326045)
		(end 98.74205 133.328553)
		(width 0.1)
		(layer "In2.Cu")
		(net 190)
	)
	(segment
		(start 99.274957 142.275043)
		(end 98.775 142.775)
		(width 0.1)
		(layer "In2.Cu")
		(net 190)
	)
	(segment
		(start 99.218345 133.338456)
		(end 99.237305 133.350369)
		(width 0.1)
		(layer "In2.Cu")
		(net 190)
	)
	(segment
		(start 98.679701 132.106736)
		(end 98.698661 132.118649)
		(width 0.1)
		(layer "In2.Cu")
		(net 190)
	)
	(segment
		(start 99.25314 133.366204)
		(end 99.265053 133.385164)
		(width 0.1)
		(layer "In2.Cu")
		(net 190)
	)
	(segment
		(start 99.406091 133.119496)
		(end 99.386762 133.12626)
		(width 0.1)
		(layer "In2.Cu")
		(net 190)
	)
	(segment
		(start 98.719797 133.13106)
		(end 98.698661 133.138456)
		(width 0.1)
		(layer "In2.Cu")
		(net 190)
	)
	(segment
		(start 99.386762 133.12626)
		(end 99.366411 133.128553)
		(width 0.1)
		(layer "In2.Cu")
		(net 190)
	)
	(segment
		(start 98.74205 131.528553)
		(end 98.719797 131.53106)
		(width 0.1)
		(layer "In2.Cu")
		(net 190)
	)
	(segment
		(start 99.274957 131.028553)
		(end 99.272449 131.050805)
		(width 0.1)
		(layer "In2.Cu")
		(net 190)
	)
	(segment
		(start 99.437912 131.89412)
		(end 99.423432 131.9086)
		(width 0.1)
		(layer "In2.Cu")
		(net 190)
	)
	(segment
		(start 99.366411 132.528553)
		(end 99.386762 132.530845)
		(width 0.1)
		(layer "In2.Cu")
		(net 190)
	)
	(segment
		(start 98.64205 133.228553)
		(end 98.644557 133.250805)
		(width 0.1)
		(layer "In2.Cu")
		(net 190)
	)
	(segment
		(start 98.719797 131.726045)
		(end 98.74205 131.728553)
		(width 0.1)
		(layer "In2.Cu")
		(net 190)
	)
	(segment
		(start 98.74205 131.128553)
		(end 98.719797 131.13106)
		(width 0.1)
		(layer "In2.Cu")
		(net 190)
	)
	(segment
		(start 98.644557 133.2063)
		(end 98.64205 133.228553)
		(width 0.1)
		(layer "In2.Cu")
		(net 190)
	)
	(segment
		(start 98.74205 133.128553)
		(end 98.719797 133.13106)
		(width 0.1)
		(layer "In2.Cu")
		(net 190)
	)
	(segment
		(start 98.679701 132.350369)
		(end 98.663866 132.366204)
		(width 0.1)
		(layer "In2.Cu")
		(net 190)
	)
	(segment
		(start 99.455572 131.85745)
		(end 99.448808 131.876779)
		(width 0.1)
		(layer "In2.Cu")
		(net 190)
	)
	(segment
		(start 98.663866 132.766204)
		(end 98.651953 132.785164)
		(width 0.1)
		(layer "In2.Cu")
		(net 190)
	)
	(segment
		(start 96.775 131.475)
		(end 97.325 132.025)
		(width 0.1)
		(layer "F.Cu")
		(net 191)
	)
	(segment
		(start 104.457842 149.575)
		(end 105.074 150.191158)
		(width 0.15)
		(layer "F.Cu")
		(net 191)
	)
	(segment
		(start 104.175 149.575)
		(end 104.457842 149.575)
		(width 0.15)
		(layer "F.Cu")
		(net 191)
	)
	(segment
		(start 105.074 150.191158)
		(end 105.074 151.475)
		(width 0.15)
		(layer "F.Cu")
		(net 191)
	)
	(segment
		(start 105.074 154.19)
		(end 105.074 151.475)
		(width 0.15)
		(layer "F.Cu")
		(net 191)
	)
	(segment
		(start 103.22501 132.025)
		(end 103.77501 131.475)
		(width 0.1)
		(layer "F.Cu")
		(net 191)
	)
	(segment
		(start 96.775 130.175)
		(end 96.775 131.475)
		(width 0.1)
		(layer "F.Cu")
		(net 191)
	)
	(segment
		(start 97.325 132.025)
		(end 103.22501 132.025)
		(width 0.1)
		(layer "F.Cu")
		(net 191)
	)
	(via blind
		(at 103.77501 131.475)
		(size 0.5)
		(drill 0.2)
		(layers "F.Cu" "In5.Cu")
		(net 191)
	)
	(via
		(at 105.074 151.475)
		(size 0.5)
		(drill 0.2)
		(layers "F.Cu" "B.Cu")
		(net 191)
	)
	(segment
		(start 105.074 147.974)
		(end 104.175 147.075)
		(width 0.1)
		(layer "In5.Cu")
		(net 191)
	)
	(segment
		(start 104.175001 145.173999)
		(end 104.175001 142.075001)
		(width 0.1)
		(layer "In5.Cu")
		(net 191)
	)
	(segment
		(start 105.074 151.475)
		(end 105.074 147.974)
		(width 0.1)
		(layer "In5.Cu")
		(net 191)
	)
	(segment
		(start 104.175001 142.075001)
		(end 103.77501 141.67501)
		(width 0.1)
		(layer "In5.Cu")
		(net 191)
	)
	(segment
		(start 103.77501 141.67501)
		(end 103.77501 131.475)
		(width 0.1)
		(layer "In5.Cu")
		(net 191)
	)
	(segment
		(start 104.175 147.075)
		(end 104.174 145.175)
		(width 0.1)
		(layer "In5.Cu")
		(net 191)
	)
	(segment
		(start 104.174 145.175)
		(end 104.175001 145.173999)
		(width 0.1)
		(layer "In5.Cu")
		(net 191)
	)
	(segment
		(start 97.37501 129.57499)
		(end 97.37501 129.675)
		(width 0.15)
		(layer "F.Cu")
		(net 192)
	)
	(segment
		(start 96.975 149.575)
		(end 97.375 149.175)
		(width 0.1)
		(layer "F.Cu")
		(net 192)
	)
	(segment
		(start 97.775 129.175)
		(end 97.37501 129.57499)
		(width 0.15)
		(layer "F.Cu")
		(net 192)
	)
	(via blind
		(at 97.375 149.175)
		(size 0.5)
		(drill 0.2)
		(layers "F.Cu" "In2.Cu")
		(net 192)
	)
	(via blind
		(at 97.37501 129.675)
		(size 0.5)
		(drill 0.2)
		(layers "F.Cu" "In2.Cu")
		(net 192)
	)
	(segment
		(start 97.377518 132.752737)
		(end 97.37501 132.77499)
		(width 0.1)
		(layer "In2.Cu")
		(net 192)
	)
	(segment
		(start 97.589106 131.837338)
		(end 97.573271 131.853173)
		(width 0.1)
		(layer "In2.Cu")
		(net 192)
	)
	(segment
		(start 97.209378 130.709988)
		(end 97.198303 130.727613)
		(width 0.1)
		(layer "In2.Cu")
		(net 192)
	)
	(segment
		(start 97.198303 130.727613)
		(end 97.191428 130.747261)
		(width 0.1)
		(layer "In2.Cu")
		(net 192)
	)
	(segment
		(start 97.282054 132.07499)
		(end 97.510922 132.07499)
		(width 0.1)
		(layer "In2.Cu")
		(net 192)
	)
	(segment
		(start 97.775001 143.075001)
		(end 97.775001 145.374999)
		(width 0.1)
		(layer "In2.Cu")
		(net 192)
	)
	(segment
		(start 97.37501 130.47499)
		(end 97.510922 130.47499)
		(width 0.1)
		(layer "In2.Cu")
		(net 192)
	)
	(segment
		(start 97.198303 132.022366)
		(end 97.209378 132.039991)
		(width 0.1)
		(layer "In2.Cu")
		(net 192)
	)
	(segment
		(start 97.589106 131.312641)
		(end 97.601019 131.331601)
		(width 0.1)
		(layer "In2.Cu")
		(net 192)
	)
	(segment
		(start 97.189098 130.360902)
		(end 97.189098 130.37499)
		(width 0.1)
		(layer "In2.Cu")
		(net 192)
	)
	(segment
		(start 97.224096 131.89527)
		(end 97.209378 131.909988)
		(width 0.1)
		(layer "In2.Cu")
		(net 192)
	)
	(segment
		(start 97.322386 130.25874)
		(end 97.302738 130.265615)
		(width 0.1)
		(layer "In2.Cu")
		(net 192)
	)
	(segment
		(start 97.37501 130.17499)
		(end 97.372679 130.195674)
		(width 0.1)
		(layer "In2.Cu")
		(net 192)
	)
	(segment
		(start 97.533175 131.277497)
		(end 97.554311 131.284893)
		(width 0.1)
		(layer "In2.Cu")
		(net 192)
	)
	(segment
		(start 97.608415 132.152737)
		(end 97.610922 132.17499)
		(width 0.1)
		(layer "In2.Cu")
		(net 192)
	)
	(segment
		(start 97.241721 131.484195)
		(end 97.224096 131.49527)
		(width 0.1)
		(layer "In2.Cu")
		(net 192)
	)
	(segment
		(start 97.198303 132.327613)
		(end 97.191428 132.347261)
		(width 0.1)
		(layer "In2.Cu")
		(net 192)
	)
	(segment
		(start 97.224096 132.454709)
		(end 97.241721 132.465784)
		(width 0.1)
		(layer "In2.Cu")
		(net 192)
	)
	(segment
		(start 97.282054 131.47499)
		(end 97.261369 131.47732)
		(width 0.1)
		(layer "In2.Cu")
		(net 192)
	)
	(segment
		(start 97.610922 130.97499)
		(end 97.608415 130.997242)
		(width 0.1)
		(layer "In2.Cu")
		(net 192)
	)
	(segment
		(start 97.261369 130.465615)
		(end 97.282054 130.467946)
		(width 0.1)
		(layer "In2.Cu")
		(net 192)
	)
	(segment
		(start 97.610922 132.57499)
		(end 97.608415 132.597242)
		(width 0.1)
		(layer "In2.Cu")
		(net 192)
	)
	(segment
		(start 97.37501 130.467946)
		(end 97.37501 130.47499)
		(width 0.1)
		(layer "In2.Cu")
		(net 192)
	)
	(segment
		(start 97.554311 132.665086)
		(end 97.533175 132.672482)
		(width 0.1)
		(layer "In2.Cu")
		(net 192)
	)
	(segment
		(start 97.189098 130.767946)
		(end 97.189098 130.782034)
		(width 0.1)
		(layer "In2.Cu")
		(net 192)
	)
	(segment
		(start 97.198303 131.622366)
		(end 97.209378 131.639991)
		(width 0.1)
		(layer "In2.Cu")
		(net 192)
	)
	(segment
		(start 97.608415 131.397242)
		(end 97.601019 131.418378)
		(width 0.1)
		(layer "In2.Cu")
		(net 192)
	)
	(segment
		(start 97.573271 130.896806)
		(end 97.589106 130.912641)
		(width 0.1)
		(layer "In2.Cu")
		(net 192)
	)
	(segment
		(start 97.37501 142.67501)
		(end 97.775001 143.075001)
		(width 0.1)
		(layer "In2.Cu")
		(net 192)
	)
	(segment
		(start 97.241721 132.465784)
		(end 97.261369 132.472659)
		(width 0.1)
		(layer "In2.Cu")
		(net 192)
	)
	(segment
		(start 97.241721 132.284195)
		(end 97.224096 132.29527)
		(width 0.1)
		(layer "In2.Cu")
		(net 192)
	)
	(segment
		(start 97.209378 132.309988)
		(end 97.198303 132.327613)
		(width 0.1)
		(layer "In2.Cu")
		(net 192)
	)
	(segment
		(start 97.610922 132.17499)
		(end 97.608415 132.197242)
		(width 0.1)
		(layer "In2.Cu")
		(net 192)
	)
	(segment
		(start 97.241721 131.665784)
		(end 97.261369 131.672659)
		(width 0.1)
		(layer "In2.Cu")
		(net 192)
	)
	(segment
		(start 97.191428 131.547261)
		(end 97.189098 131.567946)
		(width 0.1)
		(layer "In2.Cu")
		(net 192)
	)
	(segment
		(start 97.573271 132.496806)
		(end 97.589106 132.512641)
		(width 0.1)
		(layer "In2.Cu")
		(net 192)
	)
	(segment
		(start 97.209378 130.432947)
		(end 97.224096 130.447665)
		(width 0.1)
		(layer "In2.Cu")
		(net 192)
	)
	(segment
		(start 97.589106 132.237338)
		(end 97.573271 132.253173)
		(width 0.1)
		(layer "In2.Cu")
		(net 192)
	)
	(segment
		(start 97.610922 131.37499)
		(end 97.608415 131.397242)
		(width 0.1)
		(layer "In2.Cu")
		(net 192)
	)
	(segment
		(start 97.510922 130.87499)
		(end 97.533175 130.877497)
		(width 0.1)
		(layer "In2.Cu")
		(net 192)
	)
	(segment
		(start 97.209378 130.302944)
		(end 97.198303 130.320569)
		(width 0.1)
		(layer "In2.Cu")
		(net 192)
	)
	(segment
		(start 97.241721 131.265784)
		(end 97.261369 131.272659)
		(width 0.1)
		(layer "In2.Cu")
		(net 192)
	)
	(segment
		(start 97.554311 132.084893)
		(end 97.573271 132.096806)
		(width 0.1)
		(layer "In2.Cu")
		(net 192)
	)
	(segment
		(start 97.573271 131.053173)
		(end 97.554311 131.065086)
		(width 0.1)
		(layer "In2.Cu")
		(net 192)
	)
	(segment
		(start 97.601019 131.731601)
		(end 97.608415 131.752737)
		(width 0.1)
		(layer "In2.Cu")
		(net 192)
	)
	(segment
		(start 97.573271 132.653173)
		(end 97.554311 132.665086)
		(width 0.1)
		(layer "In2.Cu")
		(net 192)
	)
	(segment
		(start 97.533175 130.672482)
		(end 97.510922 130.67499)
		(width 0.1)
		(layer "In2.Cu")
		(net 192)
	)
	(segment
		(start 97.510922 131.87499)
		(end 97.282054 131.87499)
		(width 0.1)
		(layer "In2.Cu")
		(net 192)
	)
	(segment
		(start 97.189098 131.167946)
		(end 97.189098 131.182034)
		(width 0.1)
		(layer "In2.Cu")
		(net 192)
	)
	(segment
		(start 97.601019 132.618378)
		(end 97.589106 132.637338)
		(width 0.1)
		(layer "In2.Cu")
		(net 192)
	)
	(segment
		(start 97.198303 131.927613)
		(end 97.191428 131.947261)
		(width 0.1)
		(layer "In2.Cu")
		(net 192)
	)
	(segment
		(start 97.412662 132.696806)
		(end 97.396827 132.712641)
		(width 0.1)
		(layer "In2.Cu")
		(net 192)
	)
	(segment
		(start 97.554311 132.265086)
		(end 97.533175 132.272482)
		(width 0.1)
		(layer "In2.Cu")
		(net 192)
	)
	(segment
		(start 97.601019 132.131601)
		(end 97.608415 132.152737)
		(width 0.1)
		(layer "In2.Cu")
		(net 192)
	)
	(segment
		(start 97.224096 130.447665)
		(end 97.241721 130.45874)
		(width 0.1)
		(layer "In2.Cu")
		(net 192)
	)
	(segment
		(start 97.608415 131.797242)
		(end 97.601019 131.818378)
		(width 0.1)
		(layer "In2.Cu")
		(net 192)
	)
	(segment
		(start 97.589106 130.637338)
		(end 97.573271 130.653173)
		(width 0.1)
		(layer "In2.Cu")
		(net 192)
	)
	(segment
		(start 97.282054 131.27499)
		(end 97.510922 131.27499)
		(width 0.1)
		(layer "In2.Cu")
		(net 192)
	)
	(segment
		(start 97.224096 131.09527)
		(end 97.209378 131.109988)
		(width 0.1)
		(layer "In2.Cu")
		(net 192)
	)
	(segment
		(start 97.601019 131.018378)
		(end 97.589106 131.037338)
		(width 0.1)
		(layer "In2.Cu")
		(net 192)
	)
	(segment
		(start 97.601019 132.218378)
		(end 97.589106 132.237338)
		(width 0.1)
		(layer "In2.Cu")
		(net 192)
	)
	(segment
		(start 97.191428 131.202718)
		(end 97.198303 131.222366)
		(width 0.1)
		(layer "In2.Cu")
		(net 192)
	)
	(segment
		(start 97.261369 131.47732)
		(end 97.241721 131.484195)
		(width 0.1)
		(layer "In2.Cu")
		(net 192)
	)
	(segment
		(start 97.375 145.775)
		(end 97.375 149.175)
		(width 0.1)
		(layer "In2.Cu")
		(net 192)
	)
	(segment
		(start 97.224096 132.054709)
		(end 97.241721 132.065784)
		(width 0.1)
		(layer "In2.Cu")
		(net 192)
	)
	(segment
		(start 97.191428 132.402718)
		(end 97.198303 132.422366)
		(width 0.1)
		(layer "In2.Cu")
		(net 192)
	)
	(segment
		(start 97.554311 131.865086)
		(end 97.533175 131.872482)
		(width 0.1)
		(layer "In2.Cu")
		(net 192)
	)
	(segment
		(start 97.261369 131.272659)
		(end 97.282054 131.27499)
		(width 0.1)
		(layer "In2.Cu")
		(net 192)
	)
	(segment
		(start 97.224096 131.49527)
		(end 97.209378 131.509988)
		(width 0.1)
		(layer "In2.Cu")
		(net 192)
	)
	(segment
		(start 97.608415 132.552737)
		(end 97.610922 132.57499)
		(width 0.1)
		(layer "In2.Cu")
		(net 192)
	)
	(segment
		(start 97.198303 130.320569)
		(end 97.191428 130.340217)
		(width 0.1)
		(layer "In2.Cu")
		(net 192)
	)
	(segment
		(start 97.510922 132.07499)
		(end 97.533175 132.077497)
		(width 0.1)
		(layer "In2.Cu")
		(net 192)
	)
	(segment
		(start 97.198303 131.127613)
		(end 97.191428 131.147261)
		(width 0.1)
		(layer "In2.Cu")
		(net 192)
	)
	(segment
		(start 97.554311 130.884893)
		(end 97.573271 130.896806)
		(width 0.1)
		(layer "In2.Cu")
		(net 192)
	)
	(segment
		(start 97.261369 131.87732)
		(end 97.241721 131.884195)
		(width 0.1)
		(layer "In2.Cu")
		(net 192)
	)
	(segment
		(start 97.589106 132.112641)
		(end 97.601019 132.131601)
		(width 0.1)
		(layer "In2.Cu")
		(net 192)
	)
	(segment
		(start 97.261369 132.27732)
		(end 97.241721 132.284195)
		(width 0.1)
		(layer "In2.Cu")
		(net 192)
	)
	(segment
		(start 97.573271 131.453173)
		(end 97.554311 131.465086)
		(width 0.1)
		(layer "In2.Cu")
		(net 192)
	)
	(segment
		(start 97.601019 131.418378)
		(end 97.589106 131.437338)
		(width 0.1)
		(layer "In2.Cu")
		(net 192)
	)
	(segment
		(start 97.261369 130.67732)
		(end 97.241721 130.684195)
		(width 0.1)
		(layer "In2.Cu")
		(net 192)
	)
	(segment
		(start 97.189098 132.382034)
		(end 97.191428 132.402718)
		(width 0.1)
		(layer "In2.Cu")
		(net 192)
	)
	(segment
		(start 97.282054 132.27499)
		(end 97.261369 132.27732)
		(width 0.1)
		(layer "In2.Cu")
		(net 192)
	)
	(segment
		(start 97.601019 130.931601)
		(end 97.608415 130.952737)
		(width 0.1)
		(layer "In2.Cu")
		(net 192)
	)
	(segment
		(start 97.282054 131.07499)
		(end 97.261369 131.07732)
		(width 0.1)
		(layer "In2.Cu")
		(net 192)
	)
	(segment
		(start 97.37501 129.675)
		(end 97.37501 130.17499)
		(width 0.1)
		(layer "In2.Cu")
		(net 192)
	)
	(segment
		(start 97.589106 131.712641)
		(end 97.601019 131.731601)
		(width 0.1)
		(layer "In2.Cu")
		(net 192)
	)
	(segment
		(start 97.282054 131.87499)
		(end 97.261369 131.87732)
		(width 0.1)
		(layer "In2.Cu")
		(net 192)
	)
	(segment
		(start 97.241721 130.277151)
		(end 97.224096 130.288226)
		(width 0.1)
		(layer "In2.Cu")
		(net 192)
	)
	(segment
		(start 97.224096 131.254709)
		(end 97.241721 131.265784)
		(width 0.1)
		(layer "In2.Cu")
		(net 192)
	)
	(segment
		(start 97.533175 132.077497)
		(end 97.554311 132.084893)
		(width 0.1)
		(layer "In2.Cu")
		(net 192)
	)
	(segment
		(start 97.198303 131.222366)
		(end 97.209378 131.239991)
		(width 0.1)
		(layer "In2.Cu")
		(net 192)
	)
	(segment
		(start 97.608415 130.952737)
		(end 97.610922 130.97499)
		(width 0.1)
		(layer "In2.Cu")
		(net 192)
	)
	(segment
		(start 97.282054 130.67499)
		(end 97.261369 130.67732)
		(width 0.1)
		(layer "In2.Cu")
		(net 192)
	)
	(segment
		(start 97.554311 130.484893)
		(end 97.573271 130.496806)
		(width 0.1)
		(layer "In2.Cu")
		(net 192)
	)
	(segment
		(start 97.282054 131.67499)
		(end 97.510922 131.67499)
		(width 0.1)
		(layer "In2.Cu")
		(net 192)
	)
	(segment
		(start 97.589106 131.437338)
		(end 97.573271 131.453173)
		(width 0.1)
		(layer "In2.Cu")
		(net 192)
	)
	(segment
		(start 97.198303 130.415322)
		(end 97.209378 130.432947)
		(width 0.1)
		(layer "In2.Cu")
		(net 192)
	)
	(segment
		(start 97.191428 130.395674)
		(end 97.198303 130.415322)
		(width 0.1)
		(layer "In2.Cu")
		(net 192)
	)
	(segment
		(start 97.209378 131.509988)
		(end 97.198303 131.527613)
		(width 0.1)
		(layer "In2.Cu")
		(net 192)
	)
	(segment
		(start 97.510922 131.67499)
		(end 97.533175 131.677497)
		(width 0.1)
		(layer "In2.Cu")
		(net 192)
	)
	(segment
		(start 97.533175 131.677497)
		(end 97.554311 131.684893)
		(width 0.1)
		(layer "In2.Cu")
		(net 192)
	)
	(segment
		(start 97.608415 130.597242)
		(end 97.601019 130.618378)
		(width 0.1)
		(layer "In2.Cu")
		(net 192)
	)
	(segment
		(start 97.554311 131.465086)
		(end 97.533175 131.472482)
		(width 0.1)
		(layer "In2.Cu")
		(net 192)
	)
	(segment
		(start 97.354729 130.232947)
		(end 97.340011 130.247665)
		(width 0.1)
		(layer "In2.Cu")
		(net 192)
	)
	(segment
		(start 97.189098 131.582034)
		(end 97.191428 131.602718)
		(width 0.1)
		(layer "In2.Cu")
		(net 192)
	)
	(segment
		(start 97.533175 130.877497)
		(end 97.554311 130.884893)
		(width 0.1)
		(layer "In2.Cu")
		(net 192)
	)
	(segment
		(start 97.189098 131.982034)
		(end 97.191428 132.002718)
		(width 0.1)
		(layer "In2.Cu")
		(net 192)
	)
	(segment
		(start 97.261369 132.072659)
		(end 97.282054 132.07499)
		(width 0.1)
		(layer "In2.Cu")
		(net 192)
	)
	(segment
		(start 97.209378 132.439991)
		(end 97.224096 132.454709)
		(width 0.1)
		(layer "In2.Cu")
		(net 192)
	)
	(segment
		(start 97.191428 131.602718)
		(end 97.198303 131.622366)
		(width 0.1)
		(layer "In2.Cu")
		(net 192)
	)
	(segment
		(start 97.241721 131.884195)
		(end 97.224096 131.89527)
		(width 0.1)
		(layer "In2.Cu")
		(net 192)
	)
	(segment
		(start 97.533175 132.272482)
		(end 97.510922 132.27499)
		(width 0.1)
		(layer "In2.Cu")
		(net 192)
	)
	(segment
		(start 97.209378 132.039991)
		(end 97.224096 132.054709)
		(width 0.1)
		(layer "In2.Cu")
		(net 192)
	)
	(segment
		(start 97.554311 131.065086)
		(end 97.533175 131.072482)
		(width 0.1)
		(layer "In2.Cu")
		(net 192)
	)
	(segment
		(start 97.340011 130.247665)
		(end 97.322386 130.25874)
		(width 0.1)
		(layer "In2.Cu")
		(net 192)
	)
	(segment
		(start 97.533175 130.477497)
		(end 97.554311 130.484893)
		(width 0.1)
		(layer "In2.Cu")
		(net 192)
	)
	(segment
		(start 97.554311 131.684893)
		(end 97.573271 131.696806)
		(width 0.1)
		(layer "In2.Cu")
		(net 192)
	)
	(segment
		(start 97.241721 132.065784)
		(end 97.261369 132.072659)
		(width 0.1)
		(layer "In2.Cu")
		(net 192)
	)
	(segment
		(start 97.589106 132.637338)
		(end 97.573271 132.653173)
		(width 0.1)
		(layer "In2.Cu")
		(net 192)
	)
	(segment
		(start 97.589106 131.037338)
		(end 97.573271 131.053173)
		(width 0.1)
		(layer "In2.Cu")
		(net 192)
	)
	(segment
		(start 97.191428 131.147261)
		(end 97.189098 131.167946)
		(width 0.1)
		(layer "In2.Cu")
		(net 192)
	)
	(segment
		(start 97.191428 130.802718)
		(end 97.198303 130.822366)
		(width 0.1)
		(layer "In2.Cu")
		(net 192)
	)
	(segment
		(start 97.510922 132.27499)
		(end 97.282054 132.27499)
		(width 0.1)
		(layer "In2.Cu")
		(net 192)
	)
	(segment
		(start 97.601019 132.531601)
		(end 97.608415 132.552737)
		(width 0.1)
		(layer "In2.Cu")
		(net 192)
	)
	(segment
		(start 97.37501 132.77499)
		(end 97.37501 142.67501)
		(width 0.1)
		(layer "In2.Cu")
		(net 192)
	)
	(segment
		(start 97.191428 132.002718)
		(end 97.198303 132.022366)
		(width 0.1)
		(layer "In2.Cu")
		(net 192)
	)
	(segment
		(start 97.573271 131.296806)
		(end 97.589106 131.312641)
		(width 0.1)
		(layer "In2.Cu")
		(net 192)
	)
	(segment
		(start 97.365804 130.215322)
		(end 97.354729 130.232947)
		(width 0.1)
		(layer "In2.Cu")
		(net 192)
	)
	(segment
		(start 97.189098 131.567946)
		(end 97.189098 131.582034)
		(width 0.1)
		(layer "In2.Cu")
		(net 192)
	)
	(segment
		(start 97.189098 131.967946)
		(end 97.189098 131.982034)
		(width 0.1)
		(layer "In2.Cu")
		(net 192)
	)
	(segment
		(start 97.261369 131.672659)
		(end 97.282054 131.67499)
		(width 0.1)
		(layer "In2.Cu")
		(net 192)
	)
	(segment
		(start 97.510922 131.27499)
		(end 97.533175 131.277497)
		(width 0.1)
		(layer "In2.Cu")
		(net 192)
	)
	(segment
		(start 97.610922 131.77499)
		(end 97.608415 131.797242)
		(width 0.1)
		(layer "In2.Cu")
		(net 192)
	)
	(segment
		(start 97.241721 130.45874)
		(end 97.261369 130.465615)
		(width 0.1)
		(layer "In2.Cu")
		(net 192)
	)
	(segment
		(start 97.224096 130.288226)
		(end 97.209378 130.302944)
		(width 0.1)
		(layer "In2.Cu")
		(net 192)
	)
	(segment
		(start 97.189098 132.367946)
		(end 97.189098 132.382034)
		(width 0.1)
		(layer "In2.Cu")
		(net 192)
	)
	(segment
		(start 97.261369 132.472659)
		(end 97.282054 132.47499)
		(width 0.1)
		(layer "In2.Cu")
		(net 192)
	)
	(segment
		(start 97.533175 132.672482)
		(end 97.510922 132.67499)
		(width 0.1)
		(layer "In2.Cu")
		(net 192)
	)
	(segment
		(start 97.224096 132.29527)
		(end 97.209378 132.309988)
		(width 0.1)
		(layer "In2.Cu")
		(net 192)
	)
	(segment
		(start 97.198303 132.422366)
		(end 97.209378 132.439991)
		(width 0.1)
		(layer "In2.Cu")
		(net 192)
	)
	(segment
		(start 97.431622 132.684893)
		(end 97.412662 132.696806)
		(width 0.1)
		(layer "In2.Cu")
		(net 192)
	)
	(segment
		(start 97.573271 132.253173)
		(end 97.554311 132.265086)
		(width 0.1)
		(layer "In2.Cu")
		(net 192)
	)
	(segment
		(start 97.47501 132.67499)
		(end 97.452758 132.677497)
		(width 0.1)
		(layer "In2.Cu")
		(net 192)
	)
	(segment
		(start 97.533175 132.477497)
		(end 97.554311 132.484893)
		(width 0.1)
		(layer "In2.Cu")
		(net 192)
	)
	(segment
		(start 97.261369 130.872659)
		(end 97.282054 130.87499)
		(width 0.1)
		(layer "In2.Cu")
		(net 192)
	)
	(segment
		(start 97.573271 130.653173)
		(end 97.554311 130.665086)
		(width 0.1)
		(layer "In2.Cu")
		(net 192)
	)
	(segment
		(start 97.601019 130.531601)
		(end 97.608415 130.552737)
		(width 0.1)
		(layer "In2.Cu")
		(net 192)
	)
	(segment
		(start 97.282054 132.47499)
		(end 97.510922 132.47499)
		(width 0.1)
		(layer "In2.Cu")
		(net 192)
	)
	(segment
		(start 97.573271 130.496806)
		(end 97.589106 130.512641)
		(width 0.1)
		(layer "In2.Cu")
		(net 192)
	)
	(segment
		(start 97.224096 131.654709)
		(end 97.241721 131.665784)
		(width 0.1)
		(layer "In2.Cu")
		(net 192)
	)
	(segment
		(start 97.209378 131.239991)
		(end 97.224096 131.254709)
		(width 0.1)
		(layer "In2.Cu")
		(net 192)
	)
	(segment
		(start 97.608415 130.552737)
		(end 97.610922 130.57499)
		(width 0.1)
		(layer "In2.Cu")
		(net 192)
	)
	(segment
		(start 97.198303 131.527613)
		(end 97.191428 131.547261)
		(width 0.1)
		(layer "In2.Cu")
		(net 192)
	)
	(segment
		(start 97.533175 131.872482)
		(end 97.510922 131.87499)
		(width 0.1)
		(layer "In2.Cu")
		(net 192)
	)
	(segment
		(start 97.282054 130.87499)
		(end 97.510922 130.87499)
		(width 0.1)
		(layer "In2.Cu")
		(net 192)
	)
	(segment
		(start 97.601019 131.818378)
		(end 97.589106 131.837338)
		(width 0.1)
		(layer "In2.Cu")
		(net 192)
	)
	(segment
		(start 97.372679 130.195674)
		(end 97.365804 130.215322)
		(width 0.1)
		(layer "In2.Cu")
		(net 192)
	)
	(segment
		(start 97.589106 130.912641)
		(end 97.601019 130.931601)
		(width 0.1)
		(layer "In2.Cu")
		(net 192)
	)
	(segment
		(start 97.191428 130.747261)
		(end 97.189098 130.767946)
		(width 0.1)
		(layer "In2.Cu")
		(net 192)
	)
	(segment
		(start 97.241721 131.084195)
		(end 97.224096 131.09527)
		(width 0.1)
		(layer "In2.Cu")
		(net 192)
	)
	(segment
		(start 97.261369 130.270276)
		(end 97.241721 130.277151)
		(width 0.1)
		(layer "In2.Cu")
		(net 192)
	)
	(segment
		(start 97.510922 130.67499)
		(end 97.282054 130.67499)
		(width 0.1)
		(layer "In2.Cu")
		(net 192)
	)
	(segment
		(start 97.610922 130.57499)
		(end 97.608415 130.597242)
		(width 0.1)
		(layer "In2.Cu")
		(net 192)
	)
	(segment
		(start 97.589106 130.512641)
		(end 97.601019 130.531601)
		(width 0.1)
		(layer "In2.Cu")
		(net 192)
	)
	(segment
		(start 97.241721 130.684195)
		(end 97.224096 130.69527)
		(width 0.1)
		(layer "In2.Cu")
		(net 192)
	)
	(segment
		(start 97.510922 132.47499)
		(end 97.533175 132.477497)
		(width 0.1)
		(layer "In2.Cu")
		(net 192)
	)
	(segment
		(start 97.554311 132.484893)
		(end 97.573271 132.496806)
		(width 0.1)
		(layer "In2.Cu")
		(net 192)
	)
	(segment
		(start 97.209378 131.639991)
		(end 97.224096 131.654709)
		(width 0.1)
		(layer "In2.Cu")
		(net 192)
	)
	(segment
		(start 97.608415 132.197242)
		(end 97.601019 132.218378)
		(width 0.1)
		(layer "In2.Cu")
		(net 192)
	)
	(segment
		(start 97.191428 130.340217)
		(end 97.189098 130.360902)
		(width 0.1)
		(layer "In2.Cu")
		(net 192)
	)
	(segment
		(start 97.554311 130.665086)
		(end 97.533175 130.672482)
		(width 0.1)
		(layer "In2.Cu")
		(net 192)
	)
	(segment
		(start 97.191428 131.947261)
		(end 97.189098 131.967946)
		(width 0.1)
		(layer "In2.Cu")
		(net 192)
	)
	(segment
		(start 97.573271 132.096806)
		(end 97.589106 132.112641)
		(width 0.1)
		(layer "In2.Cu")
		(net 192)
	)
	(segment
		(start 97.452758 132.677497)
		(end 97.431622 132.684893)
		(width 0.1)
		(layer "In2.Cu")
		(net 192)
	)
	(segment
		(start 97.302738 130.265615)
		(end 97.261369 130.270276)
		(width 0.1)
		(layer "In2.Cu")
		(net 192)
	)
	(segment
		(start 97.601019 131.331601)
		(end 97.608415 131.352737)
		(width 0.1)
		(layer "In2.Cu")
		(net 192)
	)
	(segment
		(start 97.224096 130.69527)
		(end 97.209378 130.709988)
		(width 0.1)
		(layer "In2.Cu")
		(net 192)
	)
	(segment
		(start 97.209378 131.109988)
		(end 97.198303 131.127613)
		(width 0.1)
		(layer "In2.Cu")
		(net 192)
	)
	(segment
		(start 97.224096 130.854709)
		(end 97.241721 130.865784)
		(width 0.1)
		(layer "In2.Cu")
		(net 192)
	)
	(segment
		(start 97.573271 131.853173)
		(end 97.554311 131.865086)
		(width 0.1)
		(layer "In2.Cu")
		(net 192)
	)
	(segment
		(start 97.510922 131.47499)
		(end 97.282054 131.47499)
		(width 0.1)
		(layer "In2.Cu")
		(net 192)
	)
	(segment
		(start 97.608415 130.997242)
		(end 97.601019 131.018378)
		(width 0.1)
		(layer "In2.Cu")
		(net 192)
	)
	(segment
		(start 97.608415 132.597242)
		(end 97.601019 132.618378)
		(width 0.1)
		(layer "In2.Cu")
		(net 192)
	)
	(segment
		(start 97.384914 132.731601)
		(end 97.377518 132.752737)
		(width 0.1)
		(layer "In2.Cu")
		(net 192)
	)
	(segment
		(start 97.191428 132.347261)
		(end 97.189098 132.367946)
		(width 0.1)
		(layer "In2.Cu")
		(net 192)
	)
	(segment
		(start 97.261369 131.07732)
		(end 97.241721 131.084195)
		(width 0.1)
		(layer "In2.Cu")
		(net 192)
	)
	(segment
		(start 97.533175 131.472482)
		(end 97.510922 131.47499)
		(width 0.1)
		(layer "In2.Cu")
		(net 192)
	)
	(segment
		(start 97.510922 132.67499)
		(end 97.47501 132.67499)
		(width 0.1)
		(layer "In2.Cu")
		(net 192)
	)
	(segment
		(start 97.241721 130.865784)
		(end 97.261369 130.872659)
		(width 0.1)
		(layer "In2.Cu")
		(net 192)
	)
	(segment
		(start 97.775001 145.374999)
		(end 97.375 145.775)
		(width 0.1)
		(layer "In2.Cu")
		(net 192)
	)
	(segment
		(start 97.209378 130.839991)
		(end 97.224096 130.854709)
		(width 0.1)
		(layer "In2.Cu")
		(net 192)
	)
	(segment
		(start 97.510922 131.07499)
		(end 97.282054 131.07499)
		(width 0.1)
		(layer "In2.Cu")
		(net 192)
	)
	(segment
		(start 97.282054 130.467946)
		(end 97.37501 130.467946)
		(width 0.1)
		(layer "In2.Cu")
		(net 192)
	)
	(segment
		(start 97.209378 131.909988)
		(end 97.198303 131.927613)
		(width 0.1)
		(layer "In2.Cu")
		(net 192)
	)
	(segment
		(start 97.554311 131.284893)
		(end 97.573271 131.296806)
		(width 0.1)
		(layer "In2.Cu")
		(net 192)
	)
	(segment
		(start 97.189098 131.182034)
		(end 97.191428 131.202718)
		(width 0.1)
		(layer "In2.Cu")
		(net 192)
	)
	(segment
		(start 97.396827 132.712641)
		(end 97.384914 132.731601)
		(width 0.1)
		(layer "In2.Cu")
		(net 192)
	)
	(segment
		(start 97.189098 130.782034)
		(end 97.191428 130.802718)
		(width 0.1)
		(layer "In2.Cu")
		(net 192)
	)
	(segment
		(start 97.198303 130.822366)
		(end 97.209378 130.839991)
		(width 0.1)
		(layer "In2.Cu")
		(net 192)
	)
	(segment
		(start 97.608415 131.752737)
		(end 97.610922 131.77499)
		(width 0.1)
		(layer "In2.Cu")
		(net 192)
	)
	(segment
		(start 97.601019 130.618378)
		(end 97.589106 130.637338)
		(width 0.1)
		(layer "In2.Cu")
		(net 192)
	)
	(segment
		(start 97.533175 131.072482)
		(end 97.510922 131.07499)
		(width 0.1)
		(layer "In2.Cu")
		(net 192)
	)
	(segment
		(start 97.608415 131.352737)
		(end 97.610922 131.37499)
		(width 0.1)
		(layer "In2.Cu")
		(net 192)
	)
	(segment
		(start 97.510922 130.47499)
		(end 97.533175 130.477497)
		(width 0.1)
		(layer "In2.Cu")
		(net 192)
	)
	(segment
		(start 97.189098 130.37499)
		(end 97.191428 130.395674)
		(width 0.1)
		(layer "In2.Cu")
		(net 192)
	)
	(segment
		(start 97.573271 131.696806)
		(end 97.589106 131.712641)
		(width 0.1)
		(layer "In2.Cu")
		(net 192)
	)
	(segment
		(start 97.589106 132.512641)
		(end 97.601019 132.531601)
		(width 0.1)
		(layer "In2.Cu")
		(net 192)
	)
	(segment
		(start 94.575 145.575)
		(end 94.575 146.175)
		(width 0.1)
		(layer "F.Cu")
		(net 193)
	)
	(segment
		(start 94.775 128.175)
		(end 95.275 128.675)
		(width 0.15)
		(layer "F.Cu")
		(net 193)
	)
	(via blind
		(at 94.575 146.175)
		(size 0.5)
		(drill 0.2)
		(layers "F.Cu" "In2.Cu")
		(net 193)
	)
	(via blind
		(at 95.275 128.675)
		(size 0.5)
		(drill 0.2)
		(layers "F.Cu" "In2.Cu")
		(net 193)
	)
	(segment
		(start 94.500169 132.975)
		(end 94.962416 132.975)
		(width 0.1)
		(layer "In2.Cu")
		(net 193)
	)
	(segment
		(start 94.818388 133.384903)
		(end 94.837348 133.396816)
		(width 0.1)
		(layer "In2.Cu")
		(net 193)
	)
	(segment
		(start 94.43782 132.796816)
		(end 94.421985 132.812651)
		(width 0.1)
		(layer "In2.Cu")
		(net 193)
	)
	(segment
		(start 94.875 129.075)
		(end 94.875 132.675)
		(width 0.1)
		(layer "In2.Cu")
		(net 193)
	)
	(segment
		(start 95.016919 132.994071)
		(end 95.03076 133.007912)
		(width 0.1)
		(layer "In2.Cu")
		(net 193)
	)
	(segment
		(start 95.016919 133.155928)
		(end 95.000344 133.166343)
		(width 0.1)
		(layer "In2.Cu")
		(net 193)
	)
	(segment
		(start 94.477916 133.177507)
		(end 94.45678 133.184903)
		(width 0.1)
		(layer "In2.Cu")
		(net 193)
	)
	(segment
		(start 94.421985 132.812651)
		(end 94.410072 132.831611)
		(width 0.1)
		(layer "In2.Cu")
		(net 193)
	)
	(segment
		(start 94.853183 133.412651)
		(end 94.865096 133.431611)
		(width 0.1)
		(layer "In2.Cu")
		(net 193)
	)
	(segment
		(start 94.981868 133.172808)
		(end 94.962416 133.175)
		(width 0.1)
		(layer "In2.Cu")
		(net 193)
	)
	(segment
		(start 94.421985 133.337348)
		(end 94.43782 133.353183)
		(width 0.1)
		(layer "In2.Cu")
		(net 193)
	)
	(segment
		(start 95.041175 133.125512)
		(end 95.03076 133.142087)
		(width 0.1)
		(layer "In2.Cu")
		(net 193)
	)
	(segment
		(start 94.797252 133.377507)
		(end 94.818388 133.384903)
		(width 0.1)
		(layer "In2.Cu")
		(net 193)
	)
	(segment
		(start 94.875 145.275)
		(end 94.575 145.575)
		(width 0.1)
		(layer "In2.Cu")
		(net 193)
	)
	(segment
		(start 94.477916 133.372492)
		(end 94.500169 133.375)
		(width 0.1)
		(layer "In2.Cu")
		(net 193)
	)
	(segment
		(start 94.477916 132.777507)
		(end 94.45678 132.784903)
		(width 0.1)
		(layer "In2.Cu")
		(net 193)
	)
	(segment
		(start 94.500169 132.775)
		(end 94.477916 132.777507)
		(width 0.1)
		(layer "In2.Cu")
		(net 193)
	)
	(segment
		(start 94.962416 133.175)
		(end 94.500169 133.175)
		(width 0.1)
		(layer "In2.Cu")
		(net 193)
	)
	(segment
		(start 94.402676 133.252747)
		(end 94.400169 133.275)
		(width 0.1)
		(layer "In2.Cu")
		(net 193)
	)
	(segment
		(start 94.865096 132.718388)
		(end 94.853183 132.737348)
		(width 0.1)
		(layer "In2.Cu")
		(net 193)
	)
	(segment
		(start 95.04764 133.107036)
		(end 95.041175 133.125512)
		(width 0.1)
		(layer "In2.Cu")
		(net 193)
	)
	(segment
		(start 95.275 128.675)
		(end 94.875 129.075)
		(width 0.1)
		(layer "In2.Cu")
		(net 193)
	)
	(segment
		(start 94.43782 133.196816)
		(end 94.421985 133.212651)
		(width 0.1)
		(layer "In2.Cu")
		(net 193)
	)
	(segment
		(start 95.04764 133.042963)
		(end 95.049831 133.062415)
		(width 0.1)
		(layer "In2.Cu")
		(net 193)
	)
	(segment
		(start 94.421985 132.937348)
		(end 94.43782 132.953183)
		(width 0.1)
		(layer "In2.Cu")
		(net 193)
	)
	(segment
		(start 94.981868 132.977191)
		(end 95.000344 132.983656)
		(width 0.1)
		(layer "In2.Cu")
		(net 193)
	)
	(segment
		(start 94.45678 133.365096)
		(end 94.477916 133.372492)
		(width 0.1)
		(layer "In2.Cu")
		(net 193)
	)
	(segment
		(start 94.775 133.375)
		(end 94.797252 133.377507)
		(width 0.1)
		(layer "In2.Cu")
		(net 193)
	)
	(segment
		(start 94.410072 132.918388)
		(end 94.421985 132.937348)
		(width 0.1)
		(layer "In2.Cu")
		(net 193)
	)
	(segment
		(start 94.575 145.575)
		(end 94.575 146.175)
		(width 0.1)
		(layer "In2.Cu")
		(net 193)
	)
	(segment
		(start 94.410072 133.231611)
		(end 94.402676 133.252747)
		(width 0.1)
		(layer "In2.Cu")
		(net 193)
	)
	(segment
		(start 95.000344 133.166343)
		(end 94.981868 133.172808)
		(width 0.1)
		(layer "In2.Cu")
		(net 193)
	)
	(segment
		(start 94.962416 132.975)
		(end 94.981868 132.977191)
		(width 0.1)
		(layer "In2.Cu")
		(net 193)
	)
	(segment
		(start 95.049831 133.062415)
		(end 95.049831 133.087585)
		(width 0.1)
		(layer "In2.Cu")
		(net 193)
	)
	(segment
		(start 95.03076 133.142087)
		(end 95.016919 133.155928)
		(width 0.1)
		(layer "In2.Cu")
		(net 193)
	)
	(segment
		(start 95.049831 133.087585)
		(end 95.04764 133.107036)
		(width 0.1)
		(layer "In2.Cu")
		(net 193)
	)
	(segment
		(start 95.041175 133.024487)
		(end 95.04764 133.042963)
		(width 0.1)
		(layer "In2.Cu")
		(net 193)
	)
	(segment
		(start 95.000344 132.983656)
		(end 95.016919 132.994071)
		(width 0.1)
		(layer "In2.Cu")
		(net 193)
	)
	(segment
		(start 94.872492 133.452747)
		(end 94.875 133.475)
		(width 0.1)
		(layer "In2.Cu")
		(net 193)
	)
	(segment
		(start 94.500169 133.175)
		(end 94.477916 133.177507)
		(width 0.1)
		(layer "In2.Cu")
		(net 193)
	)
	(segment
		(start 94.818388 132.765096)
		(end 94.797252 132.772492)
		(width 0.1)
		(layer "In2.Cu")
		(net 193)
	)
	(segment
		(start 94.837348 132.753183)
		(end 94.818388 132.765096)
		(width 0.1)
		(layer "In2.Cu")
		(net 193)
	)
	(segment
		(start 94.797252 132.772492)
		(end 94.775 132.775)
		(width 0.1)
		(layer "In2.Cu")
		(net 193)
	)
	(segment
		(start 94.45678 133.184903)
		(end 94.43782 133.196816)
		(width 0.1)
		(layer "In2.Cu")
		(net 193)
	)
	(segment
		(start 94.402676 132.897252)
		(end 94.410072 132.918388)
		(width 0.1)
		(layer "In2.Cu")
		(net 193)
	)
	(segment
		(start 94.402676 132.852747)
		(end 94.400169 132.875)
		(width 0.1)
		(layer "In2.Cu")
		(net 193)
	)
	(segment
		(start 94.865096 133.431611)
		(end 94.872492 133.452747)
		(width 0.1)
		(layer "In2.Cu")
		(net 193)
	)
	(segment
		(start 94.837348 133.396816)
		(end 94.853183 133.412651)
		(width 0.1)
		(layer "In2.Cu")
		(net 193)
	)
	(segment
		(start 94.402676 133.297252)
		(end 94.410072 133.318388)
		(width 0.1)
		(layer "In2.Cu")
		(net 193)
	)
	(segment
		(start 94.43782 133.353183)
		(end 94.45678 133.365096)
		(width 0.1)
		(layer "In2.Cu")
		(net 193)
	)
	(segment
		(start 94.500169 133.375)
		(end 94.775 133.375)
		(width 0.1)
		(layer "In2.Cu")
		(net 193)
	)
	(segment
		(start 95.03076 133.007912)
		(end 95.041175 133.024487)
		(width 0.1)
		(layer "In2.Cu")
		(net 193)
	)
	(segment
		(start 94.775 132.775)
		(end 94.500169 132.775)
		(width 0.1)
		(layer "In2.Cu")
		(net 193)
	)
	(segment
		(start 94.45678 132.965096)
		(end 94.477916 132.972492)
		(width 0.1)
		(layer "In2.Cu")
		(net 193)
	)
	(segment
		(start 94.400169 133.275)
		(end 94.402676 133.297252)
		(width 0.1)
		(layer "In2.Cu")
		(net 193)
	)
	(segment
		(start 94.477916 132.972492)
		(end 94.500169 132.975)
		(width 0.1)
		(layer "In2.Cu")
		(net 193)
	)
	(segment
		(start 94.45678 132.784903)
		(end 94.43782 132.796816)
		(width 0.1)
		(layer "In2.Cu")
		(net 193)
	)
	(segment
		(start 94.410072 132.831611)
		(end 94.402676 132.852747)
		(width 0.1)
		(layer "In2.Cu")
		(net 193)
	)
	(segment
		(start 94.43782 132.953183)
		(end 94.45678 132.965096)
		(width 0.1)
		(layer "In2.Cu")
		(net 193)
	)
	(segment
		(start 94.410072 133.318388)
		(end 94.421985 133.337348)
		(width 0.1)
		(layer "In2.Cu")
		(net 193)
	)
	(segment
		(start 94.875 132.675)
		(end 94.872492 132.697252)
		(width 0.1)
		(layer "In2.Cu")
		(net 193)
	)
	(segment
		(start 94.400169 132.875)
		(end 94.402676 132.897252)
		(width 0.1)
		(layer "In2.Cu")
		(net 193)
	)
	(segment
		(start 94.421985 133.212651)
		(end 94.410072 133.231611)
		(width 0.1)
		(layer "In2.Cu")
		(net 193)
	)
	(segment
		(start 94.875 133.475)
		(end 94.875 145.275)
		(width 0.1)
		(layer "In2.Cu")
		(net 193)
	)
	(segment
		(start 94.872492 132.697252)
		(end 94.865096 132.718388)
		(width 0.1)
		(layer "In2.Cu")
		(net 193)
	)
	(segment
		(start 94.853183 132.737348)
		(end 94.837348 132.753183)
		(width 0.1)
		(layer "In2.Cu")
		(net 193)
	)
	(segment
		(start 95.375 148.775)
		(end 95.375 148.175)
		(width 0.1)
		(layer "F.Cu")
		(net 194)
	)
	(segment
		(start 96.275 129.675)
		(end 96.17499 129.675)
		(width 0.15)
		(layer "F.Cu")
		(net 194)
	)
	(segment
		(start 96.775 129.175)
		(end 96.275 129.675)
		(width 0.15)
		(layer "F.Cu")
		(net 194)
	)
	(via blind
		(at 95.375 148.175)
		(size 0.5)
		(drill 0.2)
		(layers "F.Cu" "In2.Cu")
		(net 194)
	)
	(via blind
		(at 96.17499 129.675)
		(size 0.5)
		(drill 0.2)
		(layers "F.Cu" "In2.Cu")
		(net 194)
	)
	(segment
		(start 96.291986 132.926153)
		(end 96.249394 132.930952)
		(width 0.1)
		(layer "In2.Cu")
		(net 194)
	)
	(segment
		(start 96.033591 132.728553)
		(end 96.27069 132.728553)
		(width 0.1)
		(layer "In2.Cu")
		(net 194)
	)
	(segment
		(start 96.356912 132.074376)
		(end 96.345511 132.092521)
		(width 0.1)
		(layer "In2.Cu")
		(net 194)
	)
	(segment
		(start 96.36399 132.402956)
		(end 96.366389 132.424252)
		(width 0.1)
		(layer "In2.Cu")
		(net 194)
	)
	(segment
		(start 95.936098 131.850805)
		(end 95.943494 131.871941)
		(width 0.1)
		(layer "In2.Cu")
		(net 194)
	)
	(segment
		(start 96.36399 131.602956)
		(end 96.366389 131.624252)
		(width 0.1)
		(layer "In2.Cu")
		(net 194)
	)
	(segment
		(start 96.356912 131.274376)
		(end 96.345511 131.292521)
		(width 0.1)
		(layer "In2.Cu")
		(net 194)
	)
	(segment
		(start 95.990202 130.318649)
		(end 96.011338 130.326045)
		(width 0.1)
		(layer "In2.Cu")
		(net 194)
	)
	(segment
		(start 95.955407 132.690901)
		(end 95.971242 132.706736)
		(width 0.1)
		(layer "In2.Cu")
		(net 194)
	)
	(segment
		(start 95.955407 130.166204)
		(end 95.943494 130.185164)
		(width 0.1)
		(layer "In2.Cu")
		(net 194)
	)
	(segment
		(start 95.955407 132.166204)
		(end 95.943494 132.185164)
		(width 0.1)
		(layer "In2.Cu")
		(net 194)
	)
	(segment
		(start 95.936098 130.650805)
		(end 95.943494 130.671941)
		(width 0.1)
		(layer "In2.Cu")
		(net 194)
	)
	(segment
		(start 96.312213 131.53803)
		(end 96.330358 131.549431)
		(width 0.1)
		(layer "In2.Cu")
		(net 194)
	)
	(segment
		(start 96.033591 131.328553)
		(end 96.011338 131.33106)
		(width 0.1)
		(layer "In2.Cu")
		(net 194)
	)
	(segment
		(start 96.312213 132.519075)
		(end 96.291986 132.526153)
		(width 0.1)
		(layer "In2.Cu")
		(net 194)
	)
	(segment
		(start 95.990202 131.738456)
		(end 95.971242 131.750369)
		(width 0.1)
		(layer "In2.Cu")
		(net 194)
	)
	(segment
		(start 96.36399 131.202956)
		(end 96.366389 131.224252)
		(width 0.1)
		(layer "In2.Cu")
		(net 194)
	)
	(segment
		(start 96.36399 131.654149)
		(end 96.356912 131.674376)
		(width 0.1)
		(layer "In2.Cu")
		(net 194)
	)
	(segment
		(start 95.933591 131.828553)
		(end 95.936098 131.850805)
		(width 0.1)
		(layer "In2.Cu")
		(net 194)
	)
	(segment
		(start 96.249394 132.930952)
		(end 96.229167 132.93803)
		(width 0.1)
		(layer "In2.Cu")
		(net 194)
	)
	(segment
		(start 96.330358 131.307674)
		(end 96.312213 131.319075)
		(width 0.1)
		(layer "In2.Cu")
		(net 194)
	)
	(segment
		(start 96.345511 132.092521)
		(end 96.330358 132.107674)
		(width 0.1)
		(layer "In2.Cu")
		(net 194)
	)
	(segment
		(start 95.933591 130.628553)
		(end 95.936098 130.650805)
		(width 0.1)
		(layer "In2.Cu")
		(net 194)
	)
	(segment
		(start 95.971242 130.306736)
		(end 95.990202 130.318649)
		(width 0.1)
		(layer "In2.Cu")
		(net 194)
	)
	(segment
		(start 95.955407 130.566204)
		(end 95.943494 130.585164)
		(width 0.1)
		(layer "In2.Cu")
		(net 194)
	)
	(segment
		(start 96.312213 131.719075)
		(end 96.291986 131.726153)
		(width 0.1)
		(layer "In2.Cu")
		(net 194)
	)
	(segment
		(start 95.936098 132.250805)
		(end 95.943494 132.271941)
		(width 0.1)
		(layer "In2.Cu")
		(net 194)
	)
	(segment
		(start 95.971242 130.150369)
		(end 95.955407 130.166204)
		(width 0.1)
		(layer "In2.Cu")
		(net 194)
	)
	(segment
		(start 96.345511 130.492521)
		(end 96.330358 130.507674)
		(width 0.1)
		(layer "In2.Cu")
		(net 194)
	)
	(segment
		(start 95.936098 132.6063)
		(end 95.933591 132.628553)
		(width 0.1)
		(layer "In2.Cu")
		(net 194)
	)
	(segment
		(start 96.330358 130.349431)
		(end 96.345511 130.364584)
		(width 0.1)
		(layer "In2.Cu")
		(net 194)
	)
	(segment
		(start 96.033591 131.528553)
		(end 96.27069 131.528553)
		(width 0.1)
		(layer "In2.Cu")
		(net 194)
	)
	(segment
		(start 96.033591 131.128553)
		(end 96.27069 131.128553)
		(width 0.1)
		(layer "In2.Cu")
		(net 194)
	)
	(segment
		(start 95.775 145.575)
		(end 95.775 146.575)
		(width 0.1)
		(layer "In2.Cu")
		(net 194)
	)
	(segment
		(start 96.36399 130.854149)
		(end 96.356912 130.874376)
		(width 0.1)
		(layer "In2.Cu")
		(net 194)
	)
	(segment
		(start 96.330358 132.749431)
		(end 96.345511 132.764584)
		(width 0.1)
		(layer "In2.Cu")
		(net 194)
	)
	(segment
		(start 95.971242 131.750369)
		(end 95.955407 131.766204)
		(width 0.1)
		(layer "In2.Cu")
		(net 194)
	)
	(segment
		(start 96.033591 130.128553)
		(end 96.011338 130.13106)
		(width 0.1)
		(layer "In2.Cu")
		(net 194)
	)
	(segment
		(start 95.971242 130.706736)
		(end 95.990202 130.718649)
		(width 0.1)
		(layer "In2.Cu")
		(net 194)
	)
	(segment
		(start 96.27069 131.728553)
		(end 96.033591 131.728553)
		(width 0.1)
		(layer "In2.Cu")
		(net 194)
	)
	(segment
		(start 96.291986 131.130952)
		(end 96.312213 131.13803)
		(width 0.1)
		(layer "In2.Cu")
		(net 194)
	)
	(segment
		(start 95.943494 131.385164)
		(end 95.936098 131.4063)
		(width 0.1)
		(layer "In2.Cu")
		(net 194)
	)
	(segment
		(start 96.330358 131.949431)
		(end 96.345511 131.964584)
		(width 0.1)
		(layer "In2.Cu")
		(net 194)
	)
	(segment
		(start 96.153173 130.090901)
		(end 96.137338 130.106736)
		(width 0.1)
		(layer "In2.Cu")
		(net 194)
	)
	(segment
		(start 96.330358 131.149431)
		(end 96.345511 131.164584)
		(width 0.1)
		(layer "In2.Cu")
		(net 194)
	)
	(segment
		(start 96.366389 130.432854)
		(end 96.36399 130.454149)
		(width 0.1)
		(layer "In2.Cu")
		(net 194)
	)
	(segment
		(start 95.943494 131.785164)
		(end 95.936098 131.8063)
		(width 0.1)
		(layer "In2.Cu")
		(net 194)
	)
	(segment
		(start 96.345511 132.764584)
		(end 96.356912 132.782729)
		(width 0.1)
		(layer "In2.Cu")
		(net 194)
	)
	(segment
		(start 96.356912 130.874376)
		(end 96.345511 130.892521)
		(width 0.1)
		(layer "In2.Cu")
		(net 194)
	)
	(segment
		(start 96.330358 132.507674)
		(end 96.312213 132.519075)
		(width 0.1)
		(layer "In2.Cu")
		(net 194)
	)
	(segment
		(start 96.345511 131.564584)
		(end 96.356912 131.582729)
		(width 0.1)
		(layer "In2.Cu")
		(net 194)
	)
	(segment
		(start 96.291986 131.530952)
		(end 96.312213 131.53803)
		(width 0.1)
		(layer "In2.Cu")
		(net 194)
	)
	(segment
		(start 96.27069 130.528553)
		(end 96.033591 130.528553)
		(width 0.1)
		(layer "In2.Cu")
		(net 194)
	)
	(segment
		(start 96.312213 130.519075)
		(end 96.291986 130.526153)
		(width 0.1)
		(layer "In2.Cu")
		(net 194)
	)
	(segment
		(start 95.943494 132.671941)
		(end 95.955407 132.690901)
		(width 0.1)
		(layer "In2.Cu")
		(net 194)
	)
	(segment
		(start 96.345511 131.164584)
		(end 96.356912 131.182729)
		(width 0.1)
		(layer "In2.Cu")
		(net 194)
	)
	(segment
		(start 96.36399 132.454149)
		(end 96.356912 132.474376)
		(width 0.1)
		(layer "In2.Cu")
		(net 194)
	)
	(segment
		(start 96.033591 131.928553)
		(end 96.27069 131.928553)
		(width 0.1)
		(layer "In2.Cu")
		(net 194)
	)
	(segment
		(start 96.36399 132.854149)
		(end 96.356912 132.874376)
		(width 0.1)
		(layer "In2.Cu")
		(net 194)
	)
	(segment
		(start 96.356912 132.874376)
		(end 96.345511 132.892521)
		(width 0.1)
		(layer "In2.Cu")
		(net 194)
	)
	(segment
		(start 95.936098 130.2063)
		(end 95.933591 130.228553)
		(width 0.1)
		(layer "In2.Cu")
		(net 194)
	)
	(segment
		(start 95.933591 130.228553)
		(end 95.936098 130.250805)
		(width 0.1)
		(layer "In2.Cu")
		(net 194)
	)
	(segment
		(start 95.936098 132.650805)
		(end 95.943494 132.671941)
		(width 0.1)
		(layer "In2.Cu")
		(net 194)
	)
	(segment
		(start 95.955407 131.890901)
		(end 95.971242 131.906736)
		(width 0.1)
		(layer "In2.Cu")
		(net 194)
	)
	(segment
		(start 96.291986 131.326153)
		(end 96.27069 131.328553)
		(width 0.1)
		(layer "In2.Cu")
		(net 194)
	)
	(segment
		(start 96.366389 131.624252)
		(end 96.366389 131.632854)
		(width 0.1)
		(layer "In2.Cu")
		(net 194)
	)
	(segment
		(start 96.36399 132.802956)
		(end 96.366389 132.824252)
		(width 0.1)
		(layer "In2.Cu")
		(net 194)
	)
	(segment
		(start 96.345511 131.964584)
		(end 96.356912 131.982729)
		(width 0.1)
		(layer "In2.Cu")
		(net 194)
	)
	(segment
		(start 96.330358 130.507674)
		(end 96.312213 130.519075)
		(width 0.1)
		(layer "In2.Cu")
		(net 194)
	)
	(segment
		(start 95.955407 131.766204)
		(end 95.943494 131.785164)
		(width 0.1)
		(layer "In2.Cu")
		(net 194)
	)
	(segment
		(start 96.345511 130.764584)
		(end 96.356912 130.782729)
		(width 0.1)
		(layer "In2.Cu")
		(net 194)
	)
	(segment
		(start 96.330358 132.107674)
		(end 96.312213 132.119075)
		(width 0.1)
		(layer "In2.Cu")
		(net 194)
	)
	(segment
		(start 96.27069 130.728553)
		(end 96.291986 130.730952)
		(width 0.1)
		(layer "In2.Cu")
		(net 194)
	)
	(segment
		(start 96.366389 131.632854)
		(end 96.36399 131.654149)
		(width 0.1)
		(layer "In2.Cu")
		(net 194)
	)
	(segment
		(start 95.990202 131.118649)
		(end 96.011338 131.126045)
		(width 0.1)
		(layer "In2.Cu")
		(net 194)
	)
	(segment
		(start 96.356912 132.474376)
		(end 96.345511 132.492521)
		(width 0.1)
		(layer "In2.Cu")
		(net 194)
	)
	(segment
		(start 96.17499 133.024252)
		(end 96.17499 145.17501)
		(width 0.1)
		(layer "In2.Cu")
		(net 194)
	)
	(segment
		(start 96.312213 131.13803)
		(end 96.330358 131.149431)
		(width 0.1)
		(layer "In2.Cu")
		(net 194)
	)
	(segment
		(start 95.971242 132.150369)
		(end 95.955407 132.166204)
		(width 0.1)
		(layer "In2.Cu")
		(net 194)
	)
	(segment
		(start 95.971242 132.306736)
		(end 95.990202 132.318649)
		(width 0.1)
		(layer "In2.Cu")
		(net 194)
	)
	(segment
		(start 96.312213 131.319075)
		(end 96.291986 131.326153)
		(width 0.1)
		(layer "In2.Cu")
		(net 194)
	)
	(segment
		(start 96.291986 132.526153)
		(end 96.27069 132.528553)
		(width 0.1)
		(layer "In2.Cu")
		(net 194)
	)
	(segment
		(start 95.943494 130.585164)
		(end 95.936098 130.6063)
		(width 0.1)
		(layer "In2.Cu")
		(net 194)
	)
	(segment
		(start 96.011338 131.526045)
		(end 96.033591 131.528553)
		(width 0.1)
		(layer "In2.Cu")
		(net 194)
	)
	(segment
		(start 96.165086 130.071941)
		(end 96.153173 130.090901)
		(width 0.1)
		(layer "In2.Cu")
		(net 194)
	)
	(segment
		(start 96.366389 132.032854)
		(end 96.36399 132.054149)
		(width 0.1)
		(layer "In2.Cu")
		(net 194)
	)
	(segment
		(start 95.990202 131.338456)
		(end 95.971242 131.350369)
		(width 0.1)
		(layer "In2.Cu")
		(net 194)
	)
	(segment
		(start 96.033591 131.728553)
		(end 96.011338 131.73106)
		(width 0.1)
		(layer "In2.Cu")
		(net 194)
	)
	(segment
		(start 96.011338 130.93106)
		(end 95.990202 130.938456)
		(width 0.1)
		(layer "In2.Cu")
		(net 194)
	)
	(segment
		(start 96.291986 131.930952)
		(end 96.312213 131.93803)
		(width 0.1)
		(layer "In2.Cu")
		(net 194)
	)
	(segment
		(start 96.291986 132.730952)
		(end 96.312213 132.73803)
		(width 0.1)
		(layer "In2.Cu")
		(net 194)
	)
	(segment
		(start 95.775 146.575)
		(end 95.375 146.975)
		(width 0.1)
		(layer "In2.Cu")
		(net 194)
	)
	(segment
		(start 95.943494 132.271941)
		(end 95.955407 132.290901)
		(width 0.1)
		(layer "In2.Cu")
		(net 194)
	)
	(segment
		(start 96.17499 130.028553)
		(end 96.172482 130.050805)
		(width 0.1)
		(layer "In2.Cu")
		(net 194)
	)
	(segment
		(start 95.990202 132.718649)
		(end 96.011338 132.726045)
		(width 0.1)
		(layer "In2.Cu")
		(net 194)
	)
	(segment
		(start 96.184468 132.982729)
		(end 96.17739 133.002956)
		(width 0.1)
		(layer "In2.Cu")
		(net 194)
	)
	(segment
		(start 95.990202 130.138456)
		(end 95.971242 130.150369)
		(width 0.1)
		(layer "In2.Cu")
		(net 194)
	)
	(segment
		(start 95.933591 131.028553)
		(end 95.936098 131.050805)
		(width 0.1)
		(layer "In2.Cu")
		(net 194)
	)
	(segment
		(start 96.345511 132.364584)
		(end 96.356912 132.382729)
		(width 0.1)
		(layer "In2.Cu")
		(net 194)
	)
	(segment
		(start 96.312213 132.33803)
		(end 96.330358 132.349431)
		(width 0.1)
		(layer "In2.Cu")
		(net 194)
	)
	(segment
		(start 96.195869 132.964584)
		(end 96.184468 132.982729)
		(width 0.1)
		(layer "In2.Cu")
		(net 194)
	)
	(segment
		(start 95.955407 130.290901)
		(end 95.971242 130.306736)
		(width 0.1)
		(layer "In2.Cu")
		(net 194)
	)
	(segment
		(start 96.27069 132.328553)
		(end 96.291986 132.330952)
		(width 0.1)
		(layer "In2.Cu")
		(net 194)
	)
	(segment
		(start 96.291986 132.330952)
		(end 96.312213 132.33803)
		(width 0.1)
		(layer "In2.Cu")
		(net 194)
	)
	(segment
		(start 96.011338 131.126045)
		(end 96.033591 131.128553)
		(width 0.1)
		(layer "In2.Cu")
		(net 194)
	)
	(segment
		(start 96.137338 130.106736)
		(end 96.118378 130.118649)
		(width 0.1)
		(layer "In2.Cu")
		(net 194)
	)
	(segment
		(start 96.033591 132.128553)
		(end 96.011338 132.13106)
		(width 0.1)
		(layer "In2.Cu")
		(net 194)
	)
	(segment
		(start 96.27069 130.928553)
		(end 96.033591 130.928553)
		(width 0.1)
		(layer "In2.Cu")
		(net 194)
	)
	(segment
		(start 96.011338 130.53106)
		(end 95.990202 130.538456)
		(width 0.1)
		(layer "In2.Cu")
		(net 194)
	)
	(segment
		(start 96.27069 132.128553)
		(end 96.033591 132.128553)
		(width 0.1)
		(layer "In2.Cu")
		(net 194)
	)
	(segment
		(start 96.356912 131.674376)
		(end 96.345511 131.692521)
		(width 0.1)
		(layer "In2.Cu")
		(net 194)
	)
	(segment
		(start 95.943494 131.871941)
		(end 95.955407 131.890901)
		(width 0.1)
		(layer "In2.Cu")
		(net 194)
	)
	(segment
		(start 95.933591 131.428553)
		(end 95.936098 131.450805)
		(width 0.1)
		(layer "In2.Cu")
		(net 194)
	)
	(segment
		(start 96.312213 130.919075)
		(end 96.291986 130.926153)
		(width 0.1)
		(layer "In2.Cu")
		(net 194)
	)
	(segment
		(start 96.366389 132.024252)
		(end 96.366389 132.032854)
		(width 0.1)
		(layer "In2.Cu")
		(net 194)
	)
	(segment
		(start 96.330358 130.907674)
		(end 96.312213 130.919075)
		(width 0.1)
		(layer "In2.Cu")
		(net 194)
	)
	(segment
		(start 96.011338 130.13106)
		(end 95.990202 130.138456)
		(width 0.1)
		(layer "In2.Cu")
		(net 194)
	)
	(segment
		(start 96.291986 132.126153)
		(end 96.27069 132.128553)
		(width 0.1)
		(layer "In2.Cu")
		(net 194)
	)
	(segment
		(start 96.366389 132.424252)
		(end 96.366389 132.432854)
		(width 0.1)
		(layer "In2.Cu")
		(net 194)
	)
	(segment
		(start 95.936098 131.4063)
		(end 95.933591 131.428553)
		(width 0.1)
		(layer "In2.Cu")
		(net 194)
	)
	(segment
		(start 95.936098 131.8063)
		(end 95.933591 131.828553)
		(width 0.1)
		(layer "In2.Cu")
		(net 194)
	)
	(segment
		(start 96.033591 130.928553)
		(end 96.011338 130.93106)
		(width 0.1)
		(layer "In2.Cu")
		(net 194)
	)
	(segment
		(start 96.033591 132.528553)
		(end 96.011338 132.53106)
		(width 0.1)
		(layer "In2.Cu")
		(net 194)
	)
	(segment
		(start 95.375 146.975)
		(end 95.375 148.175)
		(width 0.1)
		(layer "In2.Cu")
		(net 194)
	)
	(segment
		(start 96.27069 130.328553)
		(end 96.291986 130.330952)
		(width 0.1)
		(layer "In2.Cu")
		(net 194)
	)
	(segment
		(start 96.366389 130.824252)
		(end 96.366389 130.832854)
		(width 0.1)
		(layer "In2.Cu")
		(net 194)
	)
	(segment
		(start 96.36399 132.002956)
		(end 96.366389 132.024252)
		(width 0.1)
		(layer "In2.Cu")
		(net 194)
	)
	(segment
		(start 96.36399 130.402956)
		(end 96.366389 130.424252)
		(width 0.1)
		(layer "In2.Cu")
		(net 194)
	)
	(segment
		(start 96.345511 130.364584)
		(end 96.356912 130.382729)
		(width 0.1)
		(layer "In2.Cu")
		(net 194)
	)
	(segment
		(start 96.312213 130.33803)
		(end 96.330358 130.349431)
		(width 0.1)
		(layer "In2.Cu")
		(net 194)
	)
	(segment
		(start 95.936098 131.0063)
		(end 95.933591 131.028553)
		(width 0.1)
		(layer "In2.Cu")
		(net 194)
	)
	(segment
		(start 96.330358 130.749431)
		(end 96.345511 130.764584)
		(width 0.1)
		(layer "In2.Cu")
		(net 194)
	)
	(segment
		(start 95.971242 131.506736)
		(end 95.990202 131.518649)
		(width 0.1)
		(layer "In2.Cu")
		(net 194)
	)
	(segment
		(start 95.943494 132.185164)
		(end 95.936098 132.2063)
		(width 0.1)
		(layer "In2.Cu")
		(net 194)
	)
	(segment
		(start 96.291986 130.730952)
		(end 96.312213 130.73803)
		(width 0.1)
		(layer "In2.Cu")
		(net 194)
	)
	(segment
		(start 96.011338 132.326045)
		(end 96.033591 132.328553)
		(width 0.1)
		(layer "In2.Cu")
		(net 194)
	)
	(segment
		(start 96.312213 132.919075)
		(end 96.291986 132.926153)
		(width 0.1)
		(layer "In2.Cu")
		(net 194)
	)
	(segment
		(start 96.356912 131.582729)
		(end 96.36399 131.602956)
		(width 0.1)
		(layer "In2.Cu")
		(net 194)
	)
	(segment
		(start 96.312213 132.73803)
		(end 96.330358 132.749431)
		(width 0.1)
		(layer "In2.Cu")
		(net 194)
	)
	(segment
		(start 95.936098 130.6063)
		(end 95.933591 130.628553)
		(width 0.1)
		(layer "In2.Cu")
		(net 194)
	)
	(segment
		(start 95.943494 130.271941)
		(end 95.955407 130.290901)
		(width 0.1)
		(layer "In2.Cu")
		(net 194)
	)
	(segment
		(start 96.097242 130.126045)
		(end 96.07499 130.128553)
		(width 0.1)
		(layer "In2.Cu")
		(net 194)
	)
	(segment
		(start 96.356912 131.182729)
		(end 96.36399 131.202956)
		(width 0.1)
		(layer "In2.Cu")
		(net 194)
	)
	(segment
		(start 96.366389 131.224252)
		(end 96.366389 131.232854)
		(width 0.1)
		(layer "In2.Cu")
		(net 194)
	)
	(segment
		(start 96.36399 132.054149)
		(end 96.356912 132.074376)
		(width 0.1)
		(layer "In2.Cu")
		(net 194)
	)
	(segment
		(start 96.291986 130.330952)
		(end 96.312213 130.33803)
		(width 0.1)
		(layer "In2.Cu")
		(net 194)
	)
	(segment
		(start 95.971242 132.706736)
		(end 95.990202 132.718649)
		(width 0.1)
		(layer "In2.Cu")
		(net 194)
	)
	(segment
		(start 96.27069 131.328553)
		(end 96.033591 131.328553)
		(width 0.1)
		(layer "In2.Cu")
		(net 194)
	)
	(segment
		(start 95.943494 132.585164)
		(end 95.936098 132.6063)
		(width 0.1)
		(layer "In2.Cu")
		(net 194)
	)
	(segment
		(start 96.356912 132.382729)
		(end 96.36399 132.402956)
		(width 0.1)
		(layer "In2.Cu")
		(net 194)
	)
	(segment
		(start 95.933591 132.628553)
		(end 95.936098 132.650805)
		(width 0.1)
		(layer "In2.Cu")
		(net 194)
	)
	(segment
		(start 95.990202 132.538456)
		(end 95.971242 132.550369)
		(width 0.1)
		(layer "In2.Cu")
		(net 194)
	)
	(segment
		(start 96.345511 130.892521)
		(end 96.330358 130.907674)
		(width 0.1)
		(layer "In2.Cu")
		(net 194)
	)
	(segment
		(start 95.990202 132.318649)
		(end 96.011338 132.326045)
		(width 0.1)
		(layer "In2.Cu")
		(net 194)
	)
	(segment
		(start 96.07499 130.128553)
		(end 96.033591 130.128553)
		(width 0.1)
		(layer "In2.Cu")
		(net 194)
	)
	(segment
		(start 95.990202 132.138456)
		(end 95.971242 132.150369)
		(width 0.1)
		(layer "In2.Cu")
		(net 194)
	)
	(segment
		(start 96.366389 130.424252)
		(end 96.366389 130.432854)
		(width 0.1)
		(layer "In2.Cu")
		(net 194)
	)
	(segment
		(start 96.011338 131.73106)
		(end 95.990202 131.738456)
		(width 0.1)
		(layer "In2.Cu")
		(net 194)
	)
	(segment
		(start 96.356912 131.982729)
		(end 96.36399 132.002956)
		(width 0.1)
		(layer "In2.Cu")
		(net 194)
	)
	(segment
		(start 96.330358 131.549431)
		(end 96.345511 131.564584)
		(width 0.1)
		(layer "In2.Cu")
		(net 194)
	)
	(segment
		(start 96.27069 131.928553)
		(end 96.291986 131.930952)
		(width 0.1)
		(layer "In2.Cu")
		(net 194)
	)
	(segment
		(start 96.36399 130.802956)
		(end 96.366389 130.824252)
		(width 0.1)
		(layer "In2.Cu")
		(net 194)
	)
	(segment
		(start 95.990202 131.518649)
		(end 96.011338 131.526045)
		(width 0.1)
		(layer "In2.Cu")
		(net 194)
	)
	(segment
		(start 96.17499 145.17501)
		(end 95.775 145.575)
		(width 0.1)
		(layer "In2.Cu")
		(net 194)
	)
	(segment
		(start 95.971242 130.550369)
		(end 95.955407 130.566204)
		(width 0.1)
		(layer "In2.Cu")
		(net 194)
	)
	(segment
		(start 96.27069 132.528553)
		(end 96.033591 132.528553)
		(width 0.1)
		(layer "In2.Cu")
		(net 194)
	)
	(segment
		(start 96.356912 130.474376)
		(end 96.345511 130.492521)
		(width 0.1)
		(layer "In2.Cu")
		(net 194)
	)
	(segment
		(start 95.943494 130.985164)
		(end 95.936098 131.0063)
		(width 0.1)
		(layer "In2.Cu")
		(net 194)
	)
	(segment
		(start 95.943494 131.071941)
		(end 95.955407 131.090901)
		(width 0.1)
		(layer "In2.Cu")
		(net 194)
	)
	(segment
		(start 96.356912 130.382729)
		(end 96.36399 130.402956)
		(width 0.1)
		(layer "In2.Cu")
		(net 194)
	)
	(segment
		(start 96.033591 130.728553)
		(end 96.27069 130.728553)
		(width 0.1)
		(layer "In2.Cu")
		(net 194)
	)
	(segment
		(start 95.955407 131.090901)
		(end 95.971242 131.106736)
		(width 0.1)
		(layer "In2.Cu")
		(net 194)
	)
	(segment
		(start 95.936098 130.250805)
		(end 95.943494 130.271941)
		(width 0.1)
		(layer "In2.Cu")
		(net 194)
	)
	(segment
		(start 96.330358 132.907674)
		(end 96.312213 132.919075)
		(width 0.1)
		(layer "In2.Cu")
		(net 194)
	)
	(segment
		(start 96.345511 132.492521)
		(end 96.330358 132.507674)
		(width 0.1)
		(layer "In2.Cu")
		(net 194)
	)
	(segment
		(start 96.366389 132.824252)
		(end 96.366389 132.832854)
		(width 0.1)
		(layer "In2.Cu")
		(net 194)
	)
	(segment
		(start 96.312213 131.93803)
		(end 96.330358 131.949431)
		(width 0.1)
		(layer "In2.Cu")
		(net 194)
	)
	(segment
		(start 96.033591 132.328553)
		(end 96.27069 132.328553)
		(width 0.1)
		(layer "In2.Cu")
		(net 194)
	)
	(segment
		(start 96.17739 133.002956)
		(end 96.17499 133.024252)
		(width 0.1)
		(layer "In2.Cu")
		(net 194)
	)
	(segment
		(start 95.933591 132.228553)
		(end 95.936098 132.250805)
		(width 0.1)
		(layer "In2.Cu")
		(net 194)
	)
	(segment
		(start 95.971242 131.906736)
		(end 95.990202 131.918649)
		(width 0.1)
		(layer "In2.Cu")
		(net 194)
	)
	(segment
		(start 96.330358 132.349431)
		(end 96.345511 132.364584)
		(width 0.1)
		(layer "In2.Cu")
		(net 194)
	)
	(segment
		(start 95.936098 131.050805)
		(end 95.943494 131.071941)
		(width 0.1)
		(layer "In2.Cu")
		(net 194)
	)
	(segment
		(start 96.366389 132.832854)
		(end 96.36399 132.854149)
		(width 0.1)
		(layer "In2.Cu")
		(net 194)
	)
	(segment
		(start 96.17499 129.675)
		(end 96.17499 130.028553)
		(width 0.1)
		(layer "In2.Cu")
		(net 194)
	)
	(segment
		(start 95.955407 130.966204)
		(end 95.943494 130.985164)
		(width 0.1)
		(layer "In2.Cu")
		(net 194)
	)
	(segment
		(start 96.312213 130.73803)
		(end 96.330358 130.749431)
		(width 0.1)
		(layer "In2.Cu")
		(net 194)
	)
	(segment
		(start 95.955407 130.690901)
		(end 95.971242 130.706736)
		(width 0.1)
		(layer "In2.Cu")
		(net 194)
	)
	(segment
		(start 96.011338 132.13106)
		(end 95.990202 132.138456)
		(width 0.1)
		(layer "In2.Cu")
		(net 194)
	)
	(segment
		(start 96.27069 131.528553)
		(end 96.291986 131.530952)
		(width 0.1)
		(layer "In2.Cu")
		(net 194)
	)
	(segment
		(start 96.118378 130.118649)
		(end 96.097242 130.126045)
		(width 0.1)
		(layer "In2.Cu")
		(net 194)
	)
	(segment
		(start 95.971242 131.350369)
		(end 95.955407 131.366204)
		(width 0.1)
		(layer "In2.Cu")
		(net 194)
	)
	(segment
		(start 96.172482 130.050805)
		(end 96.165086 130.071941)
		(width 0.1)
		(layer "In2.Cu")
		(net 194)
	)
	(segment
		(start 96.36399 131.254149)
		(end 96.356912 131.274376)
		(width 0.1)
		(layer "In2.Cu")
		(net 194)
	)
	(segment
		(start 96.229167 132.93803)
		(end 96.211022 132.949431)
		(width 0.1)
		(layer "In2.Cu")
		(net 194)
	)
	(segment
		(start 96.345511 131.292521)
		(end 96.330358 131.307674)
		(width 0.1)
		(layer "In2.Cu")
		(net 194)
	)
	(segment
		(start 96.356912 130.782729)
		(end 96.36399 130.802956)
		(width 0.1)
		(layer "In2.Cu")
		(net 194)
	)
	(segment
		(start 96.011338 131.926045)
		(end 96.033591 131.928553)
		(width 0.1)
		(layer "In2.Cu")
		(net 194)
	)
	(segment
		(start 95.990202 130.538456)
		(end 95.971242 130.550369)
		(width 0.1)
		(layer "In2.Cu")
		(net 194)
	)
	(segment
		(start 95.971242 131.106736)
		(end 95.990202 131.118649)
		(width 0.1)
		(layer "In2.Cu")
		(net 194)
	)
	(segment
		(start 95.990202 130.938456)
		(end 95.971242 130.950369)
		(width 0.1)
		(layer "In2.Cu")
		(net 194)
	)
	(segment
		(start 96.211022 132.949431)
		(end 96.195869 132.964584)
		(width 0.1)
		(layer "In2.Cu")
		(net 194)
	)
	(segment
		(start 95.955407 132.566204)
		(end 95.943494 132.585164)
		(width 0.1)
		(layer "In2.Cu")
		(net 194)
	)
	(segment
		(start 96.011338 132.726045)
		(end 96.033591 132.728553)
		(width 0.1)
		(layer "In2.Cu")
		(net 194)
	)
	(segment
		(start 96.291986 130.926153)
		(end 96.27069 130.928553)
		(width 0.1)
		(layer "In2.Cu")
		(net 194)
	)
	(segment
		(start 96.033591 130.328553)
		(end 96.27069 130.328553)
		(width 0.1)
		(layer "In2.Cu")
		(net 194)
	)
	(segment
		(start 95.971242 132.550369)
		(end 95.955407 132.566204)
		(width 0.1)
		(layer "In2.Cu")
		(net 194)
	)
	(segment
		(start 96.366389 131.232854)
		(end 96.36399 131.254149)
		(width 0.1)
		(layer "In2.Cu")
		(net 194)
	)
	(segment
		(start 96.356912 132.782729)
		(end 96.36399 132.802956)
		(width 0.1)
		(layer "In2.Cu")
		(net 194)
	)
	(segment
		(start 96.011338 131.33106)
		(end 95.990202 131.338456)
		(width 0.1)
		(layer "In2.Cu")
		(net 194)
	)
	(segment
		(start 95.936098 131.450805)
		(end 95.943494 131.471941)
		(width 0.1)
		(layer "In2.Cu")
		(net 194)
	)
	(segment
		(start 95.955407 131.490901)
		(end 95.971242 131.506736)
		(width 0.1)
		(layer "In2.Cu")
		(net 194)
	)
	(segment
		(start 96.291986 131.726153)
		(end 96.27069 131.728553)
		(width 0.1)
		(layer "In2.Cu")
		(net 194)
	)
	(segment
		(start 95.990202 131.918649)
		(end 96.011338 131.926045)
		(width 0.1)
		(layer "In2.Cu")
		(net 194)
	)
	(segment
		(start 96.330358 131.707674)
		(end 96.312213 131.719075)
		(width 0.1)
		(layer "In2.Cu")
		(net 194)
	)
	(segment
		(start 96.36399 130.454149)
		(end 96.356912 130.474376)
		(width 0.1)
		(layer "In2.Cu")
		(net 194)
	)
	(segment
		(start 96.033591 130.528553)
		(end 96.011338 130.53106)
		(width 0.1)
		(layer "In2.Cu")
		(net 194)
	)
	(segment
		(start 95.936098 132.2063)
		(end 95.933591 132.228553)
		(width 0.1)
		(layer "In2.Cu")
		(net 194)
	)
	(segment
		(start 95.955407 131.366204)
		(end 95.943494 131.385164)
		(width 0.1)
		(layer "In2.Cu")
		(net 194)
	)
	(segment
		(start 96.345511 131.692521)
		(end 96.330358 131.707674)
		(width 0.1)
		(layer "In2.Cu")
		(net 194)
	)
	(segment
		(start 96.27069 131.128553)
		(end 96.291986 131.130952)
		(width 0.1)
		(layer "In2.Cu")
		(net 194)
	)
	(segment
		(start 95.943494 130.671941)
		(end 95.955407 130.690901)
		(width 0.1)
		(layer "In2.Cu")
		(net 194)
	)
	(segment
		(start 96.011338 130.726045)
		(end 96.033591 130.728553)
		(width 0.1)
		(layer "In2.Cu")
		(net 194)
	)
	(segment
		(start 96.011338 132.53106)
		(end 95.990202 132.538456)
		(width 0.1)
		(layer "In2.Cu")
		(net 194)
	)
	(segment
		(start 95.955407 132.290901)
		(end 95.971242 132.306736)
		(width 0.1)
		(layer "In2.Cu")
		(net 194)
	)
	(segment
		(start 95.990202 130.718649)
		(end 96.011338 130.726045)
		(width 0.1)
		(layer "In2.Cu")
		(net 194)
	)
	(segment
		(start 96.366389 130.832854)
		(end 96.36399 130.854149)
		(width 0.1)
		(layer "In2.Cu")
		(net 194)
	)
	(segment
		(start 95.971242 130.950369)
		(end 95.955407 130.966204)
		(width 0.1)
		(layer "In2.Cu")
		(net 194)
	)
	(segment
		(start 96.345511 132.892521)
		(end 96.330358 132.907674)
		(width 0.1)
		(layer "In2.Cu")
		(net 194)
	)
	(segment
		(start 96.366389 132.432854)
		(end 96.36399 132.454149)
		(width 0.1)
		(layer "In2.Cu")
		(net 194)
	)
	(segment
		(start 96.27069 132.728553)
		(end 96.291986 132.730952)
		(width 0.1)
		(layer "In2.Cu")
		(net 194)
	)
	(segment
		(start 96.312213 132.119075)
		(end 96.291986 132.126153)
		(width 0.1)
		(layer "In2.Cu")
		(net 194)
	)
	(segment
		(start 96.011338 130.326045)
		(end 96.033591 130.328553)
		(width 0.1)
		(layer "In2.Cu")
		(net 194)
	)
	(segment
		(start 95.943494 130.185164)
		(end 95.936098 130.2063)
		(width 0.1)
		(layer "In2.Cu")
		(net 194)
	)
	(segment
		(start 95.943494 131.471941)
		(end 95.955407 131.490901)
		(width 0.1)
		(layer "In2.Cu")
		(net 194)
	)
	(segment
		(start 96.291986 130.526153)
		(end 96.27069 130.528553)
		(width 0.1)
		(layer "In2.Cu")
		(net 194)
	)
	(segment
		(start 90.545 82.31)
		(end 91.545 82.31)
		(width 0.25)
		(layer "F.Cu")
		(net 195)
	)
	(segment
		(start 87.67 82.275)
		(end 89.51 82.275)
		(width 0.25)
		(layer "F.Cu")
		(net 195)
	)
	(segment
		(start 89.51 82.275)
		(end 89.545 82.31)
		(width 0.25)
		(layer "F.Cu")
		(net 195)
	)
	(segment
		(start 89.545 82.31)
		(end 90.545 82.31)
		(width 0.25)
		(layer "F.Cu")
		(net 195)
	)
	(segment
		(start 89.555 89.72)
		(end 90.555 89.72)
		(width 0.25)
		(layer "F.Cu")
		(net 196)
	)
	(segment
		(start 89.52 89.685)
		(end 89.555 89.72)
		(width 0.25)
		(layer "F.Cu")
		(net 196)
	)
	(segment
		(start 87.68 89.685)
		(end 89.52 89.685)
		(width 0.25)
		(layer "F.Cu")
		(net 196)
	)
	(segment
		(start 90.555 89.72)
		(end 91.555 89.72)
		(width 0.25)
		(layer "F.Cu")
		(net 196)
	)
	(segment
		(start 137.85 90.8875)
		(end 137.85 85.45)
		(width 0.1)
		(layer "F.Cu")
		(net 197)
	)
	(segment
		(start 139 85.05)
		(end 139 83.515)
		(width 0.1)
		(layer "F.Cu")
		(net 197)
	)
	(segment
		(start 138.25 85.05)
		(end 139 85.05)
		(width 0.1)
		(layer "F.Cu")
		(net 197)
	)
	(segment
		(start 139 83.515)
		(end 139.015 83.5)
		(width 0.1)
		(layer "F.Cu")
		(net 197)
	)
	(segment
		(start 137.85 85.45)
		(end 138.25 85.05)
		(width 0.1)
		(layer "F.Cu")
		(net 197)
	)
	(segment
		(start 137.35 90.8875)
		(end 137.45 90.7875)
		(width 0.1)
		(layer "F.Cu")
		(net 198)
	)
	(segment
		(start 137.45 87.5)
		(end 136.8 86.85)
		(width 0.1)
		(layer "F.Cu")
		(net 198)
	)
	(segment
		(start 136.65 86.8)
		(end 136.7 86.85)
		(width 0.1)
		(layer "F.Cu")
		(net 198)
	)
	(segment
		(start 137.45 90.7875)
		(end 137.45 87.5)
		(width 0.1)
		(layer "F.Cu")
		(net 198)
	)
	(segment
		(start 136.8 86.85)
		(end 136.7 86.85)
		(width 0.1)
		(layer "F.Cu")
		(net 198)
	)
	(segment
		(start 134.785 86.8)
		(end 136.65 86.8)
		(width 0.1)
		(layer "F.Cu")
		(net 198)
	)
	(segment
		(start 106.895 94.975)
		(end 107.11 95.19)
		(width 0.2)
		(layer "F.Cu")
		(net 199)
	)
	(segment
		(start 105.527149 94.975)
		(end 106.895 94.975)
		(width 0.2)
		(layer "F.Cu")
		(net 199)
	)
	(segment
		(start 111.88 96.18)
		(end 111.88 96.27)
		(width 0.2)
		(layer "F.Cu")
		(net 199)
	)
	(segment
		(start 107.11 95.19)
		(end 110.89 95.19)
		(width 0.2)
		(layer "F.Cu")
		(net 199)
	)
	(segment
		(start 110.89 95.19)
		(end 111.88 96.18)
		(width 0.2)
		(layer "F.Cu")
		(net 199)
	)
	(segment
		(start 140.264 129.014)
		(end 139.774 129.504)
		(width 0.15)
		(layer "F.Cu")
		(net 200)
	)
	(via
		(at 139.774 129.504)
		(size 0.5)
		(drill 0.2)
		(layers "F.Cu" "B.Cu")
		(net 200)
	)
	(segment
		(start 139.789 130.314)
		(end 139.789 129.519)
		(width 0.15)
		(layer "B.Cu")
		(net 200)
	)
	(segment
		(start 139.789 129.519)
		(end 139.774 129.504)
		(width 0.15)
		(layer "B.Cu")
		(net 200)
	)
	(segment
		(start 139.789 131.414)
		(end 139.789 130.314)
		(width 0.15)
		(layer "B.Cu")
		(net 200)
	)
	(segment
		(start 107.13 94.25)
		(end 107.63 94.25)
		(width 0.2)
		(layer "F.Cu")
		(net 201)
	)
	(segment
		(start 106.905 94.475)
		(end 107.13 94.25)
		(width 0.2)
		(layer "F.Cu")
		(net 201)
	)
	(segment
		(start 105.527149 94.475)
		(end 106.905 94.475)
		(width 0.2)
		(layer "F.Cu")
		(net 201)
	)
	(segment
		(start 108.65 93.695)
		(end 110.015 93.695)
		(width 0.2)
		(layer "F.Cu")
		(net 201)
	)
	(segment
		(start 108.08 94.25)
		(end 108.61 93.72)
		(width 0.2)
		(layer "F.Cu")
		(net 201)
	)
	(segment
		(start 107.63 94.25)
		(end 108.08 94.25)
		(width 0.2)
		(layer "F.Cu")
		(net 201)
	)
	(segment
		(start 110.78 86.47)
		(end 110.78 83.384)
		(width 0.2)
		(layer "B.Cu")
		(net 202)
	)
	(segment
		(start 110.78 83.384)
		(end 110.771 83.375)
		(width 0.2)
		(layer "B.Cu")
		(net 202)
	)
	(segment
		(start 111.78 82.21)
		(end 110.405 80.835)
		(width 0.2)
		(layer "B.Cu")
		(net 203)
	)
	(segment
		(start 110.405 80.835)
		(end 109.755 80.835)
		(width 0.2)
		(layer "B.Cu")
		(net 203)
	)
	(segment
		(start 111.78 86.455)
		(end 111.78 82.21)
		(width 0.2)
		(layer "B.Cu")
		(net 203)
	)
	(segment
		(start 97.55 86.505)
		(end 97.525 86.48)
		(width 0.2)
		(layer "B.Cu")
		(net 204)
	)
	(segment
		(start 97.525 86.48)
		(end 97.525 82.08)
		(width 0.2)
		(layer "B.Cu")
		(net 204)
	)
	(segment
		(start 97.525 82.08)
		(end 98.77 80.835)
		(width 0.2)
		(layer "B.Cu")
		(net 204)
	)
	(segment
		(start 98.77 80.835)
		(end 99.595 80.835)
		(width 0.2)
		(layer "B.Cu")
		(net 204)
	)
	(segment
		(start 78.485 71.905)
		(end 78.5 71.89)
		(width 0.2)
		(layer "F.Cu")
		(net 205)
	)
	(segment
		(start 78.485 73.705)
		(end 78.485 71.905)
		(width 0.2)
		(layer "F.Cu")
		(net 205)
	)
	(segment
		(start 98.57 86.52)
		(end 98.57 83.384)
		(width 0.2)
		(layer "B.Cu")
		(net 206)
	)
	(segment
		(start 98.57 83.384)
		(end 98.579 83.375)
		(width 0.2)
		(layer "B.Cu")
		(net 206)
	)
	(segment
		(start 77.149 91.899)
		(end 77.15 91.9)
		(width 0.15)
		(layer "F.Cu")
		(net 207)
	)
	(segment
		(start 76.469 91.899)
		(end 77.149 91.899)
		(width 0.15)
		(layer "F.Cu")
		(net 207)
	)
	(via
		(at 77.15 91.9)
		(size 0.5)
		(drill 0.2)
		(layers "F.Cu" "B.Cu")
		(net 207)
	)
	(segment
		(start 79.075 86.981)
		(end 78.5 87.556)
		(width 0.15)
		(layer "B.Cu")
		(net 207)
	)
	(segment
		(start 80.625 82.075)
		(end 79.675 82.075)
		(width 0.15)
		(layer "B.Cu")
		(net 207)
	)
	(segment
		(start 77.156 91.9)
		(end 77.15 91.9)
		(width 0.15)
		(layer "B.Cu")
		(net 207)
	)
	(segment
		(start 79.675 82.075)
		(end 79.075 82.675)
		(width 0.15)
		(layer "B.Cu")
		(net 207)
	)
	(segment
		(start 79.075 82.675)
		(end 79.075 86.981)
		(width 0.15)
		(layer "B.Cu")
		(net 207)
	)
	(segment
		(start 78.5 87.556)
		(end 78.5 90.556)
		(width 0.15)
		(layer "B.Cu")
		(net 207)
	)
	(segment
		(start 78.5 90.556)
		(end 77.156 91.9)
		(width 0.15)
		(layer "B.Cu")
		(net 207)
	)
	(segment
		(start 73.636 91.899)
		(end 73.635 91.9)
		(width 0.15)
		(layer "F.Cu")
		(net 208)
	)
	(segment
		(start 74.969 91.899)
		(end 73.636 91.899)
		(width 0.15)
		(layer "F.Cu")
		(net 208)
	)
	(segment
		(start 138.025 75.905)
		(end 138.025 74.68)
		(width 0.15)
		(layer "F.Cu")
		(net 209)
	)
	(segment
		(start 137.525 74.655)
		(end 137.525 75.905)
		(width 0.15)
		(layer "F.Cu")
		(net 210)
	)
	(segment
		(start 107.099 145.215)
		(end 107.074 145.19)
		(width 0.2)
		(layer "F.Cu")
		(net 211)
	)
	(segment
		(start 103.5125 160.775)
		(end 104.375 160.775)
		(width 0.15)
		(layer "F.Cu")
		(net 211)
	)
	(segment
		(start 104.8 162.9)
		(end 104.8 162.085)
		(width 0.2)
		(layer "F.Cu")
		(net 211)
	)
	(segment
		(start 104.8 162.085)
		(end 104.79 162.075)
		(width 0.2)
		(layer "F.Cu")
		(net 211)
	)
	(segment
		(start 100.975 144.775)
		(end 101.375 145.175)
		(width 0.1)
		(layer "F.Cu")
		(net 211)
	)
	(segment
		(start 107 145.085)
		(end 107 145.9)
		(width 0.2)
		(layer "F.Cu")
		(net 211)
	)
	(segment
		(start 106.8 146.1)
		(end 106.8 146.2)
		(width 0.2)
		(layer "F.Cu")
		(net 211)
	)
	(segment
		(start 98.6 153.5)
		(end 98.6 154.164)
		(width 0.2)
		(layer "F.Cu")
		(net 211)
	)
	(segment
		(start 97.775 150.375)
		(end 97.775 151.675)
		(width 0.1)
		(layer "F.Cu")
		(net 211)
	)
	(segment
		(start 108.1 145.215)
		(end 107.099 145.215)
		(width 0.2)
		(layer "F.Cu")
		(net 211)
	)
	(segment
		(start 101.375 145.175)
		(end 107.074 145.175)
		(width 0.1)
		(layer "F.Cu")
		(net 211)
	)
	(segment
		(start 107 145.9)
		(end 106.8 146.1)
		(width 0.2)
		(layer "F.Cu")
		(net 211)
	)
	(segment
		(start 98.6 152.5)
		(end 98.6 153.5)
		(width 0.1)
		(layer "F.Cu")
		(net 211)
	)
	(segment
		(start 97.775 151.675)
		(end 98.6 152.5)
		(width 0.1)
		(layer "F.Cu")
		(net 211)
	)
	(segment
		(start 104.79 161.19)
		(end 104.79 162.075)
		(width 0.15)
		(layer "F.Cu")
		(net 211)
	)
	(segment
		(start 98.6 154.164)
		(end 98.574 154.19)
		(width 0.2)
		(layer "F.Cu")
		(net 211)
	)
	(segment
		(start 104.375 160.775)
		(end 104.79 161.19)
		(width 0.15)
		(layer "F.Cu")
		(net 211)
	)
	(via blind
		(at 106.8 146.2)
		(size 0.5)
		(drill 0.2)
		(layers "F.Cu" "In5.Cu")
		(net 211)
	)
	(via blind
		(at 98.6 153.5)
		(size 0.5)
		(drill 0.2)
		(layers "F.Cu" "In5.Cu")
		(net 211)
	)
	(via blind
		(at 104.8 162.9)
		(size 0.5)
		(drill 0.2)
		(layers "F.Cu" "In5.Cu")
		(net 211)
	)
	(segment
		(start 99.4 154.2)
		(end 98.7 153.5)
		(width 0.2)
		(layer "In5.Cu")
		(net 211)
	)
	(segment
		(start 105.1 154.2)
		(end 102.5 154.2)
		(width 0.2)
		(layer "In5.Cu")
		(net 211)
	)
	(segment
		(start 106.8 146.2)
		(end 106.423999 146.576001)
		(width 0.2)
		(layer "In5.Cu")
		(net 211)
	)
	(segment
		(start 105.7 147.8)
		(end 105.7 153.6)
		(width 0.2)
		(layer "In5.Cu")
		(net 211)
	)
	(segment
		(start 102.5 154.2)
		(end 99.4 154.2)
		(width 0.2)
		(layer "In5.Cu")
		(net 211)
	)
	(segment
		(start 105.225001 156.625001)
		(end 105.225001 161.074999)
		(width 0.2)
		(layer "In5.Cu")
		(net 211)
	)
	(segment
		(start 98.7 153.5)
		(end 98.6 153.5)
		(width 0.2)
		(layer "In5.Cu")
		(net 211)
	)
	(segment
		(start 102.8 154.2)
		(end 105.225001 156.625001)
		(width 0.2)
		(layer "In5.Cu")
		(net 211)
	)
	(segment
		(start 102.5 154.2)
		(end 102.8 154.2)
		(width 0.2)
		(layer "In5.Cu")
		(net 211)
	)
	(segment
		(start 105.225001 161.074999)
		(end 104.8 161.5)
		(width 0.2)
		(layer "In5.Cu")
		(net 211)
	)
	(segment
		(start 106.423999 147.076001)
		(end 105.7 147.8)
		(width 0.2)
		(layer "In5.Cu")
		(net 211)
	)
	(segment
		(start 104.8 161.5)
		(end 104.8 162.9)
		(width 0.2)
		(layer "In5.Cu")
		(net 211)
	)
	(segment
		(start 106.423999 146.576001)
		(end 106.423999 147.076001)
		(width 0.2)
		(layer "In5.Cu")
		(net 211)
	)
	(segment
		(start 105.7 153.6)
		(end 105.1 154.2)
		(width 0.2)
		(layer "In5.Cu")
		(net 211)
	)
	(segment
		(start 126.395 70.5125)
		(end 126.395 73.676704)
		(width 0.16)
		(layer "F.Cu")
		(net 212)
	)
	(segment
		(start 131.195 84.8575)
		(end 134.945 88.6075)
		(width 0.16)
		(layer "F.Cu")
		(net 212)
	)
	(segment
		(start 126.225 65.342501)
		(end 126.395 65.512501)
		(width 0.16)
		(layer "F.Cu")
		(net 212)
	)
	(segment
		(start 131.195 78.476704)
		(end 131.195 84.8575)
		(width 0.16)
		(layer "F.Cu")
		(net 212)
	)
	(segment
		(start 126.395 68.167499)
		(end 126.395 65.512501)
		(width 0.16)
		(layer "F.Cu")
		(net 212)
	)
	(segment
		(start 126.225 64.33)
		(end 126.225 65.342501)
		(width 0.16)
		(layer "F.Cu")
		(net 212)
	)
	(segment
		(start 134.945 90.7925)
		(end 134.85 90.8875)
		(width 0.16)
		(layer "F.Cu")
		(net 212)
	)
	(segment
		(start 126.2 68.812501)
		(end 126.069999 68.942502)
		(width 0.16)
		(layer "F.Cu")
		(net 212)
	)
	(segment
		(start 126.2 68.362499)
		(end 126.395 68.167499)
		(width 0.16)
		(layer "F.Cu")
		(net 212)
	)
	(segment
		(start 134.945 88.6075)
		(end 134.945 90.7925)
		(width 0.16)
		(layer "F.Cu")
		(net 212)
	)
	(segment
		(start 126.069999 70.187499)
		(end 126.395 70.5125)
		(width 0.16)
		(layer "F.Cu")
		(net 212)
	)
	(segment
		(start 126.069999 68.942502)
		(end 126.069999 70.187499)
		(width 0.16)
		(layer "F.Cu")
		(net 212)
	)
	(segment
		(start 126.395 73.676704)
		(end 131.195 78.476704)
		(width 0.16)
		(layer "F.Cu")
		(net 212)
	)
	(segment
		(start 126.2 68.5875)
		(end 126.2 68.812501)
		(width 0.16)
		(layer "F.Cu")
		(net 212)
	)
	(segment
		(start 126.2 68.5875)
		(end 126.2 68.362499)
		(width 0.16)
		(layer "F.Cu")
		(net 212)
	)
	(segment
		(start 131.505011 78.348294)
		(end 131.505011 84.729091)
		(width 0.16)
		(layer "F.Cu")
		(net 213)
	)
	(segment
		(start 126.875 64.33)
		(end 126.875 65.342501)
		(width 0.16)
		(layer "F.Cu")
		(net 213)
	)
	(segment
		(start 135.255011 88.47909)
		(end 135.255011 90.355011)
		(width 0.16)
		(layer "F.Cu")
		(net 213)
	)
	(segment
		(start 131.505011 84.729091)
		(end 135.255011 88.47909)
		(width 0.16)
		(layer "F.Cu")
		(net 213)
	)
	(segment
		(start 127.030001 73.873284)
		(end 131.505011 78.348294)
		(width 0.16)
		(layer "F.Cu")
		(net 213)
	)
	(segment
		(start 126.9 68.8975)
		(end 127.030001 69.027501)
		(width 0.16)
		(layer "F.Cu")
		(net 213)
	)
	(segment
		(start 135.35 90.45)
		(end 135.35 90.8875)
		(width 0.16)
		(layer "F.Cu")
		(net 213)
	)
	(segment
		(start 135.255011 90.355011)
		(end 135.35 90.45)
		(width 0.16)
		(layer "F.Cu")
		(net 213)
	)
	(segment
		(start 126.875 65.342501)
		(end 126.705 65.512501)
		(width 0.16)
		(layer "F.Cu")
		(net 213)
	)
	(segment
		(start 126.705 68.167499)
		(end 126.705 65.512501)
		(width 0.16)
		(layer "F.Cu")
		(net 213)
	)
	(segment
		(start 126.9 68.362499)
		(end 126.705 68.167499)
		(width 0.16)
		(layer "F.Cu")
		(net 213)
	)
	(segment
		(start 126.9 68.5875)
		(end 126.9 68.8975)
		(width 0.16)
		(layer "F.Cu")
		(net 213)
	)
	(segment
		(start 126.9 68.5875)
		(end 126.9 68.362499)
		(width 0.16)
		(layer "F.Cu")
		(net 213)
	)
	(segment
		(start 127.030001 69.027501)
		(end 127.030001 73.873284)
		(width 0.16)
		(layer "F.Cu")
		(net 213)
	)
	(segment
		(start 77.409 89.867)
		(end 77.839 89.437)
		(width 0.15)
		(layer "F.Cu")
		(net 214)
	)
	(segment
		(start 76.469 89.867)
		(end 77.409 89.867)
		(width 0.15)
		(layer "F.Cu")
		(net 214)
	)
	(segment
		(start 77.839 89.437)
		(end 77.839 89.047)
		(width 0.15)
		(layer "F.Cu")
		(net 214)
	)
	(via
		(at 77.839 89.047)
		(size 0.5)
		(drill 0.2)
		(layers "F.Cu" "B.Cu")
		(net 214)
	)
	(segment
		(start 77.825 87.875)
		(end 77.825 89.033)
		(width 0.15)
		(layer "B.Cu")
		(net 214)
	)
	(segment
		(start 77.825 89.033)
		(end 77.839 89.047)
		(width 0.15)
		(layer "B.Cu")
		(net 214)
	)
	(segment
		(start 74.936 89.9)
		(end 74.969 89.867)
		(width 0.15)
		(layer "F.Cu")
		(net 215)
	)
	(segment
		(start 73.635 89.9)
		(end 74.936 89.9)
		(width 0.15)
		(layer "F.Cu")
		(net 215)
	)
	(segment
		(start 77.113 95.963)
		(end 77.15 96)
		(width 0.15)
		(layer "F.Cu")
		(net 216)
	)
	(segment
		(start 76.469 95.963)
		(end 77.113 95.963)
		(width 0.15)
		(layer "F.Cu")
		(net 216)
	)
	(via
		(at 77.15 96)
		(size 0.5)
		(drill 0.2)
		(layers "F.Cu" "B.Cu")
		(net 216)
	)
	(segment
		(start 80.182 96)
		(end 77.15 96)
		(width 0.15)
		(layer "B.Cu")
		(net 216)
	)
	(segment
		(start 80.525 96.343)
		(end 80.182 96)
		(width 0.15)
		(layer "B.Cu")
		(net 216)
	)
	(segment
		(start 80.525 96.675)
		(end 80.525 96.343)
		(width 0.15)
		(layer "B.Cu")
		(net 216)
	)
	(segment
		(start 73.635 95.963)
		(end 74.969 95.963)
		(width 0.15)
		(layer "F.Cu")
		(net 217)
	)
	(segment
		(start 76.538 94)
		(end 76.469 93.931)
		(width 0.15)
		(layer "F.Cu")
		(net 218)
	)
	(segment
		(start 77.15 94)
		(end 76.538 94)
		(width 0.15)
		(layer "F.Cu")
		(net 218)
	)
	(via
		(at 77.15 94)
		(size 0.5)
		(drill 0.2)
		(layers "F.Cu" "B.Cu")
		(net 218)
	)
	(segment
		(start 77.15 94)
		(end 79.176 94)
		(width 0.15)
		(layer "B.Cu")
		(net 218)
	)
	(segment
		(start 79.176 94)
		(end 80.625 92.551)
		(width 0.15)
		(layer "B.Cu")
		(net 218)
	)
	(segment
		(start 80.625 89.275)
		(end 80.625 92.551)
		(width 0.15)
		(layer "B.Cu")
		(net 218)
	)
	(segment
		(start 73.635 93.931)
		(end 74.969 93.931)
		(width 0.15)
		(layer "F.Cu")
		(net 219)
	)
	(segment
		(start 64.335 84.189999)
		(end 65.351999 84.189999)
		(width 0.15)
		(layer "F.Cu")
		(net 220)
	)
	(segment
		(start 65.351999 84.189999)
		(end 65.359 84.197)
		(width 0.15)
		(layer "F.Cu")
		(net 220)
	)
	(segment
		(start 96.775 120.165)
		(end 96.300021 120.639979)
		(width 0.15)
		(layer "F.Cu")
		(net 220)
	)
	(via
		(at 89.685875 158.514122)
		(size 0.5)
		(drill 0.2)
		(layers "F.Cu" "B.Cu")
		(net 220)
	)
	(via
		(at 65.359 84.197)
		(size 0.5)
		(drill 0.2)
		(layers "F.Cu" "B.Cu")
		(net 220)
	)
	(via
		(at 96.300021 120.665)
		(size 0.5)
		(drill 0.2)
		(layers "F.Cu" "B.Cu")
		(net 220)
	)
	(segment
		(start 71.833 84.447)
		(end 71.99 84.29)
		(width 0.15)
		(layer "B.Cu")
		(net 220)
	)
	(segment
		(start 83.01699 108.36699)
		(end 79.669 105.019)
		(width 0.15)
		(layer "B.Cu")
		(net 220)
	)
	(segment
		(start 72.322 84.447)
		(end 72.147 84.447)
		(width 0.15)
		(layer "B.Cu")
		(net 220)
	)
	(segment
		(start 71.99 84.379)
		(end 71.922 84.447)
		(width 0.15)
		(layer "B.Cu")
		(net 220)
	)
	(segment
		(start 87.35899 108.36699)
		(end 83.01699 108.36699)
		(width 0.15)
		(layer "B.Cu")
		(net 220)
	)
	(segment
		(start 71.697 84.447)
		(end 71.833 84.447)
		(width 0.15)
		(layer "B.Cu")
		(net 220)
	)
	(segment
		(start 95.78 120.144979)
		(end 95.78 119.43)
		(width 0.15)
		(layer "B.Cu")
		(net 220)
	)
	(segment
		(start 79.669 99.877)
		(end 78.299 98.507)
		(width 0.15)
		(layer "B.Cu")
		(net 220)
	)
	(segment
		(start 95.78 119.43)
		(end 94.74 118.39)
		(width 0.15)
		(layer "B.Cu")
		(net 220)
	)
	(segment
		(start 89.685875 158.514122)
		(end 90.514122 158.514122)
		(width 0.15)
		(layer "B.Cu")
		(net 220)
	)
	(segment
		(start 69.919 84.197)
		(end 70.169 84.447)
		(width 0.15)
		(layer "B.Cu")
		(net 220)
	)
	(segment
		(start 71.99 81.79)
		(end 71.99 84.29)
		(width 0.15)
		(layer "B.Cu")
		(net 220)
	)
	(segment
		(start 90.514122 158.514122)
		(end 90.875 158.875)
		(width 0.15)
		(layer "B.Cu")
		(net 220)
	)
	(segment
		(start 69.334 91.566)
		(end 69.462 91.438)
		(width 0.15)
		(layer "B.Cu")
		(net 220)
	)
	(segment
		(start 92.14 118.71)
		(end 92.14 119.07)
		(width 0.15)
		(layer "B.Cu")
		(net 220)
	)
	(segment
		(start 71.84899 87.40701)
		(end 72.55 86.706)
		(width 0.15)
		(layer "B.Cu")
		(net 220)
	)
	(segment
		(start 90.35 119.32)
		(end 89.26901 118.23901)
		(width 0.15)
		(layer "B.Cu")
		(net 220)
	)
	(segment
		(start 69.462 88.008568)
		(end 70.063558 87.40701)
		(width 0.15)
		(layer "B.Cu")
		(net 220)
	)
	(segment
		(start 70.152566 98.507)
		(end 68.472 96.826434)
		(width 0.15)
		(layer "B.Cu")
		(net 220)
	)
	(segment
		(start 65.359 84.197)
		(end 69.919 84.197)
		(width 0.15)
		(layer "B.Cu")
		(net 220)
	)
	(segment
		(start 94.74 118.39)
		(end 92.46 118.39)
		(width 0.15)
		(layer "B.Cu")
		(net 220)
	)
	(segment
		(start 69.462 91.438)
		(end 69.462 88.008568)
		(width 0.15)
		(layer "B.Cu")
		(net 220)
	)
	(segment
		(start 68.472 91.729916)
		(end 68.635916 91.566)
		(width 0.15)
		(layer "B.Cu")
		(net 220)
	)
	(segment
		(start 71.99 84.29)
		(end 71.99 84.379)
		(width 0.15)
		(layer "B.Cu")
		(net 220)
	)
	(segment
		(start 90.875 158.875)
		(end 91.49 158.875)
		(width 0.15)
		(layer "B.Cu")
		(net 220)
	)
	(segment
		(start 91.89 119.32)
		(end 90.35 119.32)
		(width 0.15)
		(layer "B.Cu")
		(net 220)
	)
	(segment
		(start 71.922 84.447)
		(end 72.322 84.447)
		(width 0.15)
		(layer "B.Cu")
		(net 220)
	)
	(segment
		(start 89.26901 110.27701)
		(end 87.35899 108.36699)
		(width 0.15)
		(layer "B.Cu")
		(net 220)
	)
	(segment
		(start 70.169 84.447)
		(end 71.403 84.447)
		(width 0.15)
		(layer "B.Cu")
		(net 220)
	)
	(segment
		(start 71.403 84.447)
		(end 71.697 84.447)
		(width 0.15)
		(layer "B.Cu")
		(net 220)
	)
	(segment
		(start 92.46 118.39)
		(end 92.14 118.71)
		(width 0.15)
		(layer "B.Cu")
		(net 220)
	)
	(segment
		(start 79.669 105.019)
		(end 79.669 99.877)
		(width 0.15)
		(layer "B.Cu")
		(net 220)
	)
	(segment
		(start 72.55 84.536)
		(end 72.461 84.447)
		(width 0.15)
		(layer "B.Cu")
		(net 220)
	)
	(segment
		(start 89.26901 118.23901)
		(end 89.26901 110.27701)
		(width 0.15)
		(layer "B.Cu")
		(net 220)
	)
	(segment
		(start 68.472 96.826434)
		(end 68.472 91.729916)
		(width 0.15)
		(layer "B.Cu")
		(net 220)
	)
	(segment
		(start 70.063558 87.40701)
		(end 71.84899 87.40701)
		(width 0.15)
		(layer "B.Cu")
		(net 220)
	)
	(segment
		(start 68.635916 91.566)
		(end 69.334 91.566)
		(width 0.15)
		(layer "B.Cu")
		(net 220)
	)
	(segment
		(start 96.300021 120.665)
		(end 95.78 120.144979)
		(width 0.15)
		(layer "B.Cu")
		(net 220)
	)
	(segment
		(start 72.461 84.447)
		(end 72.322 84.447)
		(width 0.15)
		(layer "B.Cu")
		(net 220)
	)
	(segment
		(start 71.697 84.447)
		(end 71.922 84.447)
		(width 0.15)
		(layer "B.Cu")
		(net 220)
	)
	(segment
		(start 72.55 86.706)
		(end 72.55 84.536)
		(width 0.15)
		(layer "B.Cu")
		(net 220)
	)
	(segment
		(start 78.299 98.507)
		(end 70.152566 98.507)
		(width 0.15)
		(layer "B.Cu")
		(net 220)
	)
	(segment
		(start 92.14 119.07)
		(end 91.89 119.32)
		(width 0.15)
		(layer "B.Cu")
		(net 220)
	)
	(segment
		(start 72.147 84.447)
		(end 71.99 84.29)
		(width 0.15)
		(layer "B.Cu")
		(net 220)
	)
	(segment
		(start 89.685875 158.514122)
		(end 89.332322 158.514122)
		(width 0.15)
		(layer "In5.Cu")
		(net 220)
	)
	(segment
		(start 89.332322 158.514122)
		(end 85.4503 154.6321)
		(width 0.15)
		(layer "In5.Cu")
		(net 220)
	)
	(segment
		(start 85.4503 154.6321)
		(end 85.4503 126.0697)
		(width 0.15)
		(layer "In5.Cu")
		(net 220)
	)
	(segment
		(start 90.870021 120.649979)
		(end 96.285 120.649979)
		(width 0.15)
		(layer "In5.Cu")
		(net 220)
	)
	(segment
		(start 96.285 120.649979)
		(end 96.300021 120.665)
		(width 0.15)
		(layer "In5.Cu")
		(net 220)
	)
	(segment
		(start 85.4503 126.0697)
		(end 90.870021 120.649979)
		(width 0.15)
		(layer "In5.Cu")
		(net 220)
	)
	(segment
		(start 90.800001 158.700001)
		(end 89.964214 157.864214)
		(width 0.15)
		(layer "F.Cu")
		(net 221)
	)
	(segment
		(start 81.49 159.94)
		(end 81.49 159.93)
		(width 0.15)
		(layer "F.Cu")
		(net 221)
	)
	(segment
		(start 78.325 98.825)
		(end 69.075 98.825)
		(width 0.15)
		(layer "F.Cu")
		(net 221)
	)
	(segment
		(start 102.775 119.175)
		(end 103.275 119.675)
		(width 0.15)
		(layer "F.Cu")
		(net 221)
	)
	(segment
		(start 82.455 158.965)
		(end 88.255 158.965)
		(width 0.15)
		(layer "F.Cu")
		(net 221)
	)
	(segment
		(start 65.825 90.335)
		(end 65.825 94.435)
		(width 0.15)
		(layer "F.Cu")
		(net 221)
	)
	(segment
		(start 65.0562 88.3342)
		(end 65.825 89.103)
		(width 0.15)
		(layer "F.Cu")
		(net 221)
	)
	(segment
		(start 65.825 95.575)
		(end 65.825 94.435)
		(width 0.15)
		(layer "F.Cu")
		(net 221)
	)
	(segment
		(start 79.45 99.95)
		(end 78.325 98.825)
		(width 0.15)
		(layer "F.Cu")
		(net 221)
	)
	(segment
		(start 79.525 106)
		(end 79.45 105.925)
		(width 0.15)
		(layer "F.Cu")
		(net 221)
	)
	(segment
		(start 64.335 88.3342)
		(end 65.0562 88.3342)
		(width 0.15)
		(layer "F.Cu")
		(net 221)
	)
	(segment
		(start 65.825 89.103)
		(end 65.825 90.335)
		(width 0.15)
		(layer "F.Cu")
		(net 221)
	)
	(segment
		(start 90.800001 159.479999)
		(end 90.800001 158.700001)
		(width 0.15)
		(layer "F.Cu")
		(net 221)
	)
	(segment
		(start 77.572 158.45122)
		(end 77.572 159.572)
		(width 0.15)
		(layer "F.Cu")
		(net 221)
	)
	(segment
		(start 79.45 105.925)
		(end 79.45 99.95)
		(width 0.15)
		(layer "F.Cu")
		(net 221)
	)
	(segment
		(start 77.572 159.572)
		(end 77.94 159.94)
		(width 0.15)
		(layer "F.Cu")
		(net 221)
	)
	(segment
		(start 77.94 159.94)
		(end 81.49 159.94)
		(width 0.15)
		(layer "F.Cu")
		(net 221)
	)
	(segment
		(start 89.23 159.94)
		(end 90.34 159.94)
		(width 0.15)
		(layer "F.Cu")
		(net 221)
	)
	(segment
		(start 69.075 98.825)
		(end 65.825 95.575)
		(width 0.15)
		(layer "F.Cu")
		(net 221)
	)
	(segment
		(start 89.964214 157.864214)
		(end 89.674817 157.864214)
		(width 0.15)
		(layer "F.Cu")
		(net 221)
	)
	(segment
		(start 90.34 159.94)
		(end 90.800001 159.479999)
		(width 0.15)
		(layer "F.Cu")
		(net 221)
	)
	(segment
		(start 81.49 159.93)
		(end 82.455 158.965)
		(width 0.15)
		(layer "F.Cu")
		(net 221)
	)
	(segment
		(start 88.255 158.965)
		(end 89.23 159.94)
		(width 0.15)
		(layer "F.Cu")
		(net 221)
	)
	(via
		(at 89.61 123.5)
		(size 0.5)
		(drill 0.2)
		(layers "F.Cu" "B.Cu")
		(net 221)
	)
	(via blind
		(at 103.275 119.675)
		(size 0.5)
		(drill 0.2)
		(layers "F.Cu" "In5.Cu")
		(net 221)
	)
	(via
		(at 79.525 106)
		(size 0.5)
		(drill 0.2)
		(layers "F.Cu" "B.Cu")
		(net 221)
	)
	(via
		(at 89.674817 157.864214)
		(size 0.5)
		(drill 0.2)
		(layers "F.Cu" "B.Cu")
		(net 221)
	)
	(segment
		(start 82.699666 108.925)
		(end 79.774666 106)
		(width 0.15)
		(layer "B.Cu")
		(net 221)
	)
	(segment
		(start 87 108.925)
		(end 82.699666 108.925)
		(width 0.15)
		(layer "B.Cu")
		(net 221)
	)
	(segment
		(start 89.61 123.5)
		(end 88.625 122.515)
		(width 0.15)
		(layer "B.Cu")
		(net 221)
	)
	(segment
		(start 91.49 157.875)
		(end 89.685603 157.875)
		(width 0.15)
		(layer "B.Cu")
		(net 221)
	)
	(segment
		(start 79.774666 106)
		(end 79.525 106)
		(width 0.15)
		(layer "B.Cu")
		(net 221)
	)
	(segment
		(start 88.625 122.515)
		(end 88.625 110.55)
		(width 0.15)
		(layer "B.Cu")
		(net 221)
	)
	(segment
		(start 88.625 110.55)
		(end 87 108.925)
		(width 0.15)
		(layer "B.Cu")
		(net 221)
	)
	(segment
		(start 89.685603 157.875)
		(end 89.674817 157.864214)
		(width 0.15)
		(layer "B.Cu")
		(net 221)
	)
	(segment
		(start 89.61 122.53)
		(end 90.965 121.175)
		(width 0.15)
		(layer "In5.Cu")
		(net 221)
	)
	(segment
		(start 90.965 121.175)
		(end 101.475 121.175)
		(width 0.15)
		(layer "In5.Cu")
		(net 221)
	)
	(segment
		(start 85.750311 153.939708)
		(end 89.674817 157.864214)
		(width 0.15)
		(layer "In5.Cu")
		(net 221)
	)
	(segment
		(start 101.750001 120.499999)
		(end 102.075 120.175)
		(width 0.15)
		(layer "In5.Cu")
		(net 221)
	)
	(segment
		(start 85.750311 127.419689)
		(end 85.750311 153.939708)
		(width 0.15)
		(layer "In5.Cu")
		(net 221)
	)
	(segment
		(start 89.61 123.5)
		(end 89.61 123.56)
		(width 0.15)
		(layer "In5.Cu")
		(net 221)
	)
	(segment
		(start 101.475 121.175)
		(end 101.750001 120.899999)
		(width 0.15)
		(layer "In5.Cu")
		(net 221)
	)
	(segment
		(start 89.61 123.5)
		(end 89.61 122.53)
		(width 0.15)
		(layer "In5.Cu")
		(net 221)
	)
	(segment
		(start 89.61 123.56)
		(end 85.750311 127.419689)
		(width 0.15)
		(layer "In5.Cu")
		(net 221)
	)
	(segment
		(start 101.750001 120.899999)
		(end 101.750001 120.499999)
		(width 0.15)
		(layer "In5.Cu")
		(net 221)
	)
	(segment
		(start 102.075 120.175)
		(end 102.775 120.175)
		(width 0.15)
		(layer "In5.Cu")
		(net 221)
	)
	(segment
		(start 102.775 120.175)
		(end 103.275 119.675)
		(width 0.15)
		(layer "In5.Cu")
		(net 221)
	)
	(segment
		(start 78.072 159.472)
		(end 78.19 159.59)
		(width 0.15)
		(layer "F.Cu")
		(net 222)
	)
	(segment
		(start 78.19 159.59)
		(end 81.46 159.59)
		(width 0.15)
		(layer "F.Cu")
		(net 222)
	)
	(segment
		(start 88.615 158.715)
		(end 89.075 159.175)
		(width 0.15)
		(layer "F.Cu")
		(net 222)
	)
	(segment
		(start 65.384099 86.262099)
		(end 65.419 86.297)
		(width 0.15)
		(layer "F.Cu")
		(net 222)
	)
	(segment
		(start 89.075 159.175)
		(end 90.375 159.175)
		(width 0.15)
		(layer "F.Cu")
		(net 222)
	)
	(segment
		(start 82.335 158.715)
		(end 88.615 158.715)
		(width 0.15)
		(layer "F.Cu")
		(net 222)
	)
	(segment
		(start 64.335 86.262099)
		(end 65.384099 86.262099)
		(width 0.15)
		(layer "F.Cu")
		(net 222)
	)
	(segment
		(start 78.072 158.45122)
		(end 78.072 159.472)
		(width 0.15)
		(layer "F.Cu")
		(net 222)
	)
	(segment
		(start 106.775 119.175)
		(end 107.275 119.675)
		(width 0.15)
		(layer "F.Cu")
		(net 222)
	)
	(segment
		(start 81.46 159.59)
		(end 82.335 158.715)
		(width 0.15)
		(layer "F.Cu")
		(net 222)
	)
	(via
		(at 90.375 159.175)
		(size 0.5)
		(drill 0.2)
		(layers "F.Cu" "B.Cu")
		(net 222)
	)
	(via
		(at 65.419 86.297)
		(size 0.5)
		(drill 0.2)
		(layers "F.Cu" "B.Cu")
		(net 222)
	)
	(via blind
		(at 107.275 119.675)
		(size 0.5)
		(drill 0.2)
		(layers "F.Cu" "In5.Cu")
		(net 222)
	)
	(via
		(at 90.24 123.68)
		(size 0.5)
		(drill 0.2)
		(layers "F.Cu" "B.Cu")
		(net 222)
	)
	(segment
		(start 65.419 86.297)
		(end 69.059 86.297)
		(width 0.15)
		(layer "B.Cu")
		(net 222)
	)
	(segment
		(start 71.579 87.157)
		(end 71.99 86.746)
		(width 0.15)
		(layer "B.Cu")
		(net 222)
	)
	(segment
		(start 89.019 122.244)
		(end 89.019 110.397)
		(width 0.15)
		(layer "B.Cu")
		(net 222)
	)
	(segment
		(start 67.049 88.837)
		(end 67.759 88.127)
		(width 0.15)
		(layer "B.Cu")
		(net 222)
	)
	(segment
		(start 89.019 110.397)
		(end 87.239001 108.617001)
		(width 0.15)
		(layer "B.Cu")
		(net 222)
	)
	(segment
		(start 90.24 123.465)
		(end 89.019 122.244)
		(width 0.15)
		(layer "B.Cu")
		(net 222)
	)
	(segment
		(start 68.990002 88.127)
		(end 69.919 87.198002)
		(width 0.15)
		(layer "B.Cu")
		(net 222)
	)
	(segment
		(start 82.817001 108.617001)
		(end 79.418989 105.218989)
		(width 0.15)
		(layer "B.Cu")
		(net 222)
	)
	(segment
		(start 91.075 159.875)
		(end 91.49 159.875)
		(width 0.15)
		(layer "B.Cu")
		(net 222)
	)
	(segment
		(start 90.24 123.68)
		(end 90.24 123.465)
		(width 0.15)
		(layer "B.Cu")
		(net 222)
	)
	(segment
		(start 79.418989 105.218989)
		(end 79.418989 99.986989)
		(width 0.15)
		(layer "B.Cu")
		(net 222)
	)
	(segment
		(start 70.049 98.757)
		(end 67.049 95.757)
		(width 0.15)
		(layer "B.Cu")
		(net 222)
	)
	(segment
		(start 79.418989 99.986989)
		(end 78.189 98.757)
		(width 0.15)
		(layer "B.Cu")
		(net 222)
	)
	(segment
		(start 90.375 159.175)
		(end 91.075 159.875)
		(width 0.15)
		(layer "B.Cu")
		(net 222)
	)
	(segment
		(start 67.049 95.757)
		(end 67.049 88.837)
		(width 0.15)
		(layer "B.Cu")
		(net 222)
	)
	(segment
		(start 69.059 86.297)
		(end 69.919 87.157)
		(width 0.15)
		(layer "B.Cu")
		(net 222)
	)
	(segment
		(start 87.239001 108.617001)
		(end 82.817001 108.617001)
		(width 0.15)
		(layer "B.Cu")
		(net 222)
	)
	(segment
		(start 71.99 86.746)
		(end 71.99 85.54)
		(width 0.15)
		(layer "B.Cu")
		(net 222)
	)
	(segment
		(start 67.759 88.127)
		(end 68.990002 88.127)
		(width 0.15)
		(layer "B.Cu")
		(net 222)
	)
	(segment
		(start 69.919 87.157)
		(end 71.579 87.157)
		(width 0.15)
		(layer "B.Cu")
		(net 222)
	)
	(segment
		(start 69.919 87.198002)
		(end 69.919 87.157)
		(width 0.15)
		(layer "B.Cu")
		(net 222)
	)
	(segment
		(start 78.189 98.757)
		(end 70.049 98.757)
		(width 0.15)
		(layer "B.Cu")
		(net 222)
	)
	(segment
		(start 106.450001 121.249999)
		(end 107.025001 120.674999)
		(width 0.15)
		(layer "In5.Cu")
		(net 222)
	)
	(segment
		(start 86.050322 128.759678)
		(end 86.050322 153.536717)
		(width 0.15)
		(layer "In5.Cu")
		(net 222)
	)
	(segment
		(start 103.024989 122.125011)
		(end 103.900001 121.249999)
		(width 0.15)
		(layer "In5.Cu")
		(net 222)
	)
	(segment
		(start 107.025001 119.924999)
		(end 107.275 119.675)
		(width 0.15)
		(layer "In5.Cu")
		(net 222)
	)
	(segment
		(start 90.375 157.861395)
		(end 90.375 159.175)
		(width 0.15)
		(layer "In5.Cu")
		(net 222)
	)
	(segment
		(start 90.24 124.57)
		(end 86.050322 128.759678)
		(width 0.15)
		(layer "In5.Cu")
		(net 222)
	)
	(segment
		(start 90.24 123.68)
		(end 90.24 124.57)
		(width 0.15)
		(layer "In5.Cu")
		(net 222)
	)
	(segment
		(start 103.900001 121.249999)
		(end 106.450001 121.249999)
		(width 0.15)
		(layer "In5.Cu")
		(net 222)
	)
	(segment
		(start 91.794989 122.125011)
		(end 103.024989 122.125011)
		(width 0.15)
		(layer "In5.Cu")
		(net 222)
	)
	(segment
		(start 86.050322 153.536717)
		(end 90.375 157.861395)
		(width 0.15)
		(layer "In5.Cu")
		(net 222)
	)
	(segment
		(start 90.24 123.68)
		(end 91.794989 122.125011)
		(width 0.15)
		(layer "In5.Cu")
		(net 222)
	)
	(segment
		(start 107.025001 120.674999)
		(end 107.025001 119.924999)
		(width 0.15)
		(layer "In5.Cu")
		(net 222)
	)
	(segment
		(start 77.135 97.995)
		(end 76.469 97.995)
		(width 0.15)
		(layer "F.Cu")
		(net 223)
	)
	(segment
		(start 77.465 97.665)
		(end 77.135 97.995)
		(width 0.15)
		(layer "F.Cu")
		(net 223)
	)
	(via
		(at 77.465 97.665)
		(size 0.5)
		(drill 0.2)
		(layers "F.Cu" "B.Cu")
		(net 223)
	)
	(segment
		(start 80.525 103.303)
		(end 80.525 103.975)
		(width 0.15)
		(layer "B.Cu")
		(net 223)
	)
	(segment
		(start 80.089 98.937)
		(end 80.089 102.867)
		(width 0.15)
		(layer "B.Cu")
		(net 223)
	)
	(segment
		(start 78.817 97.665)
		(end 80.089 98.937)
		(width 0.15)
		(layer "B.Cu")
		(net 223)
	)
	(segment
		(start 77.465 97.665)
		(end 78.817 97.665)
		(width 0.15)
		(layer "B.Cu")
		(net 223)
	)
	(segment
		(start 80.089 102.867)
		(end 80.525 103.303)
		(width 0.15)
		(layer "B.Cu")
		(net 223)
	)
	(segment
		(start 73.635 97.995)
		(end 74.969 97.995)
		(width 0.15)
		(layer "F.Cu")
		(net 224)
	)
	(segment
		(start 68.815 86.265)
		(end 70.115 84.965)
		(width 0.1)
		(layer "F.Cu")
		(net 225)
	)
	(segment
		(start 70.115 84.965)
		(end 70.115 83.64)
		(width 0.1)
		(layer "F.Cu")
		(net 225)
	)
	(segment
		(start 68.216 86.265)
		(end 68.815 86.265)
		(width 0.1)
		(layer "F.Cu")
		(net 225)
	)
	(via
		(at 70.115 83.64)
		(size 0.5)
		(drill 0.2)
		(layers "F.Cu" "B.Cu")
		(net 225)
	)
	(segment
		(start 70.84 83.64)
		(end 71.04 83.44)
		(width 0.1)
		(layer "B.Cu")
		(net 225)
	)
	(segment
		(start 70.115 83.64)
		(end 70.84 83.64)
		(width 0.1)
		(layer "B.Cu")
		(net 225)
	)
	(segment
		(start 81.75 62.84)
		(end 81.75 61.7)
		(width 0.15)
		(layer "F.Cu")
		(net 226)
	)
	(segment
		(start 73.925 62.33)
		(end 73.925 63.54)
		(width 0.15)
		(layer "F.Cu")
		(net 227)
	)
	(segment
		(start 77.432 61.88)
		(end 74.375 61.88)
		(width 0.15)
		(layer "F.Cu")
		(net 227)
	)
	(segment
		(start 77.725 62.173)
		(end 77.432 61.88)
		(width 0.15)
		(layer "F.Cu")
		(net 227)
	)
	(segment
		(start 78.5 70.92)
		(end 78.5 70.205)
		(width 0.2)
		(layer "F.Cu")
		(net 227)
	)
	(segment
		(start 77.725 62.825)
		(end 77.725 62.173)
		(width 0.15)
		(layer "F.Cu")
		(net 227)
	)
	(segment
		(start 74.375 61.88)
		(end 73.925 62.33)
		(width 0.15)
		(layer "F.Cu")
		(net 227)
	)
	(segment
		(start 77.725 62.825)
		(end 76.83 62.825)
		(width 0.2)
		(layer "F.Cu")
		(net 227)
	)
	(via
		(at 76.825 62.83)
		(size 0.5)
		(drill 0.2)
		(layers "F.Cu" "B.Cu")
		(net 227)
	)
	(via
		(at 78.5 70.205)
		(size 0.5)
		(drill 0.2)
		(layers "F.Cu" "B.Cu")
		(net 227)
	)
	(segment
		(start 76.424999 66.024999)
		(end 76.424999 63.230001)
		(width 0.15)
		(layer "B.Cu")
		(net 227)
	)
	(segment
		(start 78.5 68.1)
		(end 76.424999 66.024999)
		(width 0.15)
		(layer "B.Cu")
		(net 227)
	)
	(segment
		(start 76.424999 63.230001)
		(end 76.825 62.83)
		(width 0.15)
		(layer "B.Cu")
		(net 227)
	)
	(segment
		(start 78.5 70.205)
		(end 78.5 68.1)
		(width 0.15)
		(layer "B.Cu")
		(net 227)
	)
	(segment
		(start 83.065 63.19)
		(end 84.115 62.14)
		(width 0.15)
		(layer "F.Cu")
		(net 228)
	)
	(segment
		(start 83.065 63.965)
		(end 83.065 63.19)
		(width 0.15)
		(layer "F.Cu")
		(net 228)
	)
	(segment
		(start 81.775 64.415)
		(end 82.615 64.415)
		(width 0.15)
		(layer "F.Cu")
		(net 228)
	)
	(segment
		(start 81.75 64.44)
		(end 81.775 64.415)
		(width 0.15)
		(layer "F.Cu")
		(net 228)
	)
	(segment
		(start 82.615 64.415)
		(end 83.065 63.965)
		(width 0.15)
		(layer "F.Cu")
		(net 228)
	)
	(segment
		(start 126.775 74.975)
		(end 130.425 78.625)
		(width 0.2)
		(layer "F.Cu")
		(net 240)
	)
	(segment
		(start 130.425 78.625)
		(end 130.425 88.225)
		(width 0.2)
		(layer "F.Cu")
		(net 240)
	)
	(segment
		(start 127.525 64.33)
		(end 127.525 73.525)
		(width 0.2)
		(layer "F.Cu")
		(net 240)
	)
	(segment
		(start 127.525 73.525)
		(end 127.875 73.875)
		(width 0.2)
		(layer "F.Cu")
		(net 240)
	)
	(via
		(at 126.775 74.975)
		(size 0.5)
		(drill 0.2)
		(layers "F.Cu" "B.Cu")
		(net 240)
	)
	(via
		(at 127.875 73.875)
		(size 0.5)
		(drill 0.2)
		(layers "F.Cu" "B.Cu")
		(net 240)
	)
	(segment
		(start 127.875 73.875)
		(end 126.775 74.975)
		(width 0.2)
		(layer "B.Cu")
		(net 240)
	)
	(segment
		(start 72.165 169.815)
		(end 74.215 169.815)
		(width 0.15)
		(layer "F.Cu")
		(net 243)
	)
	(segment
		(start 71.415 168.35)
		(end 71.415 169.065)
		(width 0.15)
		(layer "F.Cu")
		(net 243)
	)
	(segment
		(start 71.415 169.065)
		(end 72.165 169.815)
		(width 0.15)
		(layer "F.Cu")
		(net 243)
	)
	(segment
		(start 75.69 171.29)
		(end 75.69 177.345)
		(width 0.15)
		(layer "F.Cu")
		(net 243)
	)
	(segment
		(start 74.215 169.815)
		(end 75.69 171.29)
		(width 0.15)
		(layer "F.Cu")
		(net 243)
	)
	(segment
		(start 91.475 160.86)
		(end 88.8 160.86)
		(width 0.15)
		(layer "B.Cu")
		(net 244)
	)
	(segment
		(start 82.645 174.835)
		(end 82.645 175.755)
		(width 0.15)
		(layer "B.Cu")
		(net 244)
	)
	(segment
		(start 82.282264 167.377736)
		(end 82.282264 174.472264)
		(width 0.15)
		(layer "B.Cu")
		(net 244)
	)
	(segment
		(start 88.8 160.86)
		(end 82.282264 167.377736)
		(width 0.15)
		(layer "B.Cu")
		(net 244)
	)
	(segment
		(start 82.282264 174.472264)
		(end 82.645 174.835)
		(width 0.15)
		(layer "B.Cu")
		(net 244)
	)
	(segment
		(start 82.645 175.755)
		(end 82.286978 176.113022)
		(width 0.15)
		(layer "B.Cu")
		(net 244)
	)
	(segment
		(start 82.286978 176.113022)
		(end 82.286978 176.223022)
		(width 0.15)
		(layer "B.Cu")
		(net 244)
	)
	(segment
		(start 82.286978 176.223022)
		(end 82.29 177.345)
		(width 0.15)
		(layer "B.Cu")
		(net 244)
	)
	(segment
		(start 127.39 177.345)
		(end 127.39 175.145)
		(width 0.15)
		(layer "B.Cu")
		(net 245)
	)
	(segment
		(start 118.73 141.675)
		(end 117.98 141.675)
		(width 0.15)
		(layer "B.Cu")
		(net 245)
	)
	(segment
		(start 122.324999 145.269999)
		(end 118.73 141.675)
		(width 0.15)
		(layer "B.Cu")
		(net 245)
	)
	(segment
		(start 122.324999 170.079999)
		(end 122.324999 145.269999)
		(width 0.15)
		(layer "B.Cu")
		(net 245)
	)
	(segment
		(start 127.39 175.145)
		(end 122.324999 170.079999)
		(width 0.15)
		(layer "B.Cu")
		(net 245)
	)
	(segment
		(start 126.79 174.898566)
		(end 122.074989 170.183556)
		(width 0.15)
		(layer "B.Cu")
		(net 246)
	)
	(segment
		(start 118.87 142.675)
		(end 117.98 142.675)
		(width 0.15)
		(layer "B.Cu")
		(net 246)
	)
	(segment
		(start 122.074989 170.183556)
		(end 122.074989 145.879989)
		(width 0.15)
		(layer "B.Cu")
		(net 246)
	)
	(segment
		(start 122.074989 145.879989)
		(end 118.87 142.675)
		(width 0.15)
		(layer "B.Cu")
		(net 246)
	)
	(segment
		(start 126.79 177.345)
		(end 126.79 174.898566)
		(width 0.15)
		(layer "B.Cu")
		(net 246)
	)
	(segment
		(start 121.72 146.755)
		(end 118.64 143.675)
		(width 0.15)
		(layer "B.Cu")
		(net 247)
	)
	(segment
		(start 126.19 174.652133)
		(end 121.72 170.182133)
		(width 0.15)
		(layer "B.Cu")
		(net 247)
	)
	(segment
		(start 121.72 170.182133)
		(end 121.72 146.755)
		(width 0.15)
		(layer "B.Cu")
		(net 247)
	)
	(segment
		(start 126.19 177.345)
		(end 126.19 174.652133)
		(width 0.15)
		(layer "B.Cu")
		(net 247)
	)
	(segment
		(start 118.64 143.675)
		(end 117.98 143.675)
		(width 0.15)
		(layer "B.Cu")
		(net 247)
	)
	(segment
		(start 119.04 146.675)
		(end 117.98 146.675)
		(width 0.15)
		(layer "B.Cu")
		(net 248)
	)
	(segment
		(start 124.39 177.345)
		(end 124.39 174.098567)
		(width 0.15)
		(layer "B.Cu")
		(net 248)
	)
	(segment
		(start 124.39 174.098567)
		(end 120.93999 170.648557)
		(width 0.15)
		(layer "B.Cu")
		(net 248)
	)
	(segment
		(start 120.93999 170.648557)
		(end 120.93999 148.57499)
		(width 0.15)
		(layer "B.Cu")
		(net 248)
	)
	(segment
		(start 120.93999 148.57499)
		(end 119.04 146.675)
		(width 0.15)
		(layer "B.Cu")
		(net 248)
	)
	(segment
		(start 124.99 177.345)
		(end 124.99 174.295)
		(width 0.15)
		(layer "B.Cu")
		(net 249)
	)
	(segment
		(start 121.19 170.495)
		(end 121.19 147.945)
		(width 0.15)
		(layer "B.Cu")
		(net 249)
	)
	(segment
		(start 121.19 147.945)
		(end 118.92 145.675)
		(width 0.15)
		(layer "B.Cu")
		(net 249)
	)
	(segment
		(start 118.92 145.675)
		(end 118.275 145.675)
		(width 0.15)
		(layer "B.Cu")
		(net 249)
	)
	(segment
		(start 124.99 174.295)
		(end 121.19 170.495)
		(width 0.15)
		(layer "B.Cu")
		(net 249)
	)
	(segment
		(start 118.275 145.675)
		(end 117.98 145.675)
		(width 0.15)
		(layer "B.Cu")
		(net 249)
	)
	(segment
		(start 121.44 170.325349)
		(end 121.44 147.525)
		(width 0.15)
		(layer "B.Cu")
		(net 250)
	)
	(segment
		(start 121.44 147.525)
		(end 118.59 144.675)
		(width 0.15)
		(layer "B.Cu")
		(net 250)
	)
	(segment
		(start 125.59 177.345)
		(end 125.59 174.475349)
		(width 0.15)
		(layer "B.Cu")
		(net 250)
	)
	(segment
		(start 125.59 174.475349)
		(end 121.44 170.325349)
		(width 0.15)
		(layer "B.Cu")
		(net 250)
	)
	(segment
		(start 118.59 144.675)
		(end 117.98 144.675)
		(width 0.15)
		(layer "B.Cu")
		(net 250)
	)
	(segment
		(start 123.79 177.345)
		(end 123.79 173.852133)
		(width 0.15)
		(layer "B.Cu")
		(net 251)
	)
	(segment
		(start 119.01 147.675)
		(end 117.98 147.675)
		(width 0.15)
		(layer "B.Cu")
		(net 251)
	)
	(segment
		(start 123.79 173.852133)
		(end 120.68998 170.752114)
		(width 0.15)
		(layer "B.Cu")
		(net 251)
	)
	(segment
		(start 120.68998 149.35498)
		(end 119.01 147.675)
		(width 0.15)
		(layer "B.Cu")
		(net 251)
	)
	(segment
		(start 120.68998 170.752114)
		(end 120.68998 149.35498)
		(width 0.15)
		(layer "B.Cu")
		(net 251)
	)
	(segment
		(start 118.99 148.675)
		(end 117.98 148.675)
		(width 0.15)
		(layer "B.Cu")
		(net 252)
	)
	(segment
		(start 120.43997 150.12497)
		(end 118.99 148.675)
		(width 0.15)
		(layer "B.Cu")
		(net 252)
	)
	(segment
		(start 123.19 173.605699)
		(end 120.43997 170.855671)
		(width 0.15)
		(layer "B.Cu")
		(net 252)
	)
	(segment
		(start 120.43997 170.855671)
		(end 120.43997 150.12497)
		(width 0.15)
		(layer "B.Cu")
		(net 252)
	)
	(segment
		(start 123.19 177.345)
		(end 123.19 173.605699)
		(width 0.15)
		(layer "B.Cu")
		(net 252)
	)
	(segment
		(start 118.93 149.675)
		(end 117.98 149.675)
		(width 0.15)
		(layer "B.Cu")
		(net 253)
	)
	(segment
		(start 120.18996 150.93496)
		(end 118.93 149.675)
		(width 0.15)
		(layer "B.Cu")
		(net 253)
	)
	(segment
		(start 122.59 177.345)
		(end 122.59 173.359266)
		(width 0.15)
		(layer "B.Cu")
		(net 253)
	)
	(segment
		(start 120.18996 170.959228)
		(end 120.18996 150.93496)
		(width 0.15)
		(layer "B.Cu")
		(net 253)
	)
	(segment
		(start 122.59 173.359266)
		(end 120.18996 170.959228)
		(width 0.15)
		(layer "B.Cu")
		(net 253)
	)
	(segment
		(start 119.93995 171.09495)
		(end 119.93995 151.82495)
		(width 0.15)
		(layer "B.Cu")
		(net 254)
	)
	(segment
		(start 118.79 150.675)
		(end 118.03 150.675)
		(width 0.15)
		(layer "B.Cu")
		(net 254)
	)
	(segment
		(start 119.93995 151.82495)
		(end 118.79 150.675)
		(width 0.15)
		(layer "B.Cu")
		(net 254)
	)
	(segment
		(start 121.99 173.145)
		(end 119.93995 171.09495)
		(width 0.15)
		(layer "B.Cu")
		(net 254)
	)
	(segment
		(start 121.99 177.345)
		(end 121.99 173.145)
		(width 0.15)
		(layer "B.Cu")
		(net 254)
	)
	(segment
		(start 118.66 151.675)
		(end 118.03 151.675)
		(width 0.15)
		(layer "B.Cu")
		(net 255)
	)
	(segment
		(start 119.68994 171.198507)
		(end 119.68994 152.70494)
		(width 0.15)
		(layer "B.Cu")
		(net 255)
	)
	(segment
		(start 119.68994 152.70494)
		(end 118.66 151.675)
		(width 0.15)
		(layer "B.Cu")
		(net 255)
	)
	(segment
		(start 121.39 177.345)
		(end 121.39 172.898567)
		(width 0.15)
		(layer "B.Cu")
		(net 255)
	)
	(segment
		(start 121.39 172.898567)
		(end 119.68994 171.198507)
		(width 0.15)
		(layer "B.Cu")
		(net 255)
	)
	(segment
		(start 119.43993 153.41993)
		(end 118.685 152.665)
		(width 0.15)
		(layer "B.Cu")
		(net 256)
	)
	(segment
		(start 118.685 152.665)
		(end 118.025 152.665)
		(width 0.15)
		(layer "B.Cu")
		(net 256)
	)
	(segment
		(start 120.79 177.345)
		(end 120.79 172.745)
		(width 0.15)
		(layer "B.Cu")
		(net 256)
	)
	(segment
		(start 120.79 172.745)
		(end 119.43993 171.39493)
		(width 0.15)
		(layer "B.Cu")
		(net 256)
	)
	(segment
		(start 119.43993 171.39493)
		(end 119.43993 153.41993)
		(width 0.15)
		(layer "B.Cu")
		(net 256)
	)
	(segment
		(start 119.14 171.495)
		(end 119.14 153.98)
		(width 0.15)
		(layer "B.Cu")
		(net 257)
	)
	(segment
		(start 118.825 153.665)
		(end 118.025 153.665)
		(width 0.15)
		(layer "B.Cu")
		(net 257)
	)
	(segment
		(start 120.19 172.545)
		(end 119.14 171.495)
		(width 0.15)
		(layer "B.Cu")
		(net 257)
	)
	(segment
		(start 119.14 153.98)
		(end 118.825 153.665)
		(width 0.15)
		(layer "B.Cu")
		(net 257)
	)
	(segment
		(start 120.19 177.16)
		(end 120.19 172.545)
		(width 0.15)
		(layer "B.Cu")
		(net 257)
	)
	(segment
		(start 119.605 177.345)
		(end 119.605 173.005)
		(width 0.15)
		(layer "B.Cu")
		(net 258)
	)
	(segment
		(start 118.44 154.69)
		(end 118.065 154.69)
		(width 0.15)
		(layer "B.Cu")
		(net 258)
	)
	(segment
		(start 119.605 173.005)
		(end 118.865 172.265)
		(width 0.15)
		(layer "B.Cu")
		(net 258)
	)
	(segment
		(start 118.865 155.115)
		(end 118.44 154.69)
		(width 0.15)
		(layer "B.Cu")
		(net 258)
	)
	(segment
		(start 118.865 172.265)
		(end 118.865 155.115)
		(width 0.15)
		(layer "B.Cu")
		(net 258)
	)
	(segment
		(start 106.775 122.175)
		(end 107.275 122.675)
		(width 0.15)
		(layer "F.Cu")
		(net 259)
	)
	(via blind
		(at 107.275 122.675)
		(size 0.5)
		(drill 0.2)
		(layers "F.Cu" "In2.Cu")
		(net 259)
	)
	(via
		(at 117.01 121.59)
		(size 0.5)
		(drill 0.2)
		(layers "F.Cu" "B.Cu")
		(net 259)
	)
	(segment
		(start 116.225 122.375)
		(end 117.01 121.59)
		(width 0.15)
		(layer "In2.Cu")
		(net 259)
	)
	(segment
		(start 107.974989 121.975011)
		(end 110.475011 121.975011)
		(width 0.15)
		(layer "In2.Cu")
		(net 259)
	)
	(segment
		(start 110.875 122.375)
		(end 116.225 122.375)
		(width 0.15)
		(layer "In2.Cu")
		(net 259)
	)
	(segment
		(start 110.475011 121.975011)
		(end 110.875 122.375)
		(width 0.15)
		(layer "In2.Cu")
		(net 259)
	)
	(segment
		(start 107.275 122.675)
		(end 107.974989 121.975011)
		(width 0.15)
		(layer "In2.Cu")
		(net 259)
	)
	(segment
		(start 141.47 109.68)
		(end 144.52 109.68)
		(width 0.15)
		(layer "In5.Cu")
		(net 259)
	)
	(segment
		(start 117.77 120.83)
		(end 130.32 120.83)
		(width 0.15)
		(layer "In5.Cu")
		(net 259)
	)
	(segment
		(start 130.32 120.83)
		(end 141.47 109.68)
		(width 0.15)
		(layer "In5.Cu")
		(net 259)
	)
	(segment
		(start 117.01 121.59)
		(end 117.77 120.83)
		(width 0.15)
		(layer "In5.Cu")
		(net 259)
	)
	(segment
		(start 144.52 109.68)
		(end 144.565 109.725)
		(width 0.15)
		(layer "In5.Cu")
		(net 259)
	)
	(segment
		(start 107.235 108.715)
		(end 107.235 108.704998)
		(width 0.15)
		(layer "F.Cu")
		(net 260)
	)
	(segment
		(start 106.775 109.175)
		(end 107.235 108.715)
		(width 0.15)
		(layer "F.Cu")
		(net 260)
	)
	(via
		(at 107.235 108.704998)
		(size 0.5)
		(drill 0.2)
		(layers "F.Cu" "B.Cu")
		(net 260)
	)
	(segment
		(start 106.835 107.7)
		(end 106.835 108.304998)
		(width 0.15)
		(layer "B.Cu")
		(net 260)
	)
	(segment
		(start 107.845 107.7)
		(end 107.855 107.71)
		(width 0.15)
		(layer "B.Cu")
		(net 260)
	)
	(segment
		(start 106.835 107.7)
		(end 107.845 107.7)
		(width 0.15)
		(layer "B.Cu")
		(net 260)
	)
	(segment
		(start 106.835 108.304998)
		(end 107.235 108.704998)
		(width 0.15)
		(layer "B.Cu")
		(net 260)
	)
	(segment
		(start 124.5 154.775)
		(end 124.57 154.705)
		(width 0.1)
		(layer "F.Cu")
		(net 264)
	)
	(segment
		(start 124.5 157.2)
		(end 124.5 154.775)
		(width 0.1)
		(layer "F.Cu")
		(net 264)
	)
	(segment
		(start 106.775 120.175)
		(end 107.275 120.675)
		(width 0.15)
		(layer "F.Cu")
		(net 267)
	)
	(segment
		(start 137.625 107.545)
		(end 138.625 107.545)
		(width 0.15)
		(layer "F.Cu")
		(net 267)
	)
	(segment
		(start 137.625 107.545)
		(end 137.625 109.875)
		(width 0.15)
		(layer "F.Cu")
		(net 267)
	)
	(segment
		(start 137.625 109.875)
		(end 137.62 109.88)
		(width 0.15)
		(layer "F.Cu")
		(net 267)
	)
	(via blind
		(at 107.275 120.675)
		(size 0.5)
		(drill 0.2)
		(layers "F.Cu" "In2.Cu")
		(net 267)
	)
	(via
		(at 137.62 109.88)
		(size 0.5)
		(drill 0.2)
		(layers "F.Cu" "B.Cu")
		(net 267)
	)
	(via
		(at 115.6 121.56)
		(size 0.5)
		(drill 0.2)
		(layers "F.Cu" "B.Cu")
		(net 267)
	)
	(segment
		(start 107.775 120.175)
		(end 111.631988 120.175)
		(width 0.15)
		(layer "In2.Cu")
		(net 267)
	)
	(segment
		(start 113.016988 121.56)
		(end 115.6 121.56)
		(width 0.15)
		(layer "In2.Cu")
		(net 267)
	)
	(segment
		(start 107.275 120.675)
		(end 107.775 120.175)
		(width 0.15)
		(layer "In2.Cu")
		(net 267)
	)
	(segment
		(start 111.631988 120.175)
		(end 113.016988 121.56)
		(width 0.15)
		(layer "In2.Cu")
		(net 267)
	)
	(segment
		(start 115.6 121.56)
		(end 117.030022 120.129978)
		(width 0.15)
		(layer "In5.Cu")
		(net 267)
	)
	(segment
		(start 137.62 112.67)
		(end 137.62 109.88)
		(width 0.15)
		(layer "In5.Cu")
		(net 267)
	)
	(segment
		(start 130.160022 120.129978)
		(end 137.62 112.67)
		(width 0.15)
		(layer "In5.Cu")
		(net 267)
	)
	(segment
		(start 117.030022 120.129978)
		(end 130.160022 120.129978)
		(width 0.15)
		(layer "In5.Cu")
		(net 267)
	)
	(segment
		(start 139.62 109.83)
		(end 139.62 107.55)
		(width 0.15)
		(layer "F.Cu")
		(net 268)
	)
	(segment
		(start 139.625 107.545)
		(end 140.625 107.545)
		(width 0.15)
		(layer "F.Cu")
		(net 268)
	)
	(segment
		(start 106.775 121.175)
		(end 107.275 121.675)
		(width 0.15)
		(layer "F.Cu")
		(net 268)
	)
	(segment
		(start 139.62 107.55)
		(end 139.625 107.545)
		(width 0.15)
		(layer "F.Cu")
		(net 268)
	)
	(via
		(at 139.62 109.83)
		(size 0.5)
		(drill 0.2)
		(layers "F.Cu" "B.Cu")
		(net 268)
	)
	(via
		(at 116.3 121.58)
		(size 0.5)
		(drill 0.2)
		(layers "F.Cu" "B.Cu")
		(net 268)
	)
	(via blind
		(at 107.275 121.675)
		(size 0.5)
		(drill 0.2)
		(layers "F.Cu" "In2.Cu")
		(net 268)
	)
	(segment
		(start 110.625 121.675)
		(end 111.000001 122.050001)
		(width 0.15)
		(layer "In2.Cu")
		(net 268)
	)
	(segment
		(start 111.000001 122.050001)
		(end 115.829999 122.050001)
		(width 0.15)
		(layer "In2.Cu")
		(net 268)
	)
	(segment
		(start 115.829999 122.050001)
		(end 116.3 121.58)
		(width 0.15)
		(layer "In2.Cu")
		(net 268)
	)
	(segment
		(start 107.275 121.675)
		(end 110.625 121.675)
		(width 0.15)
		(layer "In2.Cu")
		(net 268)
	)
	(segment
		(start 139.62 111.094279)
		(end 139.62 109.83)
		(width 0.15)
		(layer "In5.Cu")
		(net 268)
	)
	(segment
		(start 116.3 121.58)
		(end 117.400011 120.479989)
		(width 0.15)
		(layer "In5.Cu")
		(net 268)
	)
	(segment
		(start 130.23429 120.479989)
		(end 139.62 111.094279)
		(width 0.15)
		(layer "In5.Cu")
		(net 268)
	)
	(segment
		(start 117.400011 120.479989)
		(end 130.23429 120.479989)
		(width 0.15)
		(layer "In5.Cu")
		(net 268)
	)
	(segment
		(start 122.5 157.2)
		(end 122.5 154.695)
		(width 0.1)
		(layer "F.Cu")
		(net 269)
	)
	(segment
		(start 122.5 157.2)
		(end 122.5 159.6)
		(width 0.15)
		(layer "F.Cu")
		(net 269)
	)
	(segment
		(start 124.575 161.675)
		(end 142.4258 161.675)
		(width 0.15)
		(layer "F.Cu")
		(net 269)
	)
	(segment
		(start 122.5 159.6)
		(end 124.575 161.675)
		(width 0.15)
		(layer "F.Cu")
		(net 269)
	)
	(segment
		(start 124.521433 161.975)
		(end 122 159.453567)
		(width 0.15)
		(layer "F.Cu")
		(net 270)
	)
	(segment
		(start 141.225 163.175)
		(end 140.025 161.975)
		(width 0.15)
		(layer "F.Cu")
		(net 270)
	)
	(segment
		(start 142.2258 163.175)
		(end 141.225 163.175)
		(width 0.15)
		(layer "F.Cu")
		(net 270)
	)
	(segment
		(start 142.575 163.5242)
		(end 142.2258 163.175)
		(width 0.15)
		(layer "F.Cu")
		(net 270)
	)
	(segment
		(start 122 159.453567)
		(end 122 157.2)
		(width 0.15)
		(layer "F.Cu")
		(net 270)
	)
	(segment
		(start 140.025 161.975)
		(end 124.521433 161.975)
		(width 0.15)
		(layer "F.Cu")
		(net 270)
	)
	(segment
		(start 91.545 103.44)
		(end 90.545 103.44)
		(width 0.25)
		(layer "F.Cu")
		(net 274)
	)
	(segment
		(start 90.545 103.44)
		(end 90.545 102.775)
		(width 0.25)
		(layer "F.Cu")
		(net 274)
	)
	(segment
		(start 90.545 102.775)
		(end 90.395 102.625)
		(width 0.25)
		(layer "F.Cu")
		(net 274)
	)
	(segment
		(start 81.55 100.45)
		(end 82.65 100.45)
		(width 0.5)
		(layer "F.Cu")
		(net 274)
	)
	(segment
		(start 81.125 100.875)
		(end 81.55 100.45)
		(width 0.5)
		(layer "F.Cu")
		(net 274)
	)
	(segment
		(start 80.175 100.875)
		(end 81.125 100.875)
		(width 0.5)
		(layer "F.Cu")
		(net 274)
	)
	(via
		(at 90.395 102.625)
		(size 0.5)
		(drill 0.2)
		(layers "F.Cu" "B.Cu")
		(net 274)
	)
	(via
		(at 85.395 100.825)
		(size 0.5)
		(drill 0.2)
		(layers "F.Cu" "B.Cu")
		(net 274)
	)
	(segment
		(start 90.395 102.625)
		(end 88.595 100.825)
		(width 0.25)
		(layer "B.Cu")
		(net 274)
	)
	(segment
		(start 88.595 100.825)
		(end 85.395 100.825)
		(width 0.25)
		(layer "B.Cu")
		(net 274)
	)
	(segment
		(start 91.545 96.09)
		(end 90.545 96.09)
		(width 0.25)
		(layer "F.Cu")
		(net 275)
	)
	(segment
		(start 90.545 95.425)
		(end 90.395 95.275)
		(width 0.25)
		(layer "F.Cu")
		(net 275)
	)
	(segment
		(start 90.545 96.09)
		(end 90.545 95.425)
		(width 0.25)
		(layer "F.Cu")
		(net 275)
	)
	(segment
		(start 79.675 93.275)
		(end 82.5545 93.275)
		(width 0.5)
		(layer "F.Cu")
		(net 275)
	)
	(segment
		(start 82.5545 93.275)
		(end 82.575 93.2955)
		(width 0.5)
		(layer "F.Cu")
		(net 275)
	)
	(via
		(at 90.395 95.275)
		(size 0.5)
		(drill 0.2)
		(layers "F.Cu" "B.Cu")
		(net 275)
	)
	(via
		(at 85.395 93.475)
		(size 0.5)
		(drill 0.2)
		(layers "F.Cu" "B.Cu")
		(net 275)
	)
	(segment
		(start 90.395 95.275)
		(end 88.595 93.475)
		(width 0.25)
		(layer "B.Cu")
		(net 275)
	)
	(segment
		(start 88.595 93.475)
		(end 85.395 93.475)
		(width 0.25)
		(layer "B.Cu")
		(net 275)
	)
	(segment
		(start 91.545 81.34)
		(end 90.545 81.34)
		(width 0.25)
		(layer "F.Cu")
		(net 276)
	)
	(segment
		(start 90.545 80.675)
		(end 90.395 80.525)
		(width 0.25)
		(layer "F.Cu")
		(net 276)
	)
	(segment
		(start 90.545 81.34)
		(end 90.545 80.675)
		(width 0.25)
		(layer "F.Cu")
		(net 276)
	)
	(segment
		(start 82.4545 78.675)
		(end 82.475 78.6955)
		(width 0.5)
		(layer "F.Cu")
		(net 276)
	)
	(segment
		(start 80.075 78.675)
		(end 82.4545 78.675)
		(width 0.5)
		(layer "F.Cu")
		(net 276)
	)
	(via
		(at 90.395 80.525)
		(size 0.5)
		(drill 0.2)
		(layers "F.Cu" "B.Cu")
		(net 276)
	)
	(via
		(at 85.475 78.775)
		(size 0.5)
		(drill 0.2)
		(layers "F.Cu" "B.Cu")
		(net 276)
	)
	(segment
		(start 88.645 78.775)
		(end 90.395 80.525)
		(width 0.25)
		(layer "B.Cu")
		(net 276)
	)
	(segment
		(start 85.475 78.775)
		(end 88.645 78.775)
		(width 0.25)
		(layer "B.Cu")
		(net 276)
	)
	(segment
		(start 90.555 88.75)
		(end 90.555 88.085)
		(width 0.25)
		(layer "F.Cu")
		(net 277)
	)
	(segment
		(start 90.555 88.085)
		(end 90.405 87.935)
		(width 0.25)
		(layer "F.Cu")
		(net 277)
	)
	(segment
		(start 91.555 88.75)
		(end 90.555 88.75)
		(width 0.25)
		(layer "F.Cu")
		(net 277)
	)
	(segment
		(start 80.075 86.075)
		(end 82.975 86.075)
		(width 0.5)
		(layer "F.Cu")
		(net 277)
	)
	(via
		(at 90.405 87.935)
		(size 0.5)
		(drill 0.2)
		(layers "F.Cu" "B.Cu")
		(net 277)
	)
	(via
		(at 85.405 86.135)
		(size 0.5)
		(drill 0.2)
		(layers "F.Cu" "B.Cu")
		(net 277)
	)
	(segment
		(start 88.605 86.135)
		(end 85.405 86.135)
		(width 0.25)
		(layer "B.Cu")
		(net 277)
	)
	(segment
		(start 90.405 87.935)
		(end 88.605 86.135)
		(width 0.25)
		(layer "B.Cu")
		(net 277)
	)
	(segment
		(start 66.715 87.34)
		(end 66.715 86.266)
		(width 0.1)
		(layer "F.Cu")
		(net 279)
	)
	(segment
		(start 66.715 86.266)
		(end 66.716 86.265)
		(width 0.1)
		(layer "F.Cu")
		(net 279)
	)
	(via
		(at 66.715 87.34)
		(size 0.5)
		(drill 0.2)
		(layers "F.Cu" "B.Cu")
		(net 279)
	)
	(segment
		(start 67.605 87.315)
		(end 66.74 87.315)
		(width 0.1)
		(layer "B.Cu")
		(net 279)
	)
	(segment
		(start 66.74 87.315)
		(end 66.715 87.34)
		(width 0.1)
		(layer "B.Cu")
		(net 279)
	)
	(segment
		(start 68.709 82.457)
		(end 68.216 82.95)
		(width 0.1)
		(layer "F.Cu")
		(net 281)
	)
	(segment
		(start 69.269 79.677)
		(end 68.709 80.237)
		(width 0.1)
		(layer "F.Cu")
		(net 281)
	)
	(segment
		(start 68.709 80.237)
		(end 68.709 82.457)
		(width 0.1)
		(layer "F.Cu")
		(net 281)
	)
	(segment
		(start 68.216 82.95)
		(end 68.216 84.215)
		(width 0.1)
		(layer "F.Cu")
		(net 281)
	)
	(via
		(at 69.269 79.677)
		(size 0.5)
		(drill 0.2)
		(layers "F.Cu" "B.Cu")
		(net 281)
	)
	(segment
		(start 69.282 79.69)
		(end 69.269 79.677)
		(width 0.1)
		(layer "B.Cu")
		(net 281)
	)
	(segment
		(start 71.04 79.69)
		(end 69.282 79.69)
		(width 0.1)
		(layer "B.Cu")
		(net 281)
	)
	(segment
		(start 125.575 64.33)
		(end 125.575 66.105)
		(width 0.2)
		(layer "F.Cu")
		(net 282)
	)
	(segment
		(start 125.575 66.105)
		(end 124.925 66.755)
		(width 0.2)
		(layer "F.Cu")
		(net 282)
	)
	(segment
		(start 66.69 84.241)
		(end 66.716 84.215)
		(width 0.1)
		(layer "F.Cu")
		(net 283)
	)
	(segment
		(start 66.69 85.24)
		(end 66.69 84.241)
		(width 0.1)
		(layer "F.Cu")
		(net 283)
	)
	(via
		(at 66.69 85.24)
		(size 0.5)
		(drill 0.2)
		(layers "F.Cu" "B.Cu")
		(net 283)
	)
	(segment
		(start 67.605 85.24)
		(end 66.69 85.24)
		(width 0.1)
		(layer "B.Cu")
		(net 283)
	)
	(segment
		(start 139.64 61.915)
		(end 139.95 61.605)
		(width 0.15)
		(layer "F.Cu")
		(net 284)
	)
	(segment
		(start 123.7 68.13)
		(end 123.725 68.105)
		(width 0.2)
		(layer "F.Cu")
		(net 284)
	)
	(segment
		(start 122.425 68.13)
		(end 123.7 68.13)
		(width 0.2)
		(layer "F.Cu")
		(net 284)
	)
	(segment
		(start 138.99 61.915)
		(end 139.64 61.915)
		(width 0.15)
		(layer "F.Cu")
		(net 284)
	)
	(via
		(at 139.95 61.605)
		(size 0.5)
		(drill 0.2)
		(layers "F.Cu" "B.Cu")
		(net 284)
	)
	(via
		(at 123.725 68.105)
		(size 0.5)
		(drill 0.2)
		(layers "F.Cu" "B.Cu")
		(net 284)
	)
	(segment
		(start 130.025 62.355)
		(end 139.2 62.355)
		(width 0.15)
		(layer "B.Cu")
		(net 284)
	)
	(segment
		(start 123.725 68.105)
		(end 124.275 68.105)
		(width 0.15)
		(layer "B.Cu")
		(net 284)
	)
	(segment
		(start 139.95 61.605)
		(end 139.2 62.355)
		(width 0.15)
		(layer "B.Cu")
		(net 284)
	)
	(segment
		(start 124.275 68.105)
		(end 130.025 62.355)
		(width 0.15)
		(layer "B.Cu")
		(net 284)
	)
	(segment
		(start 138.125 60.655)
		(end 138.325 60.455)
		(width 0.2)
		(layer "F.Cu")
		(net 286)
	)
	(segment
		(start 138.34 63.22)
		(end 138.125 63.005)
		(width 0.2)
		(layer "F.Cu")
		(net 286)
	)
	(segment
		(start 138.94 60.465)
		(end 138.99 60.415)
		(width 0.2)
		(layer "F.Cu")
		(net 286)
	)
	(segment
		(start 138.325 60.455)
		(end 138.95 60.455)
		(width 0.2)
		(layer "F.Cu")
		(net 286)
	)
	(segment
		(start 138.975 63.22)
		(end 138.34 63.22)
		(width 0.2)
		(layer "F.Cu")
		(net 286)
	)
	(segment
		(start 138.125 63.005)
		(end 138.125 60.655)
		(width 0.2)
		(layer "F.Cu")
		(net 286)
	)
	(segment
		(start 114.09 177.345)
		(end 114.09 172.26)
		(width 0.25)
		(layer "F.Cu")
		(net 287)
	)
	(segment
		(start 140.35 142.465)
		(end 140.35 159.605)
		(width 0.25)
		(layer "F.Cu")
		(net 287)
	)
	(segment
		(start 114.09 172.26)
		(end 115.63 170.72)
		(width 0.25)
		(layer "F.Cu")
		(net 287)
	)
	(segment
		(start 140.35 159.605)
		(end 140.34 159.615)
		(width 0.25)
		(layer "F.Cu")
		(net 287)
	)
	(via
		(at 140.34 159.615)
		(size 0.5)
		(drill 0.2)
		(layers "F.Cu" "B.Cu")
		(net 287)
	)
	(via
		(at 115.63 170.72)
		(size 0.5)
		(drill 0.2)
		(layers "F.Cu" "B.Cu")
		(net 287)
	)
	(segment
		(start 140.34 164.24)
		(end 140.34 159.615)
		(width 0.25)
		(layer "In5.Cu")
		(net 287)
	)
	(segment
		(start 115.63 170.72)
		(end 133.86 170.72)
		(width 0.25)
		(layer "In5.Cu")
		(net 287)
	)
	(segment
		(start 133.86 170.72)
		(end 140.34 164.24)
		(width 0.25)
		(layer "In5.Cu")
		(net 287)
	)
	(segment
		(start 86.32 97.525)
		(end 86.32 98.05)
		(width 0.25)
		(layer "F.Cu")
		(net 292)
	)
	(segment
		(start 86.32 98.05)
		(end 86.095 98.275)
		(width 0.25)
		(layer "F.Cu")
		(net 292)
	)
	(via
		(at 86.095 98.275)
		(size 0.5)
		(drill 0.2)
		(layers "F.Cu" "B.Cu")
		(net 292)
	)
	(segment
		(start 82.355 94.9)
		(end 82.355 95.355)
		(width 0.15)
		(layer "B.Cu")
		(net 292)
	)
	(segment
		(start 84.825 96.025)
		(end 86.075 97.275)
		(width 0.15)
		(layer "B.Cu")
		(net 292)
	)
	(segment
		(start 82.526 95.526)
		(end 82.526 95.924)
		(width 0.15)
		(layer "B.Cu")
		(net 292)
	)
	(segment
		(start 86.075 98.255)
		(end 86.095 98.275)
		(width 0.15)
		(layer "B.Cu")
		(net 292)
	)
	(segment
		(start 82.355 95.355)
		(end 82.526 95.526)
		(width 0.15)
		(layer "B.Cu")
		(net 292)
	)
	(segment
		(start 82.425 96.025)
		(end 84.825 96.025)
		(width 0.15)
		(layer "B.Cu")
		(net 292)
	)
	(segment
		(start 86.075 97.275)
		(end 86.075 98.255)
		(width 0.15)
		(layer "B.Cu")
		(net 292)
	)
	(segment
		(start 82.526 95.924)
		(end 82.425 96.025)
		(width 0.15)
		(layer "B.Cu")
		(net 292)
	)
	(segment
		(start 86.33 90.71)
		(end 86.105 90.935)
		(width 0.25)
		(layer "F.Cu")
		(net 293)
	)
	(segment
		(start 86.33 90.185)
		(end 86.33 90.71)
		(width 0.25)
		(layer "F.Cu")
		(net 293)
	)
	(via
		(at 86.105 90.935)
		(size 0.5)
		(drill 0.2)
		(layers "F.Cu" "B.Cu")
		(net 293)
	)
	(segment
		(start 86.105 90.935)
		(end 86.105 89.305)
		(width 0.15)
		(layer "B.Cu")
		(net 293)
	)
	(segment
		(start 86.105 89.305)
		(end 85.425 88.625)
		(width 0.15)
		(layer "B.Cu")
		(net 293)
	)
	(segment
		(start 85.425 88.625)
		(end 82.525 88.625)
		(width 0.15)
		(layer "B.Cu")
		(net 293)
	)
	(segment
		(start 82.525 87.812)
		(end 82.471 87.758)
		(width 0.15)
		(layer "B.Cu")
		(net 293)
	)
	(segment
		(start 82.525 88.625)
		(end 82.525 87.812)
		(width 0.15)
		(layer "B.Cu")
		(net 293)
	)
	(segment
		(start 82.425 103.325)
		(end 82.425 102.513)
		(width 0.15)
		(layer "B.Cu")
		(net 294)
	)
	(segment
		(start 82.425 102.513)
		(end 82.448 102.49)
		(width 0.15)
		(layer "B.Cu")
		(net 294)
	)
	(segment
		(start 70.692 93.581)
		(end 70.967 93.306)
		(width 0.15)
		(layer "F.Cu")
		(net 295)
	)
	(segment
		(start 70.692 94.906857)
		(end 70.692 93.581)
		(width 0.15)
		(layer "F.Cu")
		(net 295)
	)
	(segment
		(start 90.46 83.375)
		(end 91.175 83.375)
		(width 0.15)
		(layer "F.Cu")
		(net 295)
	)
	(via
		(at 70.967 93.306)
		(size 0.5)
		(drill 0.2)
		(layers "F.Cu" "B.Cu")
		(net 295)
	)
	(via
		(at 91.175 83.375)
		(size 0.5)
		(drill 0.2)
		(layers "F.Cu" "B.Cu")
		(net 295)
	)
	(segment
		(start 70.967 93.306)
		(end 70.967 92.136)
		(width 0.15)
		(layer "B.Cu")
		(net 295)
	)
	(segment
		(start 70.967 92.136)
		(end 71.032 92.071)
		(width 0.15)
		(layer "B.Cu")
		(net 295)
	)
	(segment
		(start 79.269 87.907)
		(end 80.023 87.907)
		(width 0.15)
		(layer "B.Cu")
		(net 295)
	)
	(segment
		(start 91.175 84.381)
		(end 91.175 83.375)
		(width 0.15)
		(layer "B.Cu")
		(net 295)
	)
	(segment
		(start 70.967 93.306)
		(end 76.96 93.306)
		(width 0.15)
		(layer "B.Cu")
		(net 295)
	)
	(segment
		(start 78.9 91.366)
		(end 78.9 88.276)
		(width 0.15)
		(layer "B.Cu")
		(net 295)
	)
	(segment
		(start 90.389 85.167)
		(end 91.175 84.381)
		(width 0.15)
		(layer "B.Cu")
		(net 295)
	)
	(segment
		(start 76.96 93.306)
		(end 78.9 91.366)
		(width 0.15)
		(layer "B.Cu")
		(net 295)
	)
	(segment
		(start 82.763 85.167)
		(end 90.389 85.167)
		(width 0.15)
		(layer "B.Cu")
		(net 295)
	)
	(segment
		(start 78.9 88.276)
		(end 79.269 87.907)
		(width 0.15)
		(layer "B.Cu")
		(net 295)
	)
	(segment
		(start 80.023 87.907)
		(end 82.763 85.167)
		(width 0.15)
		(layer "B.Cu")
		(net 295)
	)
	(segment
		(start 70.042 93.381)
		(end 69.967 93.306)
		(width 0.15)
		(layer "F.Cu")
		(net 296)
	)
	(segment
		(start 70.042 94.906857)
		(end 70.042 93.381)
		(width 0.15)
		(layer "F.Cu")
		(net 296)
	)
	(segment
		(start 90.46 98.075)
		(end 90.46 98.76)
		(width 0.15)
		(layer "F.Cu")
		(net 296)
	)
	(segment
		(start 90.46 98.76)
		(end 90.475 98.775)
		(width 0.15)
		(layer "F.Cu")
		(net 296)
	)
	(via
		(at 69.967 93.306)
		(size 0.5)
		(drill 0.2)
		(layers "F.Cu" "B.Cu")
		(net 296)
	)
	(via
		(at 90.475 98.775)
		(size 0.5)
		(drill 0.2)
		(layers "F.Cu" "B.Cu")
		(net 296)
	)
	(segment
		(start 69.967 93.306)
		(end 69.967 92.041)
		(width 0.15)
		(layer "B.Cu")
		(net 296)
	)
	(segment
		(start 82.3 99.5)
		(end 81.197 98.397)
		(width 0.15)
		(layer "B.Cu")
		(net 296)
	)
	(segment
		(start 71.519 97.047)
		(end 69.967 95.495)
		(width 0.15)
		(layer "B.Cu")
		(net 296)
	)
	(segment
		(start 80.259 98.397)
		(end 78.909 97.047)
		(width 0.15)
		(layer "B.Cu")
		(net 296)
	)
	(segment
		(start 78.909 97.047)
		(end 71.519 97.047)
		(width 0.15)
		(layer "B.Cu")
		(net 296)
	)
	(segment
		(start 69.967 95.495)
		(end 69.967 93.306)
		(width 0.15)
		(layer "B.Cu")
		(net 296)
	)
	(segment
		(start 81.197 98.397)
		(end 80.259 98.397)
		(width 0.15)
		(layer "B.Cu")
		(net 296)
	)
	(segment
		(start 90.475 98.775)
		(end 86.025 98.775)
		(width 0.15)
		(layer "B.Cu")
		(net 296)
	)
	(segment
		(start 86.025 98.775)
		(end 85.3 99.5)
		(width 0.15)
		(layer "B.Cu")
		(net 296)
	)
	(segment
		(start 85.3 99.5)
		(end 82.3 99.5)
		(width 0.15)
		(layer "B.Cu")
		(net 296)
	)
	(segment
		(start 69.392 93.731)
		(end 68.967 93.306)
		(width 0.15)
		(layer "F.Cu")
		(net 297)
	)
	(segment
		(start 69.392 94.906857)
		(end 69.392 93.731)
		(width 0.15)
		(layer "F.Cu")
		(net 297)
	)
	(segment
		(start 90.435 75.95)
		(end 91.15 75.95)
		(width 0.15)
		(layer "F.Cu")
		(net 297)
	)
	(segment
		(start 92.474999 104.821001)
		(end 92.474999 91.302999)
		(width 0.15)
		(layer "F.Cu")
		(net 297)
	)
	(segment
		(start 90.417 90.856)
		(end 91.13 90.856)
		(width 0.15)
		(layer "F.Cu")
		(net 297)
	)
	(segment
		(start 68.967 92.849)
		(end 68.967 93.306)
		(width 0.15)
		(layer "F.Cu")
		(net 297)
	)
	(segment
		(start 70.459 92.897)
		(end 70.209001 92.647001)
		(width 0.15)
		(layer "F.Cu")
		(net 297)
	)
	(segment
		(start 90.46 105.475)
		(end 91.821 105.475)
		(width 0.15)
		(layer "F.Cu")
		(net 297)
	)
	(segment
		(start 69.168999 92.647001)
		(end 68.967 92.849)
		(width 0.15)
		(layer "F.Cu")
		(net 297)
	)
	(segment
		(start 91.989 90.817)
		(end 91.169 90.817)
		(width 0.15)
		(layer "F.Cu")
		(net 297)
	)
	(segment
		(start 91.821 105.475)
		(end 92.474999 104.821001)
		(width 0.15)
		(layer "F.Cu")
		(net 297)
	)
	(segment
		(start 70.209001 92.647001)
		(end 69.168999 92.647001)
		(width 0.15)
		(layer "F.Cu")
		(net 297)
	)
	(segment
		(start 92.474999 91.302999)
		(end 91.989 90.817)
		(width 0.15)
		(layer "F.Cu")
		(net 297)
	)
	(via
		(at 68.967 93.306)
		(size 0.5)
		(drill 0.2)
		(layers "F.Cu" "B.Cu")
		(net 297)
	)
	(via
		(at 91.15 75.95)
		(size 0.5)
		(drill 0.2)
		(layers "F.Cu" "B.Cu")
		(net 297)
	)
	(via
		(at 70.459 92.897)
		(size 0.5)
		(drill 0.2)
		(layers "F.Cu" "B.Cu")
		(net 297)
	)
	(via
		(at 91.169 90.817)
		(size 0.5)
		(drill 0.2)
		(layers "F.Cu" "B.Cu")
		(net 297)
	)
	(segment
		(start 68.967 92.041)
		(end 68.967 93.306)
		(width 0.15)
		(layer "B.Cu")
		(net 297)
	)
	(segment
		(start 92.719 76.777)
		(end 91.892 75.95)
		(width 0.15)
		(layer "B.Cu")
		(net 297)
	)
	(segment
		(start 91.892 75.95)
		(end 91.15 75.95)
		(width 0.15)
		(layer "B.Cu")
		(net 297)
	)
	(segment
		(start 71.948998 94.917)
		(end 70.459 93.427002)
		(width 0.15)
		(layer "B.Cu")
		(net 297)
	)
	(segment
		(start 71.948998 94.917)
		(end 79.439 94.917)
		(width 0.15)
		(layer "B.Cu")
		(net 297)
	)
	(segment
		(start 70.459 93.427002)
		(end 70.459 92.897)
		(width 0.15)
		(layer "B.Cu")
		(net 297)
	)
	(segment
		(start 91.522553 90.817)
		(end 92.719 89.620553)
		(width 0.15)
		(layer "B.Cu")
		(net 297)
	)
	(segment
		(start 90.459 92.547)
		(end 91.169 91.837)
		(width 0.15)
		(layer "B.Cu")
		(net 297)
	)
	(segment
		(start 92.719 89.620553)
		(end 92.719 76.777)
		(width 0.15)
		(layer "B.Cu")
		(net 297)
	)
	(segment
		(start 91.169 90.817)
		(end 91.522553 90.817)
		(width 0.15)
		(layer "B.Cu")
		(net 297)
	)
	(segment
		(start 81.809 92.547)
		(end 79.439 94.917)
		(width 0.15)
		(layer "B.Cu")
		(net 297)
	)
	(segment
		(start 81.809 92.547)
		(end 90.459 92.547)
		(width 0.15)
		(layer "B.Cu")
		(net 297)
	)
	(segment
		(start 91.169 91.837)
		(end 91.169 90.817)
		(width 0.15)
		(layer "B.Cu")
		(net 297)
	)
	(segment
		(start 135.85 89.4975)
		(end 135.85 90.8875)
		(width 0.1)
		(layer "F.Cu")
		(net 298)
	)
	(segment
		(start 130.425 89.1975)
		(end 129.3475 89.1975)
		(width 0.2)
		(layer "F.Cu")
		(net 299)
	)
	(segment
		(start 131.226784 89.973216)
		(end 130.451068 89.1975)
		(width 0.2)
		(layer "F.Cu")
		(net 299)
	)
	(segment
		(start 131.673216 89.973216)
		(end 131.226784 89.973216)
		(width 0.2)
		(layer "F.Cu")
		(net 299)
	)
	(segment
		(start 131.851 90.886)
		(end 131.851 90.151)
		(width 0.2)
		(layer "F.Cu")
		(net 299)
	)
	(segment
		(start 131.851 90.151)
		(end 131.673216 89.973216)
		(width 0.2)
		(layer "F.Cu")
		(net 299)
	)
	(segment
		(start 126.925 113.81)
		(end 126.925 114.39)
		(width 0.15)
		(layer "F.Cu")
		(net 300)
	)
	(segment
		(start 129.195 115.675)
		(end 129.49 115.675)
		(width 0.15)
		(layer "F.Cu")
		(net 300)
	)
	(segment
		(start 126.925 114.39)
		(end 128.21 115.675)
		(width 0.15)
		(layer "F.Cu")
		(net 300)
	)
	(segment
		(start 128.21 115.675)
		(end 129.195 115.675)
		(width 0.15)
		(layer "F.Cu")
		(net 300)
	)
	(segment
		(start 91.775 109.175)
		(end 91.349999 108.749999)
		(width 0.15)
		(layer "F.Cu")
		(net 301)
	)
	(segment
		(start 78.572 157.383)
		(end 79.265 156.69)
		(width 0.15)
		(layer "F.Cu")
		(net 301)
	)
	(segment
		(start 79.265 156.69)
		(end 82.34 156.69)
		(width 0.15)
		(layer "F.Cu")
		(net 301)
	)
	(segment
		(start 81.305001 108.749999)
		(end 91.349999 108.749999)
		(width 0.15)
		(layer "F.Cu")
		(net 301)
	)
	(segment
		(start 83.14 156.69)
		(end 83.314479 156.515521)
		(width 0.15)
		(layer "F.Cu")
		(net 301)
	)
	(segment
		(start 80.915 110.04)
		(end 80.965 110.09)
		(width 0.15)
		(layer "F.Cu")
		(net 301)
	)
	(segment
		(start 82.34 156.69)
		(end 83.14 156.69)
		(width 0.15)
		(layer "F.Cu")
		(net 301)
	)
	(segment
		(start 81.305001 108.749999)
		(end 80.915 109.14)
		(width 0.15)
		(layer "F.Cu")
		(net 301)
	)
	(segment
		(start 78.572 158.45122)
		(end 78.572 157.383)
		(width 0.15)
		(layer "F.Cu")
		(net 301)
	)
	(segment
		(start 82.34 156.69)
		(end 83.165 156.69)
		(width 0.15)
		(layer "F.Cu")
		(net 301)
	)
	(segment
		(start 80.915 109.14)
		(end 80.915 110.04)
		(width 0.15)
		(layer "F.Cu")
		(net 301)
	)
	(via
		(at 80.965 110.165)
		(size 0.5)
		(drill 0.2)
		(layers "F.Cu" "B.Cu")
		(net 301)
	)
	(via
		(at 83.314479 156.515521)
		(size 0.5)
		(drill 0.2)
		(layers "F.Cu" "B.Cu")
		(net 301)
	)
	(segment
		(start 76.91501 142.922164)
		(end 76.91501 116.43282)
		(width 0.15)
		(layer "B.Cu")
		(net 301)
	)
	(segment
		(start 80.40252 112.945311)
		(end 80.40252 111.20248)
		(width 0.15)
		(layer "B.Cu")
		(net 301)
	)
	(segment
		(start 83.314479 149.321633)
		(end 76.91501 142.922164)
		(width 0.15)
		(layer "B.Cu")
		(net 301)
	)
	(segment
		(start 76.91501 116.43282)
		(end 80.40252 112.945311)
		(width 0.15)
		(layer "B.Cu")
		(net 301)
	)
	(segment
		(start 80.965 110.64)
		(end 80.965 110.165)
		(width 0.15)
		(layer "B.Cu")
		(net 301)
	)
	(segment
		(start 80.40252 111.20248)
		(end 80.965 110.64)
		(width 0.15)
		(layer "B.Cu")
		(net 301)
	)
	(segment
		(start 83.314479 156.515521)
		(end 83.314479 149.321633)
		(width 0.15)
		(layer "B.Cu")
		(net 301)
	)
	(segment
		(start 127.61 111.625)
		(end 129.71 111.625)
		(width 0.15)
		(layer "F.Cu")
		(net 302)
	)
	(segment
		(start 129.71 111.625)
		(end 129.775 111.69)
		(width 0.15)
		(layer "F.Cu")
		(net 302)
	)
	(segment
		(start 126.725 130.81)
		(end 127.29 131.375)
		(width 0.15)
		(layer "F.Cu")
		(net 303)
	)
	(segment
		(start 127.29 131.375)
		(end 128.09 131.375)
		(width 0.15)
		(layer "F.Cu")
		(net 303)
	)
	(segment
		(start 126.725 129.91)
		(end 126.725 130.81)
		(width 0.15)
		(layer "F.Cu")
		(net 303)
	)
	(segment
		(start 127.41 127.725)
		(end 129.04 127.725)
		(width 0.15)
		(layer "F.Cu")
		(net 304)
	)
	(segment
		(start 129.04 127.725)
		(end 129.075 127.69)
		(width 0.15)
		(layer "F.Cu")
		(net 304)
	)
	(segment
		(start 124.025 71.455)
		(end 124.025 68.98)
		(width 0.2)
		(layer "F.Cu")
		(net 305)
	)
	(segment
		(start 122.425 72.08)
		(end 123.4 72.08)
		(width 0.2)
		(layer "F.Cu")
		(net 305)
	)
	(segment
		(start 123.4 72.08)
		(end 124.025 71.455)
		(width 0.2)
		(layer "F.Cu")
		(net 305)
	)
	(segment
		(start 140.44 61.915)
		(end 140.1 62.255)
		(width 0.15)
		(layer "F.Cu")
		(net 305)
	)
	(segment
		(start 140.99 61.915)
		(end 140.86 61.915)
		(width 0.15)
		(layer "F.Cu")
		(net 305)
	)
	(segment
		(start 140.86 61.915)
		(end 140.44 61.915)
		(width 0.15)
		(layer "F.Cu")
		(net 305)
	)
	(via
		(at 140.1 62.255)
		(size 0.5)
		(drill 0.2)
		(layers "F.Cu" "B.Cu")
		(net 305)
	)
	(via
		(at 124.025 68.98)
		(size 0.5)
		(drill 0.2)
		(layers "F.Cu" "B.Cu")
		(net 305)
	)
	(segment
		(start 140.1 62.255)
		(end 139.7 62.655)
		(width 0.15)
		(layer "B.Cu")
		(net 305)
	)
	(segment
		(start 124.025 68.98)
		(end 130.35 62.655)
		(width 0.15)
		(layer "B.Cu")
		(net 305)
	)
	(segment
		(start 130.35 62.655)
		(end 139.7 62.655)
		(width 0.15)
		(layer "B.Cu")
		(net 305)
	)
	(segment
		(start 138.274 120.014)
		(end 138.274 119.274)
		(width 0.15)
		(layer "F.Cu")
		(net 306)
	)
	(via
		(at 138.274 119.274)
		(size 0.5)
		(drill 0.2)
		(layers "F.Cu" "B.Cu")
		(net 306)
	)
	(segment
		(start 138.274 118.556)
		(end 138.274 119.274)
		(width 0.15)
		(layer "B.Cu")
		(net 306)
	)
	(segment
		(start 138.29 118.54)
		(end 138.274 118.556)
		(width 0.15)
		(layer "B.Cu")
		(net 306)
	)
	(segment
		(start 141.8 62.98)
		(end 141.55 63.23)
		(width 0.2)
		(layer "F.Cu")
		(net 307)
	)
	(segment
		(start 140.985 60.415)
		(end 141.535 60.415)
		(width 0.2)
		(layer "F.Cu")
		(net 307)
	)
	(segment
		(start 141.55 63.23)
		(end 141.05 63.23)
		(width 0.2)
		(layer "F.Cu")
		(net 307)
	)
	(segment
		(start 141.025 60.415)
		(end 140.985 60.415)
		(width 0.2)
		(layer "F.Cu")
		(net 307)
	)
	(segment
		(start 141.8 60.68)
		(end 141.8 62.98)
		(width 0.2)
		(layer "F.Cu")
		(net 307)
	)
	(segment
		(start 141.535 60.415)
		(end 141.8 60.68)
		(width 0.2)
		(layer "F.Cu")
		(net 307)
	)
	(segment
		(start 126.425 114.725)
		(end 128.475 116.775)
		(width 0.15)
		(layer "F.Cu")
		(net 308)
	)
	(segment
		(start 128.475 116.775)
		(end 129.49 116.775)
		(width 0.15)
		(layer "F.Cu")
		(net 308)
	)
	(segment
		(start 126.425 113.81)
		(end 126.425 114.725)
		(width 0.15)
		(layer "F.Cu")
		(net 308)
	)
	(segment
		(start 123.275 76.055)
		(end 124.725 74.605)
		(width 0.2)
		(layer "F.Cu")
		(net 309)
	)
	(segment
		(start 143.04 61.915)
		(end 142.29 61.915)
		(width 0.15)
		(layer "F.Cu")
		(net 309)
	)
	(segment
		(start 142.29 61.915)
		(end 142.25 61.955)
		(width 0.15)
		(layer "F.Cu")
		(net 309)
	)
	(segment
		(start 124.725 74.605)
		(end 124.725 68.98)
		(width 0.2)
		(layer "F.Cu")
		(net 309)
	)
	(segment
		(start 122.4 76.055)
		(end 123.275 76.055)
		(width 0.2)
		(layer "F.Cu")
		(net 309)
	)
	(via
		(at 142.25 61.955)
		(size 0.5)
		(drill 0.2)
		(layers "F.Cu" "B.Cu")
		(net 309)
	)
	(via
		(at 124.725 68.98)
		(size 0.5)
		(drill 0.2)
		(layers "F.Cu" "B.Cu")
		(net 309)
	)
	(segment
		(start 124.725 68.905)
		(end 124.725 68.98)
		(width 0.15)
		(layer "B.Cu")
		(net 309)
	)
	(segment
		(start 141.25 62.955)
		(end 130.675 62.955)
		(width 0.15)
		(layer "B.Cu")
		(net 309)
	)
	(segment
		(start 130.675 62.955)
		(end 124.725 68.905)
		(width 0.15)
		(layer "B.Cu")
		(net 309)
	)
	(segment
		(start 142.25 61.955)
		(end 141.25 62.955)
		(width 0.15)
		(layer "B.Cu")
		(net 309)
	)
	(segment
		(start 126.225 130.905)
		(end 127.795 132.475)
		(width 0.15)
		(layer "F.Cu")
		(net 310)
	)
	(segment
		(start 127.795 132.475)
		(end 128.09 132.475)
		(width 0.15)
		(layer "F.Cu")
		(net 310)
	)
	(segment
		(start 126.225 129.91)
		(end 126.225 130.905)
		(width 0.15)
		(layer "F.Cu")
		(net 310)
	)
	(segment
		(start 143.925 60.605)
		(end 143.725 60.405)
		(width 0.2)
		(layer "F.Cu")
		(net 311)
	)
	(segment
		(start 143.725 60.405)
		(end 143.075 60.405)
		(width 0.2)
		(layer "F.Cu")
		(net 311)
	)
	(segment
		(start 143.66 63.22)
		(end 143.925 62.955)
		(width 0.2)
		(layer "F.Cu")
		(net 311)
	)
	(segment
		(start 143.05 63.22)
		(end 143.66 63.22)
		(width 0.2)
		(layer "F.Cu")
		(net 311)
	)
	(segment
		(start 143.925 62.955)
		(end 143.925 60.605)
		(width 0.2)
		(layer "F.Cu")
		(net 311)
	)
	(segment
		(start 83.29 165.765)
		(end 83.09 165.565)
		(width 0.15)
		(layer "F.Cu")
		(net 312)
	)
	(segment
		(start 84.455 165.765)
		(end 83.29 165.765)
		(width 0.15)
		(layer "F.Cu")
		(net 312)
	)
	(segment
		(start 88.425 78.28)
		(end 88.475 78.23)
		(width 0.15)
		(layer "F.Cu")
		(net 313)
	)
	(segment
		(start 87.75 78.28)
		(end 88.425 78.28)
		(width 0.15)
		(layer "F.Cu")
		(net 313)
	)
	(segment
		(start 76.939 86.857)
		(end 77.859 86.857)
		(width 0.15)
		(layer "F.Cu")
		(net 313)
	)
	(segment
		(start 76.469 87.327)
		(end 76.939 86.857)
		(width 0.15)
		(layer "F.Cu")
		(net 313)
	)
	(segment
		(start 76.469 87.857)
		(end 76.469 87.327)
		(width 0.15)
		(layer "F.Cu")
		(net 313)
	)
	(via
		(at 88.475 78.23)
		(size 0.5)
		(drill 0.2)
		(layers "F.Cu" "B.Cu")
		(net 313)
	)
	(via
		(at 77.859 86.857)
		(size 0.5)
		(drill 0.2)
		(layers "F.Cu" "B.Cu")
		(net 313)
	)
	(segment
		(start 85.7 75.605)
		(end 85.7 77.605)
		(width 0.15)
		(layer "B.Cu")
		(net 313)
	)
	(segment
		(start 80.8 74.955)
		(end 85.05 74.955)
		(width 0.15)
		(layer "B.Cu")
		(net 313)
	)
	(segment
		(start 77.859 86.857)
		(end 78.675 86.041)
		(width 0.15)
		(layer "B.Cu")
		(net 313)
	)
	(segment
		(start 85.05 74.955)
		(end 85.7 75.605)
		(width 0.15)
		(layer "B.Cu")
		(net 313)
	)
	(segment
		(start 78.675 77.08)
		(end 80.8 74.955)
		(width 0.15)
		(layer "B.Cu")
		(net 313)
	)
	(segment
		(start 78.675 86.041)
		(end 78.675 77.08)
		(width 0.15)
		(layer "B.Cu")
		(net 313)
	)
	(segment
		(start 86.325 78.23)
		(end 88.475 78.23)
		(width 0.15)
		(layer "B.Cu")
		(net 313)
	)
	(segment
		(start 85.7 77.605)
		(end 86.325 78.23)
		(width 0.15)
		(layer "B.Cu")
		(net 313)
	)
	(segment
		(start 88.695 105.475)
		(end 89.49 105.475)
		(width 0.15)
		(layer "F.Cu")
		(net 314)
	)
	(segment
		(start 87.67 104.875)
		(end 88.095 104.875)
		(width 0.15)
		(layer "F.Cu")
		(net 314)
	)
	(segment
		(start 88.095 104.875)
		(end 88.695 105.475)
		(width 0.15)
		(layer "F.Cu")
		(net 314)
	)
	(segment
		(start 88.645 98.075)
		(end 89.49 98.075)
		(width 0.15)
		(layer "F.Cu")
		(net 315)
	)
	(segment
		(start 88.095 97.525)
		(end 88.645 98.075)
		(width 0.15)
		(layer "F.Cu")
		(net 315)
	)
	(segment
		(start 87.67 97.525)
		(end 88.095 97.525)
		(width 0.15)
		(layer "F.Cu")
		(net 315)
	)
	(segment
		(start 105.775 111.175)
		(end 105.275 111.675)
		(width 0.15)
		(layer "F.Cu")
		(net 316)
	)
	(segment
		(start 120.35 68.13)
		(end 120.35 67.13)
		(width 0.15)
		(layer "F.Cu")
		(net 316)
	)
	(via blind
		(at 105.275 111.675)
		(size 0.5)
		(drill 0.2)
		(layers "F.Cu" "In2.Cu")
		(net 316)
	)
	(via
		(at 120.35 68.13)
		(size 0.5)
		(drill 0.2)
		(layers "F.Cu" "B.Cu")
		(net 316)
	)
	(segment
		(start 106.842863 111.100001)
		(end 112.7 105.242864)
		(width 0.15)
		(layer "In2.Cu")
		(net 316)
	)
	(segment
		(start 112.7 105.242864)
		(end 112.7 88.155)
		(width 0.15)
		(layer "In2.Cu")
		(net 316)
	)
	(segment
		(start 112.7 88.155)
		(end 119.55 81.305)
		(width 0.15)
		(layer "In2.Cu")
		(net 316)
	)
	(segment
		(start 119.55 68.93)
		(end 120.35 68.13)
		(width 0.15)
		(layer "In2.Cu")
		(net 316)
	)
	(segment
		(start 105.275 111.675)
		(end 105.849999 111.100001)
		(width 0.15)
		(layer "In2.Cu")
		(net 316)
	)
	(segment
		(start 105.849999 111.100001)
		(end 106.842863 111.100001)
		(width 0.15)
		(layer "In2.Cu")
		(net 316)
	)
	(segment
		(start 119.55 81.305)
		(end 119.55 68.93)
		(width 0.15)
		(layer "In2.Cu")
		(net 316)
	)
	(segment
		(start 106.775 111.175)
		(end 107.275 111.675)
		(width 0.15)
		(layer "F.Cu")
		(net 317)
	)
	(segment
		(start 120.3 72.055)
		(end 120.3 71.105)
		(width 0.15)
		(layer "F.Cu")
		(net 317)
	)
	(via blind
		(at 107.275 111.675)
		(size 0.5)
		(drill 0.2)
		(layers "F.Cu" "In2.Cu")
		(net 317)
	)
	(via
		(at 120.3 72.055)
		(size 0.5)
		(drill 0.2)
		(layers "F.Cu" "B.Cu")
		(net 317)
	)
	(segment
		(start 113 88.305)
		(end 119.875 81.43)
		(width 0.15)
		(layer "In2.Cu")
		(net 317)
	)
	(segment
		(start 119.875 81.43)
		(end 119.875 72.48)
		(width 0.15)
		(layer "In2.Cu")
		(net 317)
	)
	(segment
		(start 119.875 72.48)
		(end 120.3 72.055)
		(width 0.15)
		(layer "In2.Cu")
		(net 317)
	)
	(segment
		(start 107.275 111.675)
		(end 107.275 111.021432)
		(width 0.15)
		(layer "In2.Cu")
		(net 317)
	)
	(segment
		(start 107.275 111.021432)
		(end 113 105.296432)
		(width 0.15)
		(layer "In2.Cu")
		(net 317)
	)
	(segment
		(start 113 105.296432)
		(end 113 88.305)
		(width 0.15)
		(layer "In2.Cu")
		(net 317)
	)
	(segment
		(start 108.775 111.175)
		(end 108.275 111.675)
		(width 0.15)
		(layer "F.Cu")
		(net 318)
	)
	(segment
		(start 120.325 75.155)
		(end 120.3 75.13)
		(width 0.15)
		(layer "F.Cu")
		(net 318)
	)
	(segment
		(start 120.325 76.005)
		(end 120.325 75.155)
		(width 0.15)
		(layer "F.Cu")
		(net 318)
	)
	(via blind
		(at 108.275 111.675)
		(size 0.5)
		(drill 0.2)
		(layers "F.Cu" "In2.Cu")
		(net 318)
	)
	(via
		(at 120.325 76.005)
		(size 0.5)
		(drill 0.2)
		(layers "F.Cu" "B.Cu")
		(net 318)
	)
	(segment
		(start 113.3 88.481068)
		(end 120.325 81.456068)
		(width 0.15)
		(layer "In2.Cu")
		(net 318)
	)
	(segment
		(start 108.275 111.675)
		(end 108.275 110.375)
		(width 0.15)
		(layer "In2.Cu")
		(net 318)
	)
	(segment
		(start 120.325 81.456068)
		(end 120.325 76.005)
		(width 0.15)
		(layer "In2.Cu")
		(net 318)
	)
	(segment
		(start 113.3 105.35)
		(end 113.3 88.481068)
		(width 0.15)
		(layer "In2.Cu")
		(net 318)
	)
	(segment
		(start 108.275 110.375)
		(end 113.3 105.35)
		(width 0.15)
		(layer "In2.Cu")
		(net 318)
	)
	(segment
		(start 87.67 82.775)
		(end 88.475 82.775)
		(width 0.15)
		(layer "F.Cu")
		(net 319)
	)
	(segment
		(start 88.475 82.775)
		(end 89.075 83.375)
		(width 0.15)
		(layer "F.Cu")
		(net 319)
	)
	(segment
		(start 89.075 83.375)
		(end 89.49 83.375)
		(width 0.15)
		(layer "F.Cu")
		(net 319)
	)
	(segment
		(start 75.072 158.44622)
		(end 75.072 156.578)
		(width 0.15)
		(layer "F.Cu")
		(net 320)
	)
	(segment
		(start 82.585 159.235)
		(end 87.925 159.235)
		(width 0.15)
		(layer "F.Cu")
		(net 320)
	)
	(segment
		(start 75.45078 159.875)
		(end 76.6 159.875)
		(width 0.15)
		(layer "F.Cu")
		(net 320)
	)
	(segment
		(start 75.072 158.44622)
		(end 75.072 159.49622)
		(width 0.15)
		(layer "F.Cu")
		(net 320)
	)
	(segment
		(start 87.925 159.235)
		(end 88.98 160.29)
		(width 0.15)
		(layer "F.Cu")
		(net 320)
	)
	(segment
		(start 75.072 156.578)
		(end 75.075 156.575)
		(width 0.15)
		(layer "F.Cu")
		(net 320)
	)
	(segment
		(start 90.59 160.29)
		(end 90.64 160.34)
		(width 0.15)
		(layer "F.Cu")
		(net 320)
	)
	(segment
		(start 77.015 160.29)
		(end 81.53 160.29)
		(width 0.15)
		(layer "F.Cu")
		(net 320)
	)
	(segment
		(start 75.072 158.44622)
		(end 75.072 156.982)
		(width 0.15)
		(layer "F.Cu")
		(net 320)
	)
	(segment
		(start 76.6 159.875)
		(end 77.015 160.29)
		(width 0.15)
		(layer "F.Cu")
		(net 320)
	)
	(segment
		(start 88.98 160.29)
		(end 90.59 160.29)
		(width 0.15)
		(layer "F.Cu")
		(net 320)
	)
	(segment
		(start 75.072 159.49622)
		(end 75.45078 159.875)
		(width 0.15)
		(layer "F.Cu")
		(net 320)
	)
	(segment
		(start 81.53 160.29)
		(end 82.585 159.235)
		(width 0.15)
		(layer "F.Cu")
		(net 320)
	)
	(segment
		(start 75.072 156.982)
		(end 75.07 156.98)
		(width 0.15)
		(layer "F.Cu")
		(net 320)
	)
	(segment
		(start 100.775 119.175)
		(end 101.275 119.675)
		(width 0.15)
		(layer "F.Cu")
		(net 320)
	)
	(via
		(at 90.64 160.34)
		(size 0.5)
		(drill 0.2)
		(layers "F.Cu" "B.Cu")
		(net 320)
	)
	(via
		(at 75.075 156.575)
		(size 0.5)
		(drill 0.2)
		(layers "F.Cu" "B.Cu")
		(net 320)
	)
	(via blind
		(at 101.275 119.675)
		(size 0.5)
		(drill 0.2)
		(layers "F.Cu" "In5.Cu")
		(net 320)
	)
	(segment
		(start 74.06 155.775)
		(end 75.06 155.775)
		(width 0.15)
		(layer "B.Cu")
		(net 320)
	)
	(segment
		(start 75.075 155.76)
		(end 75.075 156.575)
		(width 0.15)
		(layer "B.Cu")
		(net 320)
	)
	(segment
		(start 75.06 155.775)
		(end 75.075 155.76)
		(width 0.15)
		(layer "B.Cu")
		(net 320)
	)
	(segment
		(start 89.451474 120.349968)
		(end 85.150289 124.651153)
		(width 0.15)
		(layer "In5.Cu")
		(net 320)
	)
	(segment
		(start 100.799999 120.150001)
		(end 91.999999 120.150001)
		(width 0.15)
		(layer "In5.Cu")
		(net 320)
	)
	(segment
		(start 101.275 119.675)
		(end 100.799999 120.150001)
		(width 0.15)
		(layer "In5.Cu")
		(net 320)
	)
	(segment
		(start 85.150289 155.003842)
		(end 90.486447 160.34)
		(width 0.15)
		(layer "In5.Cu")
		(net 320)
	)
	(segment
		(start 91.999999 120.150001)
		(end 91.800032 120.349968)
		(width 0.15)
		(layer "In5.Cu")
		(net 320)
	)
	(segment
		(start 91.800032 120.349968)
		(end 89.451474 120.349968)
		(width 0.15)
		(layer "In5.Cu")
		(net 320)
	)
	(segment
		(start 90.486447 160.34)
		(end 90.64 160.34)
		(width 0.15)
		(layer "In5.Cu")
		(net 320)
	)
	(segment
		(start 85.150289 124.651153)
		(end 85.150289 155.003842)
		(width 0.15)
		(layer "In5.Cu")
		(net 320)
	)
	(segment
		(start 103.775 114.175)
		(end 104.275 114.675)
		(width 0.15)
		(layer "F.Cu")
		(net 321)
	)
	(segment
		(start 142.274 124.004)
		(end 141.784 123.514)
		(width 0.15)
		(layer "F.Cu")
		(net 321)
	)
	(via
		(at 141.784 123.514)
		(size 0.5)
		(drill 0.2)
		(layers "F.Cu" "B.Cu")
		(net 321)
	)
	(via blind
		(at 104.275 114.675)
		(size 0.5)
		(drill 0.2)
		(layers "F.Cu" "In2.Cu")
		(net 321)
	)
	(segment
		(start 141.789 124.214)
		(end 141.789 123.519)
		(width 0.15)
		(layer "B.Cu")
		(net 321)
	)
	(segment
		(start 141.789 123.519)
		(end 141.784 123.514)
		(width 0.15)
		(layer "B.Cu")
		(net 321)
	)
	(segment
		(start 140.174082 124.328855)
		(end 140.142378 124.317761)
		(width 0.15)
		(layer "In2.Cu")
		(net 321)
	)
	(segment
		(start 140.226274 124.370477)
		(end 140.202523 124.346726)
		(width 0.15)
		(layer "In2.Cu")
		(net 321)
	)
	(segment
		(start 140.952825 124.303091)
		(end 140.944908 124.295174)
		(width 0.15)
		(layer "In2.Cu")
		(net 321)
	)
	(segment
		(start 140.409 124.873517)
		(end 140.375621 124.869757)
		(width 0.15)
		(layer "In2.Cu")
		(net 321)
	)
	(segment
		(start 140.923091 124.232825)
		(end 140.915174 124.224908)
		(width 0.15)
		(layer "In2.Cu")
		(net 321)
	)
	(segment
		(start 140.932746 124.252873)
		(end 140.929048 124.242305)
		(width 0.15)
		(layer "In2.Cu")
		(net 321)
	)
	(segment
		(start 140.662305 124.218951)
		(end 140.652825 124.224908)
		(width 0.15)
		(layer "In2.Cu")
		(net 321)
	)
	(segment
		(start 140.652825 124.224908)
		(end 140.644908 124.232825)
		(width 0.15)
		(layer "In2.Cu")
		(net 321)
	)
	(segment
		(start 140.259 124.723517)
		(end 140.259 124.464)
		(width 0.15)
		(layer "In2.Cu")
		(net 321)
	)
	(segment
		(start 140.972873 124.312746)
		(end 140.962305 124.309048)
		(width 0.15)
		(layer "In2.Cu")
		(net 321)
	)
	(segment
		(start 140.905694 124.218951)
		(end 140.895126 124.215253)
		(width 0.15)
		(layer "In2.Cu")
		(net 321)
	)
	(segment
		(start 140.555239 124.756896)
		(end 140.544145 124.7886)
		(width 0.15)
		(layer "In2.Cu")
		(net 321)
	)
	(segment
		(start 140.672873 124.215253)
		(end 140.662305 124.218951)
		(width 0.15)
		(layer "In2.Cu")
		(net 321)
	)
	(segment
		(start 124.975 123.575)
		(end 120.975 123.575)
		(width 0.15)
		(layer "In2.Cu")
		(net 321)
	)
	(segment
		(start 140.634 124.264)
		(end 140.634 124.314)
		(width 0.15)
		(layer "In2.Cu")
		(net 321)
	)
	(segment
		(start 104.575 116.475)
		(end 104.275 116.175)
		(width 0.15)
		(layer "In2.Cu")
		(net 321)
	)
	(segment
		(start 104.275 116.175)
		(end 104.275 114.675)
		(width 0.15)
		(layer "In2.Cu")
		(net 321)
	)
	(segment
		(start 140.343917 124.858663)
		(end 140.315476 124.840792)
		(width 0.15)
		(layer "In2.Cu")
		(net 321)
	)
	(segment
		(start 115.574981 118.174981)
		(end 111.974981 118.174981)
		(width 0.15)
		(layer "In2.Cu")
		(net 321)
	)
	(segment
		(start 141.784 123.514)
		(end 140.984 124.314)
		(width 0.15)
		(layer "In2.Cu")
		(net 321)
	)
	(segment
		(start 140.291725 124.817041)
		(end 140.273854 124.7886)
		(width 0.15)
		(layer "In2.Cu")
		(net 321)
	)
	(segment
		(start 140.255239 124.430622)
		(end 140.244145 124.398918)
		(width 0.15)
		(layer "In2.Cu")
		(net 321)
	)
	(segment
		(start 140.315476 124.840792)
		(end 140.291725 124.817041)
		(width 0.15)
		(layer "In2.Cu")
		(net 321)
	)
	(segment
		(start 140.634 124.314)
		(end 140.559 124.314)
		(width 0.15)
		(layer "In2.Cu")
		(net 321)
	)
	(segment
		(start 140.929048 124.242305)
		(end 140.923091 124.232825)
		(width 0.15)
		(layer "In2.Cu")
		(net 321)
	)
	(segment
		(start 140.142378 124.317761)
		(end 140.109 124.314)
		(width 0.15)
		(layer "In2.Cu")
		(net 321)
	)
	(segment
		(start 140.895126 124.215253)
		(end 140.884 124.214)
		(width 0.15)
		(layer "In2.Cu")
		(net 321)
	)
	(segment
		(start 140.884 124.214)
		(end 140.684 124.214)
		(width 0.15)
		(layer "In2.Cu")
		(net 321)
	)
	(segment
		(start 111.174982 117.374982)
		(end 110.750722 117.374982)
		(width 0.15)
		(layer "In2.Cu")
		(net 321)
	)
	(segment
		(start 140.944908 124.295174)
		(end 140.938951 124.285694)
		(width 0.15)
		(layer "In2.Cu")
		(net 321)
	)
	(segment
		(start 140.638951 124.242305)
		(end 140.635253 124.252873)
		(width 0.15)
		(layer "In2.Cu")
		(net 321)
	)
	(segment
		(start 140.474082 124.858663)
		(end 140.442378 124.869757)
		(width 0.15)
		(layer "In2.Cu")
		(net 321)
	)
	(segment
		(start 106.075 116.475)
		(end 104.575 116.475)
		(width 0.15)
		(layer "In2.Cu")
		(net 321)
	)
	(segment
		(start 140.559 124.723517)
		(end 140.555239 124.756896)
		(width 0.15)
		(layer "In2.Cu")
		(net 321)
	)
	(segment
		(start 139.848 124.575)
		(end 125.975 124.575)
		(width 0.15)
		(layer "In2.Cu")
		(net 321)
	)
	(segment
		(start 140.635253 124.252873)
		(end 140.634 124.264)
		(width 0.15)
		(layer "In2.Cu")
		(net 321)
	)
	(segment
		(start 111.974981 118.174981)
		(end 111.174982 117.374982)
		(width 0.15)
		(layer "In2.Cu")
		(net 321)
	)
	(segment
		(start 140.938951 124.285694)
		(end 140.935253 124.275126)
		(width 0.15)
		(layer "In2.Cu")
		(net 321)
	)
	(segment
		(start 140.109 124.314)
		(end 139.848 124.575)
		(width 0.15)
		(layer "In2.Cu")
		(net 321)
	)
	(segment
		(start 140.442378 124.869757)
		(end 140.409 124.873517)
		(width 0.15)
		(layer "In2.Cu")
		(net 321)
	)
	(segment
		(start 140.644908 124.232825)
		(end 140.638951 124.242305)
		(width 0.15)
		(layer "In2.Cu")
		(net 321)
	)
	(segment
		(start 140.984 124.314)
		(end 140.972873 124.312746)
		(width 0.15)
		(layer "In2.Cu")
		(net 321)
	)
	(segment
		(start 110.750722 117.374982)
		(end 110.750714 117.37499)
		(width 0.15)
		(layer "In2.Cu")
		(net 321)
	)
	(segment
		(start 140.244145 124.398918)
		(end 140.226274 124.370477)
		(width 0.15)
		(layer "In2.Cu")
		(net 321)
	)
	(segment
		(start 140.962305 124.309048)
		(end 140.952825 124.303091)
		(width 0.15)
		(layer "In2.Cu")
		(net 321)
	)
	(segment
		(start 140.26276 124.756896)
		(end 140.259 124.723517)
		(width 0.15)
		(layer "In2.Cu")
		(net 321)
	)
	(segment
		(start 140.915174 124.224908)
		(end 140.905694 124.218951)
		(width 0.15)
		(layer "In2.Cu")
		(net 321)
	)
	(segment
		(start 140.259 124.464)
		(end 140.255239 124.430622)
		(width 0.15)
		(layer "In2.Cu")
		(net 321)
	)
	(segment
		(start 140.202523 124.346726)
		(end 140.174082 124.328855)
		(width 0.15)
		(layer "In2.Cu")
		(net 321)
	)
	(segment
		(start 125.975 124.575)
		(end 124.975 123.575)
		(width 0.15)
		(layer "In2.Cu")
		(net 321)
	)
	(segment
		(start 140.526274 124.817041)
		(end 140.502523 124.840792)
		(width 0.15)
		(layer "In2.Cu")
		(net 321)
	)
	(segment
		(start 140.684 124.214)
		(end 140.672873 124.215253)
		(width 0.15)
		(layer "In2.Cu")
		(net 321)
	)
	(segment
		(start 140.502523 124.840792)
		(end 140.474082 124.858663)
		(width 0.15)
		(layer "In2.Cu")
		(net 321)
	)
	(segment
		(start 140.375621 124.869757)
		(end 140.343917 124.858663)
		(width 0.15)
		(layer "In2.Cu")
		(net 321)
	)
	(segment
		(start 140.935253 124.275126)
		(end 140.932746 124.252873)
		(width 0.15)
		(layer "In2.Cu")
		(net 321)
	)
	(segment
		(start 110.750714 117.37499)
		(end 106.97499 117.37499)
		(width 0.15)
		(layer "In2.Cu")
		(net 321)
	)
	(segment
		(start 120.975 123.575)
		(end 115.574981 118.174981)
		(width 0.15)
		(layer "In2.Cu")
		(net 321)
	)
	(segment
		(start 106.97499 117.37499)
		(end 106.075 116.475)
		(width 0.15)
		(layer "In2.Cu")
		(net 321)
	)
	(segment
		(start 140.544145 124.7886)
		(end 140.526274 124.817041)
		(width 0.15)
		(layer "In2.Cu")
		(net 321)
	)
	(segment
		(start 140.273854 124.7886)
		(end 140.26276 124.756896)
		(width 0.15)
		(layer "In2.Cu")
		(net 321)
	)
	(segment
		(start 140.559 124.314)
		(end 140.559 124.723517)
		(width 0.15)
		(layer "In2.Cu")
		(net 321)
	)
	(segment
		(start 108.775 114.175)
		(end 109.275 113.675)
		(width 0.15)
		(layer "F.Cu")
		(net 322)
	)
	(segment
		(start 142.274 121.024)
		(end 142.774 121.524)
		(width 0.15)
		(layer "F.Cu")
		(net 322)
	)
	(segment
		(start 142.274 121.014)
		(end 142.274 121.024)
		(width 0.15)
		(layer "F.Cu")
		(net 322)
	)
	(via
		(at 142.774 121.524)
		(size 0.5)
		(drill 0.2)
		(layers "F.Cu" "B.Cu")
		(net 322)
	)
	(via blind
		(at 109.275 113.675)
		(size 0.5)
		(drill 0.2)
		(layers "F.Cu" "In2.Cu")
		(net 322)
	)
	(segment
		(start 142.774 121.117)
		(end 142.584 120.927)
		(width 0.15)
		(layer "B.Cu")
		(net 322)
	)
	(segment
		(start 142.774 121.524)
		(end 142.774 121.117)
		(width 0.15)
		(layer "B.Cu")
		(net 322)
	)
	(segment
		(start 129.781476 120.138657)
		(end 129.809917 120.156528)
		(width 0.15)
		(layer "In2.Cu")
		(net 322)
	)
	(segment
		(start 129.110145 119.459917)
		(end 129.121239 119.491621)
		(width 0.15)
		(layer "In2.Cu")
		(net 322)
	)
	(segment
		(start 129.421239 120.004761)
		(end 129.425 119.971383)
		(width 0.15)
		(layer "In2.Cu")
		(net 322)
	)
	(segment
		(start 130.925 120.021383)
		(end 130.92876 120.054761)
		(width 0.15)
		(layer "In2.Cu")
		(net 322)
	)
	(segment
		(start 133.575 119.375)
		(end 134.348969 120.148969)
		(width 0.15)
		(layer "In2.Cu")
		(net 322)
	)
	(segment
		(start 130.925 118.978617)
		(end 130.925 120.021383)
		(width 0.15)
		(layer "In2.Cu")
		(net 322)
	)
	(segment
		(start 131.192274 120.114906)
		(end 131.210145 120.086465)
		(width 0.15)
		(layer "In2.Cu")
		(net 322)
	)
	(segment
		(start 129.121239 119.491621)
		(end 129.125 119.525)
		(width 0.15)
		(layer "In2.Cu")
		(net 322)
	)
	(segment
		(start 130.141621 118.832378)
		(end 130.175 118.828617)
		(width 0.15)
		(layer "In2.Cu")
		(net 322)
	)
	(segment
		(start 131.22876 119.491621)
		(end 131.239854 119.459917)
		(width 0.15)
		(layer "In2.Cu")
		(net 322)
	)
	(segment
		(start 131.009917 120.156528)
		(end 131.041621 120.167622)
		(width 0.15)
		(layer "In2.Cu")
		(net 322)
	)
	(segment
		(start 130.175 118.828617)
		(end 130.208378 118.832378)
		(width 0.15)
		(layer "In2.Cu")
		(net 322)
	)
	(segment
		(start 130.625 118.978617)
		(end 130.62876 118.945239)
		(width 0.15)
		(layer "In2.Cu")
		(net 322)
	)
	(segment
		(start 131.168523 120.138657)
		(end 131.192274 120.114906)
		(width 0.15)
		(layer "In2.Cu")
		(net 322)
	)
	(segment
		(start 129.125 119.525)
		(end 129.125 119.971383)
		(width 0.15)
		(layer "In2.Cu")
		(net 322)
	)
	(segment
		(start 131.309917 119.389854)
		(end 131.341621 119.37876)
		(width 0.15)
		(layer "In2.Cu")
		(net 322)
	)
	(segment
		(start 129.541621 118.832378)
		(end 129.575 118.828617)
		(width 0.15)
		(layer "In2.Cu")
		(net 322)
	)
	(segment
		(start 131.221239 120.054761)
		(end 131.225 120.021383)
		(width 0.15)
		(layer "In2.Cu")
		(net 322)
	)
	(segment
		(start 130.240082 118.843472)
		(end 130.268523 118.861343)
		(width 0.15)
		(layer "In2.Cu")
		(net 322)
	)
	(segment
		(start 130.921239 118.945239)
		(end 130.925 118.978617)
		(width 0.15)
		(layer "In2.Cu")
		(net 322)
	)
	(segment
		(start 129.725 118.978617)
		(end 129.725 120.021383)
		(width 0.15)
		(layer "In2.Cu")
		(net 322)
	)
	(segment
		(start 130.32876 120.054761)
		(end 130.339854 120.086465)
		(width 0.15)
		(layer "In2.Cu")
		(net 322)
	)
	(segment
		(start 129.968523 120.138657)
		(end 129.992274 120.114906)
		(width 0.15)
		(layer "In2.Cu")
		(net 322)
	)
	(segment
		(start 130.681476 118.861343)
		(end 130.709917 118.843472)
		(width 0.15)
		(layer "In2.Cu")
		(net 322)
	)
	(segment
		(start 130.025 118.978617)
		(end 130.02876 118.945239)
		(width 0.15)
		(layer "In2.Cu")
		(net 322)
	)
	(segment
		(start 129.008378 119.37876)
		(end 129.040082 119.389854)
		(width 0.15)
		(layer "In2.Cu")
		(net 322)
	)
	(segment
		(start 129.340082 120.106528)
		(end 129.368523 120.088657)
		(width 0.15)
		(layer "In2.Cu")
		(net 322)
	)
	(segment
		(start 109.275 113.675)
		(end 110.37494 114.77494)
		(width 0.15)
		(layer "In2.Cu")
		(net 322)
	)
	(segment
		(start 130.039854 118.913535)
		(end 130.057725 118.885094)
		(width 0.15)
		(layer "In2.Cu")
		(net 322)
	)
	(segment
		(start 130.02876 118.945239)
		(end 130.039854 118.913535)
		(width 0.15)
		(layer "In2.Cu")
		(net 322)
	)
	(segment
		(start 130.508378 120.167622)
		(end 130.540082 120.156528)
		(width 0.15)
		(layer "In2.Cu")
		(net 322)
	)
	(segment
		(start 134.348969 120.148969)
		(end 141.375 120.148969)
		(width 0.15)
		(layer "In2.Cu")
		(net 322)
	)
	(segment
		(start 115.699216 114.77494)
		(end 120.299276 119.375)
		(width 0.15)
		(layer "In2.Cu")
		(net 322)
	)
	(segment
		(start 129.157725 120.064906)
		(end 129.181476 120.088657)
		(width 0.15)
		(layer "In2.Cu")
		(net 322)
	)
	(segment
		(start 129.368523 120.088657)
		(end 129.392274 120.064906)
		(width 0.15)
		(layer "In2.Cu")
		(net 322)
	)
	(segment
		(start 131.341621 119.37876)
		(end 131.375 119.375)
		(width 0.15)
		(layer "In2.Cu")
		(net 322)
	)
	(segment
		(start 130.957725 120.114906)
		(end 130.981476 120.138657)
		(width 0.15)
		(layer "In2.Cu")
		(net 322)
	)
	(segment
		(start 128.975 119.375)
		(end 129.008378 119.37876)
		(width 0.15)
		(layer "In2.Cu")
		(net 322)
	)
	(segment
		(start 130.709917 118.843472)
		(end 130.741621 118.832378)
		(width 0.15)
		(layer "In2.Cu")
		(net 322)
	)
	(segment
		(start 129.410145 120.036465)
		(end 129.421239 120.004761)
		(width 0.15)
		(layer "In2.Cu")
		(net 322)
	)
	(segment
		(start 129.72876 120.054761)
		(end 129.739854 120.086465)
		(width 0.15)
		(layer "In2.Cu")
		(net 322)
	)
	(segment
		(start 130.592274 120.114906)
		(end 130.610145 120.086465)
		(width 0.15)
		(layer "In2.Cu")
		(net 322)
	)
	(segment
		(start 129.668523 118.861343)
		(end 129.692274 118.885094)
		(width 0.15)
		(layer "In2.Cu")
		(net 322)
	)
	(segment
		(start 130.741621 118.832378)
		(end 130.775 118.828617)
		(width 0.15)
		(layer "In2.Cu")
		(net 322)
	)
	(segment
		(start 130.357725 120.114906)
		(end 130.381476 120.138657)
		(width 0.15)
		(layer "In2.Cu")
		(net 322)
	)
	(segment
		(start 130.540082 120.156528)
		(end 130.568523 120.138657)
		(width 0.15)
		(layer "In2.Cu")
		(net 322)
	)
	(segment
		(start 129.841621 120.167622)
		(end 129.875 120.171383)
		(width 0.15)
		(layer "In2.Cu")
		(net 322)
	)
	(segment
		(start 129.425 118.978617)
		(end 129.42876 118.945239)
		(width 0.15)
		(layer "In2.Cu")
		(net 322)
	)
	(segment
		(start 131.375 119.375)
		(end 133.575 119.375)
		(width 0.15)
		(layer "In2.Cu")
		(net 322)
	)
	(segment
		(start 130.892274 118.885094)
		(end 130.910145 118.913535)
		(width 0.15)
		(layer "In2.Cu")
		(net 322)
	)
	(segment
		(start 129.940082 120.156528)
		(end 129.968523 120.138657)
		(width 0.15)
		(layer "In2.Cu")
		(net 322)
	)
	(segment
		(start 129.725 120.021383)
		(end 129.72876 120.054761)
		(width 0.15)
		(layer "In2.Cu")
		(net 322)
	)
	(segment
		(start 130.321239 118.945239)
		(end 130.325 118.978617)
		(width 0.15)
		(layer "In2.Cu")
		(net 322)
	)
	(segment
		(start 131.210145 120.086465)
		(end 131.221239 120.054761)
		(width 0.15)
		(layer "In2.Cu")
		(net 322)
	)
	(segment
		(start 130.840082 118.843472)
		(end 130.868523 118.861343)
		(width 0.15)
		(layer "In2.Cu")
		(net 322)
	)
	(segment
		(start 131.225 119.525)
		(end 131.22876 119.491621)
		(width 0.15)
		(layer "In2.Cu")
		(net 322)
	)
	(segment
		(start 129.692274 118.885094)
		(end 129.710145 118.913535)
		(width 0.15)
		(layer "In2.Cu")
		(net 322)
	)
	(segment
		(start 131.281476 119.407725)
		(end 131.309917 119.389854)
		(width 0.15)
		(layer "In2.Cu")
		(net 322)
	)
	(segment
		(start 129.12876 120.004761)
		(end 129.139854 120.036465)
		(width 0.15)
		(layer "In2.Cu")
		(net 322)
	)
	(segment
		(start 130.92876 120.054761)
		(end 130.939854 120.086465)
		(width 0.15)
		(layer "In2.Cu")
		(net 322)
	)
	(segment
		(start 142.774 121.524)
		(end 141.398969 120.148969)
		(width 0.15)
		(layer "In2.Cu")
		(net 322)
	)
	(segment
		(start 120.299276 119.375)
		(end 128.975 119.375)
		(width 0.15)
		(layer "In2.Cu")
		(net 322)
	)
	(segment
		(start 130.409917 120.156528)
		(end 130.441621 120.167622)
		(width 0.15)
		(layer "In2.Cu")
		(net 322)
	)
	(segment
		(start 129.439854 118.913535)
		(end 129.457725 118.885094)
		(width 0.15)
		(layer "In2.Cu")
		(net 322)
	)
	(segment
		(start 131.075 120.171383)
		(end 131.108378 120.167622)
		(width 0.15)
		(layer "In2.Cu")
		(net 322)
	)
	(segment
		(start 129.139854 120.036465)
		(end 129.157725 120.064906)
		(width 0.15)
		(layer "In2.Cu")
		(net 322)
	)
	(segment
		(start 130.292274 118.885094)
		(end 130.310145 118.913535)
		(width 0.15)
		(layer "In2.Cu")
		(net 322)
	)
	(segment
		(start 130.868523 118.861343)
		(end 130.892274 118.885094)
		(width 0.15)
		(layer "In2.Cu")
		(net 322)
	)
	(segment
		(start 130.657725 118.885094)
		(end 130.681476 118.861343)
		(width 0.15)
		(layer "In2.Cu")
		(net 322)
	)
	(segment
		(start 130.981476 120.138657)
		(end 131.009917 120.156528)
		(width 0.15)
		(layer "In2.Cu")
		(net 322)
	)
	(segment
		(start 110.37494 114.77494)
		(end 115.699216 114.77494)
		(width 0.15)
		(layer "In2.Cu")
		(net 322)
	)
	(segment
		(start 129.757725 120.114906)
		(end 129.781476 120.138657)
		(width 0.15)
		(layer "In2.Cu")
		(net 322)
	)
	(segment
		(start 130.775 118.828617)
		(end 130.808378 118.832378)
		(width 0.15)
		(layer "In2.Cu")
		(net 322)
	)
	(segment
		(start 129.42876 118.945239)
		(end 129.439854 118.913535)
		(width 0.15)
		(layer "In2.Cu")
		(net 322)
	)
	(segment
		(start 129.092274 119.431476)
		(end 129.110145 119.459917)
		(width 0.15)
		(layer "In2.Cu")
		(net 322)
	)
	(segment
		(start 130.62876 118.945239)
		(end 130.639854 118.913535)
		(width 0.15)
		(layer "In2.Cu")
		(net 322)
	)
	(segment
		(start 130.021239 120.054761)
		(end 130.025 120.021383)
		(width 0.15)
		(layer "In2.Cu")
		(net 322)
	)
	(segment
		(start 130.339854 120.086465)
		(end 130.357725 120.114906)
		(width 0.15)
		(layer "In2.Cu")
		(net 322)
	)
	(segment
		(start 129.125 119.971383)
		(end 129.12876 120.004761)
		(width 0.15)
		(layer "In2.Cu")
		(net 322)
	)
	(segment
		(start 129.575 118.828617)
		(end 129.608378 118.832378)
		(width 0.15)
		(layer "In2.Cu")
		(net 322)
	)
	(segment
		(start 130.621239 120.054761)
		(end 130.625 120.021383)
		(width 0.15)
		(layer "In2.Cu")
		(net 322)
	)
	(segment
		(start 129.457725 118.885094)
		(end 129.481476 118.861343)
		(width 0.15)
		(layer "In2.Cu")
		(net 322)
	)
	(segment
		(start 129.875 120.171383)
		(end 129.908378 120.167622)
		(width 0.15)
		(layer "In2.Cu")
		(net 322)
	)
	(segment
		(start 129.181476 120.088657)
		(end 129.209917 120.106528)
		(width 0.15)
		(layer "In2.Cu")
		(net 322)
	)
	(segment
		(start 130.381476 120.138657)
		(end 130.409917 120.156528)
		(width 0.15)
		(layer "In2.Cu")
		(net 322)
	)
	(segment
		(start 129.710145 118.913535)
		(end 129.721239 118.945239)
		(width 0.15)
		(layer "In2.Cu")
		(net 322)
	)
	(segment
		(start 129.040082 119.389854)
		(end 129.068523 119.407725)
		(width 0.15)
		(layer "In2.Cu")
		(net 322)
	)
	(segment
		(start 129.908378 120.167622)
		(end 129.940082 120.156528)
		(width 0.15)
		(layer "In2.Cu")
		(net 322)
	)
	(segment
		(start 129.640082 118.843472)
		(end 129.668523 118.861343)
		(width 0.15)
		(layer "In2.Cu")
		(net 322)
	)
	(segment
		(start 129.241621 120.117622)
		(end 129.275 120.121383)
		(width 0.15)
		(layer "In2.Cu")
		(net 322)
	)
	(segment
		(start 130.010145 120.086465)
		(end 130.021239 120.054761)
		(width 0.15)
		(layer "In2.Cu")
		(net 322)
	)
	(segment
		(start 129.509917 118.843472)
		(end 129.541621 118.832378)
		(width 0.15)
		(layer "In2.Cu")
		(net 322)
	)
	(segment
		(start 130.639854 118.913535)
		(end 130.657725 118.885094)
		(width 0.15)
		(layer "In2.Cu")
		(net 322)
	)
	(segment
		(start 129.809917 120.156528)
		(end 129.841621 120.167622)
		(width 0.15)
		(layer "In2.Cu")
		(net 322)
	)
	(segment
		(start 131.041621 120.167622)
		(end 131.075 120.171383)
		(width 0.15)
		(layer "In2.Cu")
		(net 322)
	)
	(segment
		(start 129.992274 120.114906)
		(end 130.010145 120.086465)
		(width 0.15)
		(layer "In2.Cu")
		(net 322)
	)
	(segment
		(start 130.025 120.021383)
		(end 130.025 118.978617)
		(width 0.15)
		(layer "In2.Cu")
		(net 322)
	)
	(segment
		(start 130.081476 118.861343)
		(end 130.109917 118.843472)
		(width 0.15)
		(layer "In2.Cu")
		(net 322)
	)
	(segment
		(start 129.275 120.121383)
		(end 129.308378 120.117622)
		(width 0.15)
		(layer "In2.Cu")
		(net 322)
	)
	(segment
		(start 130.610145 120.086465)
		(end 130.621239 120.054761)
		(width 0.15)
		(layer "In2.Cu")
		(net 322)
	)
	(segment
		(start 129.209917 120.106528)
		(end 129.241621 120.117622)
		(width 0.15)
		(layer "In2.Cu")
		(net 322)
	)
	(segment
		(start 129.481476 118.861343)
		(end 129.509917 118.843472)
		(width 0.15)
		(layer "In2.Cu")
		(net 322)
	)
	(segment
		(start 131.257725 119.431476)
		(end 131.281476 119.407725)
		(width 0.15)
		(layer "In2.Cu")
		(net 322)
	)
	(segment
		(start 130.441621 120.167622)
		(end 130.475 120.171383)
		(width 0.15)
		(layer "In2.Cu")
		(net 322)
	)
	(segment
		(start 130.939854 120.086465)
		(end 130.957725 120.114906)
		(width 0.15)
		(layer "In2.Cu")
		(net 322)
	)
	(segment
		(start 130.475 120.171383)
		(end 130.508378 120.167622)
		(width 0.15)
		(layer "In2.Cu")
		(net 322)
	)
	(segment
		(start 130.109917 118.843472)
		(end 130.141621 118.832378)
		(width 0.15)
		(layer "In2.Cu")
		(net 322)
	)
	(segment
		(start 129.608378 118.832378)
		(end 129.640082 118.843472)
		(width 0.15)
		(layer "In2.Cu")
		(net 322)
	)
	(segment
		(start 130.268523 118.861343)
		(end 130.292274 118.885094)
		(width 0.15)
		(layer "In2.Cu")
		(net 322)
	)
	(segment
		(start 129.739854 120.086465)
		(end 129.757725 120.114906)
		(width 0.15)
		(layer "In2.Cu")
		(net 322)
	)
	(segment
		(start 130.808378 118.832378)
		(end 130.840082 118.843472)
		(width 0.15)
		(layer "In2.Cu")
		(net 322)
	)
	(segment
		(start 130.325 118.978617)
		(end 130.325 120.021383)
		(width 0.15)
		(layer "In2.Cu")
		(net 322)
	)
	(segment
		(start 130.208378 118.832378)
		(end 130.240082 118.843472)
		(width 0.15)
		(layer "In2.Cu")
		(net 322)
	)
	(segment
		(start 131.239854 119.459917)
		(end 131.257725 119.431476)
		(width 0.15)
		(layer "In2.Cu")
		(net 322)
	)
	(segment
		(start 131.108378 120.167622)
		(end 131.140082 120.156528)
		(width 0.15)
		(layer "In2.Cu")
		(net 322)
	)
	(segment
		(start 130.310145 118.913535)
		(end 130.321239 118.945239)
		(width 0.15)
		(layer "In2.Cu")
		(net 322)
	)
	(segment
		(start 129.308378 120.117622)
		(end 129.340082 120.106528)
		(width 0.15)
		(layer "In2.Cu")
		(net 322)
	)
	(segment
		(start 130.625 120.021383)
		(end 130.625 118.978617)
		(width 0.15)
		(layer "In2.Cu")
		(net 322)
	)
	(segment
		(start 130.057725 118.885094)
		(end 130.081476 118.861343)
		(width 0.15)
		(layer "In2.Cu")
		(net 322)
	)
	(segment
		(start 130.910145 118.913535)
		(end 130.921239 118.945239)
		(width 0.15)
		(layer "In2.Cu")
		(net 322)
	)
	(segment
		(start 129.392274 120.064906)
		(end 129.410145 120.036465)
		(width 0.15)
		(layer "In2.Cu")
		(net 322)
	)
	(segment
		(start 130.568523 120.138657)
		(end 130.592274 120.114906)
		(width 0.15)
		(layer "In2.Cu")
		(net 322)
	)
	(segment
		(start 129.721239 118.945239)
		(end 129.725 118.978617)
		(width 0.15)
		(layer "In2.Cu")
		(net 322)
	)
	(segment
		(start 131.225 120.021383)
		(end 131.225 119.525)
		(width 0.15)
		(layer "In2.Cu")
		(net 322)
	)
	(segment
		(start 130.325 120.021383)
		(end 130.32876 120.054761)
		(width 0.15)
		(layer "In2.Cu")
		(net 322)
	)
	(segment
		(start 131.140082 120.156528)
		(end 131.168523 120.138657)
		(width 0.15)
		(layer "In2.Cu")
		(net 322)
	)
	(segment
		(start 129.068523 119.407725)
		(end 129.092274 119.431476)
		(width 0.15)
		(layer "In2.Cu")
		(net 322)
	)
	(segment
		(start 129.425 119.971383)
		(end 129.425 118.978617)
		(width 0.15)
		(layer "In2.Cu")
		(net 322)
	)
	(segment
		(start 141.274 124.004)
		(end 140.784 123.514)
		(width 0.15)
		(layer "F.Cu")
		(net 323)
	)
	(segment
		(start 104.775 113.175)
		(end 104.275 113.675)
		(width 0.15)
		(layer "F.Cu")
		(net 323)
	)
	(via
		(at 140.784 123.514)
		(size 0.5)
		(drill 0.2)
		(layers "F.Cu" "B.Cu")
		(net 323)
	)
	(via blind
		(at 104.275 113.675)
		(size 0.5)
		(drill 0.2)
		(layers "F.Cu" "In2.Cu")
		(net 323)
	)
	(segment
		(start 140.759 123.539)
		(end 140.784 123.514)
		(width 0.15)
		(layer "B.Cu")
		(net 323)
	)
	(segment
		(start 140.759 124.214)
		(end 140.759 123.539)
		(width 0.15)
		(layer "B.Cu")
		(net 323)
	)
	(segment
		(start 137.625853 123.904083)
		(end 137.614759 123.872379)
		(width 0.15)
		(layer "In2.Cu")
		(net 323)
	)
	(segment
		(start 138.994377 123.98524)
		(end 138.960999 123.989001)
		(width 0.15)
		(layer "In2.Cu")
		(net 323)
	)
	(segment
		(start 140.010999 123.176204)
		(end 140.007238 123.142825)
		(width 0.15)
		(layer "In2.Cu")
		(net 323)
	)
	(segment
		(start 138.094377 123.029964)
		(end 138.060999 123.026204)
		(width 0.15)
		(layer "In2.Cu")
		(net 323)
	)
	(segment
		(start 139.443724 123.932524)
		(end 139.425853 123.904083)
		(width 0.15)
		(layer "In2.Cu")
		(net 323)
	)
	(segment
		(start 139.707238 123.872379)
		(end 139.696144 123.904083)
		(width 0.15)
		(layer "In2.Cu")
		(net 323)
	)
	(segment
		(start 138.895916 123.974146)
		(end 138.867475 123.956275)
		(width 0.15)
		(layer "In2.Cu")
		(net 323)
	)
	(segment
		(start 137.226081 123.974146)
		(end 137.194377 123.98524)
		(width 0.15)
		(layer "In2.Cu")
		(net 323)
	)
	(segment
		(start 137.194377 123.98524)
		(end 137.160999 123.989001)
		(width 0.15)
		(layer "In2.Cu")
		(net 323)
	)
	(segment
		(start 139.107238 123.872379)
		(end 139.096144 123.904083)
		(width 0.15)
		(layer "In2.Cu")
		(net 323)
	)
	(segment
		(start 137.578273 123.08268)
		(end 137.554522 123.058929)
		(width 0.15)
		(layer "In2.Cu")
		(net 323)
	)
	(segment
		(start 139.978273 123.08268)
		(end 139.954522 123.058929)
		(width 0.15)
		(layer "In2.Cu")
		(net 323)
	)
	(segment
		(start 104.975 116.175)
		(end 104.750001 115.950001)
		(width 0.15)
		(layer "In2.Cu")
		(net 323)
	)
	(segment
		(start 138.796144 123.111121)
		(end 138.778273 123.08268)
		(width 0.15)
		(layer "In2.Cu")
		(net 323)
	)
	(segment
		(start 139.378273 123.08268)
		(end 139.354522 123.058929)
		(width 0.15)
		(layer "In2.Cu")
		(net 323)
	)
	(segment
		(start 137.310999 123.839001)
		(end 137.307238 123.872379)
		(width 0.15)
		(layer "In2.Cu")
		(net 323)
	)
	(segment
		(start 139.078273 123.932524)
		(end 139.054522 123.956275)
		(width 0.15)
		(layer "In2.Cu")
		(net 323)
	)
	(segment
		(start 137.914759 123.142825)
		(end 137.910999 123.176204)
		(width 0.15)
		(layer "In2.Cu")
		(net 323)
	)
	(segment
		(start 139.678273 123.932524)
		(end 139.654522 123.956275)
		(width 0.15)
		(layer "In2.Cu")
		(net 323)
	)
	(segment
		(start 137.307238 123.872379)
		(end 137.296144 123.904083)
		(width 0.15)
		(layer "In2.Cu")
		(net 323)
	)
	(segment
		(start 138.243724 123.932524)
		(end 138.225853 123.904083)
		(width 0.15)
		(layer "In2.Cu")
		(net 323)
	)
	(segment
		(start 137.925853 123.111121)
		(end 137.914759 123.142825)
		(width 0.15)
		(layer "In2.Cu")
		(net 323)
	)
	(segment
		(start 138.394377 123.98524)
		(end 138.360999 123.989001)
		(width 0.15)
		(layer "In2.Cu")
		(net 323)
	)
	(segment
		(start 139.743724 123.08268)
		(end 139.725853 123.111121)
		(width 0.15)
		(layer "In2.Cu")
		(net 323)
	)
	(segment
		(start 138.214759 123.872379)
		(end 138.210999 123.839001)
		(width 0.15)
		(layer "In2.Cu")
		(net 323)
	)
	(segment
		(start 106.199278 116.175)
		(end 104.975 116.175)
		(width 0.15)
		(layer "In2.Cu")
		(net 323)
	)
	(segment
		(start 139.467475 123.956275)
		(end 139.443724 123.932524)
		(width 0.15)
		(layer "In2.Cu")
		(net 323)
	)
	(segment
		(start 139.167475 123.058929)
		(end 139.143724 123.08268)
		(width 0.15)
		(layer "In2.Cu")
		(net 323)
	)
	(segment
		(start 139.260999 123.026204)
		(end 139.22762 123.029964)
		(width 0.15)
		(layer "In2.Cu")
		(net 323)
	)
	(segment
		(start 138.496144 123.904083)
		(end 138.478273 123.932524)
		(width 0.15)
		(layer "In2.Cu")
		(net 323)
	)
	(segment
		(start 120.999278 123.175)
		(end 114.899258 117.07498)
		(width 0.15)
		(layer "In2.Cu")
		(net 323)
	)
	(segment
		(start 138.154522 123.058929)
		(end 138.126081 123.041058)
		(width 0.15)
		(layer "In2.Cu")
		(net 323)
	)
	(segment
		(start 137.526081 123.041058)
		(end 137.494377 123.029964)
		(width 0.15)
		(layer "In2.Cu")
		(net 323)
	)
	(segment
		(start 138.525853 123.111121)
		(end 138.514759 123.142825)
		(width 0.15)
		(layer "In2.Cu")
		(net 323)
	)
	(segment
		(start 139.054522 123.956275)
		(end 139.026081 123.974146)
		(width 0.15)
		(layer "In2.Cu")
		(net 323)
	)
	(segment
		(start 137.943724 123.08268)
		(end 137.925853 123.111121)
		(width 0.15)
		(layer "In2.Cu")
		(net 323)
	)
	(segment
		(start 138.210999 123.176204)
		(end 138.207238 123.142825)
		(width 0.15)
		(layer "In2.Cu")
		(net 323)
	)
	(segment
		(start 125.075 123.175)
		(end 120.999278 123.175)
		(width 0.15)
		(layer "In2.Cu")
		(net 323)
	)
	(segment
		(start 139.894377 123.029964)
		(end 139.860999 123.026204)
		(width 0.15)
		(layer "In2.Cu")
		(net 323)
	)
	(segment
		(start 137.695916 123.974146)
		(end 137.667475 123.956275)
		(width 0.15)
		(layer "In2.Cu")
		(net 323)
	)
	(segment
		(start 137.910999 123.839001)
		(end 137.907238 123.872379)
		(width 0.15)
		(layer "In2.Cu")
		(net 323)
	)
	(segment
		(start 139.110999 123.176204)
		(end 139.110999 123.839001)
		(width 0.15)
		(layer "In2.Cu")
		(net 323)
	)
	(segment
		(start 139.22762 123.029964)
		(end 139.195916 123.041058)
		(width 0.15)
		(layer "In2.Cu")
		(net 323)
	)
	(segment
		(start 104.750001 115.950001)
		(end 104.750001 114.150001)
		(width 0.15)
		(layer "In2.Cu")
		(net 323)
	)
	(segment
		(start 137.494377 123.029964)
		(end 137.460999 123.026204)
		(width 0.15)
		(layer "In2.Cu")
		(net 323)
	)
	(segment
		(start 139.294377 123.029964)
		(end 139.260999 123.026204)
		(width 0.15)
		(layer "In2.Cu")
		(net 323)
	)
	(segment
		(start 137.254522 123.956275)
		(end 137.226081 123.974146)
		(width 0.15)
		(layer "In2.Cu")
		(net 323)
	)
	(segment
		(start 138.62762 123.029964)
		(end 138.595916 123.041058)
		(width 0.15)
		(layer "In2.Cu")
		(net 323)
	)
	(segment
		(start 137.296144 123.904083)
		(end 137.278273 123.932524)
		(width 0.15)
		(layer "In2.Cu")
		(net 323)
	)
	(segment
		(start 140.067475 123.956275)
		(end 140.043724 123.932524)
		(width 0.15)
		(layer "In2.Cu")
		(net 323)
	)
	(segment
		(start 140.007238 123.142825)
		(end 139.996144 123.111121)
		(width 0.15)
		(layer "In2.Cu")
		(net 323)
	)
	(segment
		(start 137.896144 123.904083)
		(end 137.878273 123.932524)
		(width 0.15)
		(layer "In2.Cu")
		(net 323)
	)
	(segment
		(start 139.560999 123.989001)
		(end 139.52762 123.98524)
		(width 0.15)
		(layer "In2.Cu")
		(net 323)
	)
	(segment
		(start 137.667475 123.956275)
		(end 137.643724 123.932524)
		(width 0.15)
		(layer "In2.Cu")
		(net 323)
	)
	(segment
		(start 137.967475 123.058929)
		(end 137.943724 123.08268)
		(width 0.15)
		(layer "In2.Cu")
		(net 323)
	)
	(segment
		(start 137.910999 123.176204)
		(end 137.910999 123.839001)
		(width 0.15)
		(layer "In2.Cu")
		(net 323)
	)
	(segment
		(start 138.210999 123.839001)
		(end 138.210999 123.176204)
		(width 0.15)
		(layer "In2.Cu")
		(net 323)
	)
	(segment
		(start 138.810999 123.839001)
		(end 138.810999 123.176204)
		(width 0.15)
		(layer "In2.Cu")
		(net 323)
	)
	(segment
		(start 139.407238 123.142825)
		(end 139.396144 123.111121)
		(width 0.15)
		(layer "In2.Cu")
		(net 323)
	)
	(segment
		(start 125.975 124.075)
		(end 125.075 123.175)
		(width 0.15)
		(layer "In2.Cu")
		(net 323)
	)
	(segment
		(start 138.595916 123.041058)
		(end 138.567475 123.058929)
		(width 0.15)
		(layer "In2.Cu")
		(net 323)
	)
	(segment
		(start 138.196144 123.111121)
		(end 138.178273 123.08268)
		(width 0.15)
		(layer "In2.Cu")
		(net 323)
	)
	(segment
		(start 139.125853 123.111121)
		(end 139.114759 123.142825)
		(width 0.15)
		(layer "In2.Cu")
		(net 323)
	)
	(segment
		(start 139.114759 123.142825)
		(end 139.110999 123.176204)
		(width 0.15)
		(layer "In2.Cu")
		(net 323)
	)
	(segment
		(start 137.367475 123.058929)
		(end 137.343724 123.08268)
		(width 0.15)
		(layer "In2.Cu")
		(net 323)
	)
	(segment
		(start 137.160999 123.989001)
		(end 137.075 124.075)
		(width 0.15)
		(layer "In2.Cu")
		(net 323)
	)
	(segment
		(start 107.099257 117.074979)
		(end 114.899258 117.07498)
		(width 0.15)
		(layer "In2.Cu")
		(net 323)
	)
	(segment
		(start 137.607238 123.142825)
		(end 137.596144 123.111121)
		(width 0.15)
		(layer "In2.Cu")
		(net 323)
	)
	(segment
		(start 137.278273 123.932524)
		(end 137.254522 123.956275)
		(width 0.15)
		(layer "In2.Cu")
		(net 323)
	)
	(segment
		(start 139.926081 123.041058)
		(end 139.894377 123.029964)
		(width 0.15)
		(layer "In2.Cu")
		(net 323)
	)
	(segment
		(start 138.807238 123.142825)
		(end 138.796144 123.111121)
		(width 0.15)
		(layer "In2.Cu")
		(net 323)
	)
	(segment
		(start 137.854522 123.956275)
		(end 137.826081 123.974146)
		(width 0.15)
		(layer "In2.Cu")
		(net 323)
	)
	(segment
		(start 139.52762 123.98524)
		(end 139.495916 123.974146)
		(width 0.15)
		(layer "In2.Cu")
		(net 323)
	)
	(segment
		(start 139.714759 123.142825)
		(end 139.710999 123.176204)
		(width 0.15)
		(layer "In2.Cu")
		(net 323)
	)
	(segment
		(start 138.207238 123.142825)
		(end 138.196144 123.111121)
		(width 0.15)
		(layer "In2.Cu")
		(net 323)
	)
	(segment
		(start 138.810999 123.176204)
		(end 138.807238 123.142825)
		(width 0.15)
		(layer "In2.Cu")
		(net 323)
	)
	(segment
		(start 138.660999 123.026204)
		(end 138.62762 123.029964)
		(width 0.15)
		(layer "In2.Cu")
		(net 323)
	)
	(segment
		(start 139.195916 123.041058)
		(end 139.167475 123.058929)
		(width 0.15)
		(layer "In2.Cu")
		(net 323)
	)
	(segment
		(start 138.02762 123.029964)
		(end 137.995916 123.041058)
		(width 0.15)
		(layer "In2.Cu")
		(net 323)
	)
	(segment
		(start 138.510999 123.176204)
		(end 138.510999 123.839001)
		(width 0.15)
		(layer "In2.Cu")
		(net 323)
	)
	(segment
		(start 139.143724 123.08268)
		(end 139.125853 123.111121)
		(width 0.15)
		(layer "In2.Cu")
		(net 323)
	)
	(segment
		(start 137.878273 123.932524)
		(end 137.854522 123.956275)
		(width 0.15)
		(layer "In2.Cu")
		(net 323)
	)
	(segment
		(start 139.410999 123.839001)
		(end 139.410999 123.176204)
		(width 0.15)
		(layer "In2.Cu")
		(net 323)
	)
	(segment
		(start 137.794377 123.98524)
		(end 137.760999 123.989001)
		(width 0.15)
		(layer "In2.Cu")
		(net 323)
	)
	(segment
		(start 139.326081 123.041058)
		(end 139.294377 123.029964)
		(width 0.15)
		(layer "In2.Cu")
		(net 323)
	)
	(segment
		(start 138.360999 123.989001)
		(end 138.32762 123.98524)
		(width 0.15)
		(layer "In2.Cu")
		(net 323)
	)
	(segment
		(start 138.510999 123.839001)
		(end 138.507238 123.872379)
		(width 0.15)
		(layer "In2.Cu")
		(net 323)
	)
	(segment
		(start 140.025853 123.904083)
		(end 140.014759 123.872379)
		(width 0.15)
		(layer "In2.Cu")
		(net 323)
	)
	(segment
		(start 138.814759 123.872379)
		(end 138.810999 123.839001)
		(width 0.15)
		(layer "In2.Cu")
		(net 323)
	)
	(segment
		(start 139.82762 123.029964)
		(end 139.795916 123.041058)
		(width 0.15)
		(layer "In2.Cu")
		(net 323)
	)
	(segment
		(start 139.354522 123.058929)
		(end 139.326081 123.041058)
		(width 0.15)
		(layer "In2.Cu")
		(net 323)
	)
	(segment
		(start 139.096144 123.904083)
		(end 139.078273 123.932524)
		(width 0.15)
		(layer "In2.Cu")
		(net 323)
	)
	(segment
		(start 138.567475 123.058929)
		(end 138.543724 123.08268)
		(width 0.15)
		(layer "In2.Cu")
		(net 323)
	)
	(segment
		(start 139.414759 123.872379)
		(end 139.410999 123.839001)
		(width 0.15)
		(layer "In2.Cu")
		(net 323)
	)
	(segment
		(start 138.867475 123.956275)
		(end 138.843724 123.932524)
		(width 0.15)
		(layer "In2.Cu")
		(net 323)
	)
	(segment
		(start 139.410999 123.176204)
		(end 139.407238 123.142825)
		(width 0.15)
		(layer "In2.Cu")
		(net 323)
	)
	(segment
		(start 140.010999 123.839001)
		(end 140.010999 123.176204)
		(width 0.15)
		(layer "In2.Cu")
		(net 323)
	)
	(segment
		(start 137.995916 123.041058)
		(end 137.967475 123.058929)
		(width 0.15)
		(layer "In2.Cu")
		(net 323)
	)
	(segment
		(start 140.014759 123.872379)
		(end 140.010999 123.839001)
		(width 0.15)
		(layer "In2.Cu")
		(net 323)
	)
	(segment
		(start 137.310999 123.176204)
		(end 137.310999 123.839001)
		(width 0.15)
		(layer "In2.Cu")
		(net 323)
	)
	(segment
		(start 140.160999 123.989001)
		(end 140.12762 123.98524)
		(width 0.15)
		(layer "In2.Cu")
		(net 323)
	)
	(segment
		(start 137.907238 123.872379)
		(end 137.896144 123.904083)
		(width 0.15)
		(layer "In2.Cu")
		(net 323)
	)
	(segment
		(start 138.843724 123.932524)
		(end 138.825853 123.904083)
		(width 0.15)
		(layer "In2.Cu")
		(net 323)
	)
	(segment
		(start 138.32762 123.98524)
		(end 138.295916 123.974146)
		(width 0.15)
		(layer "In2.Cu")
		(net 323)
	)
	(segment
		(start 138.825853 123.904083)
		(end 138.814759 123.872379)
		(width 0.15)
		(layer "In2.Cu")
		(net 323)
	)
	(segment
		(start 139.795916 123.041058)
		(end 139.767475 123.058929)
		(width 0.15)
		(layer "In2.Cu")
		(net 323)
	)
	(segment
		(start 139.110999 123.839001)
		(end 139.107238 123.872379)
		(width 0.15)
		(layer "In2.Cu")
		(net 323)
	)
	(segment
		(start 139.696144 123.904083)
		(end 139.678273 123.932524)
		(width 0.15)
		(layer "In2.Cu")
		(net 323)
	)
	(segment
		(start 139.026081 123.974146)
		(end 138.994377 123.98524)
		(width 0.15)
		(layer "In2.Cu")
		(net 323)
	)
	(segment
		(start 137.826081 123.974146)
		(end 137.794377 123.98524)
		(width 0.15)
		(layer "In2.Cu")
		(net 323)
	)
	(segment
		(start 139.725853 123.111121)
		(end 139.714759 123.142825)
		(width 0.15)
		(layer "In2.Cu")
		(net 323)
	)
	(segment
		(start 138.295916 123.974146)
		(end 138.267475 123.956275)
		(width 0.15)
		(layer "In2.Cu")
		(net 323)
	)
	(segment
		(start 138.478273 123.932524)
		(end 138.454522 123.956275)
		(width 0.15)
		(layer "In2.Cu")
		(net 323)
	)
	(segment
		(start 138.514759 123.142825)
		(end 138.510999 123.176204)
		(width 0.15)
		(layer "In2.Cu")
		(net 323)
	)
	(segment
		(start 140.308999 123.989001)
		(end 140.160999 123.989001)
		(width 0.15)
		(layer "In2.Cu")
		(net 323)
	)
	(segment
		(start 107.099257 117.074979)
		(end 106.199278 116.175)
		(width 0.15)
		(layer "In2.Cu")
		(net 323)
	)
	(segment
		(start 139.860999 123.026204)
		(end 139.82762 123.029964)
		(width 0.15)
		(layer "In2.Cu")
		(net 323)
	)
	(segment
		(start 137.075 124.075)
		(end 125.975 124.075)
		(width 0.15)
		(layer "In2.Cu")
		(net 323)
	)
	(segment
		(start 139.954522 123.058929)
		(end 139.926081 123.041058)
		(width 0.15)
		(layer "In2.Cu")
		(net 323)
	)
	(segment
		(start 139.425853 123.904083)
		(end 139.414759 123.872379)
		(width 0.15)
		(layer "In2.Cu")
		(net 323)
	)
	(segment
		(start 139.495916 123.974146)
		(end 139.467475 123.956275)
		(width 0.15)
		(layer "In2.Cu")
		(net 323)
	)
	(segment
		(start 137.343724 123.08268)
		(end 137.325853 123.111121)
		(width 0.15)
		(layer "In2.Cu")
		(net 323)
	)
	(segment
		(start 140.784 123.514)
		(end 140.308999 123.989001)
		(width 0.15)
		(layer "In2.Cu")
		(net 323)
	)
	(segment
		(start 137.643724 123.932524)
		(end 137.625853 123.904083)
		(width 0.15)
		(layer "In2.Cu")
		(net 323)
	)
	(segment
		(start 139.626081 123.974146)
		(end 139.594377 123.98524)
		(width 0.15)
		(layer "In2.Cu")
		(net 323)
	)
	(segment
		(start 138.754522 123.058929)
		(end 138.726081 123.041058)
		(width 0.15)
		(layer "In2.Cu")
		(net 323)
	)
	(segment
		(start 138.178273 123.08268)
		(end 138.154522 123.058929)
		(width 0.15)
		(layer "In2.Cu")
		(net 323)
	)
	(segment
		(start 138.426081 123.974146)
		(end 138.394377 123.98524)
		(width 0.15)
		(layer "In2.Cu")
		(net 323)
	)
	(segment
		(start 139.396144 123.111121)
		(end 139.378273 123.08268)
		(width 0.15)
		(layer "In2.Cu")
		(net 323)
	)
	(segment
		(start 140.12762 123.98524)
		(end 140.095916 123.974146)
		(width 0.15)
		(layer "In2.Cu")
		(net 323)
	)
	(segment
		(start 138.694377 123.029964)
		(end 138.660999 123.026204)
		(width 0.15)
		(layer "In2.Cu")
		(net 323)
	)
	(segment
		(start 137.325853 123.111121)
		(end 137.314759 123.142825)
		(width 0.15)
		(layer "In2.Cu")
		(net 323)
	)
	(segment
		(start 138.126081 123.041058)
		(end 138.094377 123.029964)
		(width 0.15)
		(layer "In2.Cu")
		(net 323)
	)
	(segment
		(start 138.543724 123.08268)
		(end 138.525853 123.111121)
		(width 0.15)
		(layer "In2.Cu")
		(net 323)
	)
	(segment
		(start 137.760999 123.989001)
		(end 137.72762 123.98524)
		(width 0.15)
		(layer "In2.Cu")
		(net 323)
	)
	(segment
		(start 138.92762 123.98524)
		(end 138.895916 123.974146)
		(width 0.15)
		(layer "In2.Cu")
		(net 323)
	)
	(segment
		(start 137.460999 123.026204)
		(end 137.42762 123.029964)
		(width 0.15)
		(layer "In2.Cu")
		(net 323)
	)
	(segment
		(start 138.726081 123.041058)
		(end 138.694377 123.029964)
		(width 0.15)
		(layer "In2.Cu")
		(net 323)
	)
	(segment
		(start 138.060999 123.026204)
		(end 138.02762 123.029964)
		(width 0.15)
		(layer "In2.Cu")
		(net 323)
	)
	(segment
		(start 138.778273 123.08268)
		(end 138.754522 123.058929)
		(width 0.15)
		(layer "In2.Cu")
		(net 323)
	)
	(segment
		(start 138.454522 123.956275)
		(end 138.426081 123.974146)
		(width 0.15)
		(layer "In2.Cu")
		(net 323)
	)
	(segment
		(start 137.610999 123.176204)
		(end 137.607238 123.142825)
		(width 0.15)
		(layer "In2.Cu")
		(net 323)
	)
	(segment
		(start 139.710999 123.839001)
		(end 139.707238 123.872379)
		(width 0.15)
		(layer "In2.Cu")
		(net 323)
	)
	(segment
		(start 137.72762 123.98524)
		(end 137.695916 123.974146)
		(width 0.15)
		(layer "In2.Cu")
		(net 323)
	)
	(segment
		(start 139.654522 123.956275)
		(end 139.626081 123.974146)
		(width 0.15)
		(layer "In2.Cu")
		(net 323)
	)
	(segment
		(start 138.225853 123.904083)
		(end 138.214759 123.872379)
		(width 0.15)
		(layer "In2.Cu")
		(net 323)
	)
	(segment
		(start 139.996144 123.111121)
		(end 139.978273 123.08268)
		(width 0.15)
		(layer "In2.Cu")
		(net 323)
	)
	(segment
		(start 140.095916 123.974146)
		(end 140.067475 123.956275)
		(width 0.15)
		(layer "In2.Cu")
		(net 323)
	)
	(segment
		(start 139.710999 123.176204)
		(end 139.710999 123.839001)
		(width 0.15)
		(layer "In2.Cu")
		(net 323)
	)
	(segment
		(start 139.767475 123.058929)
		(end 139.743724 123.08268)
		(width 0.15)
		(layer "In2.Cu")
		(net 323)
	)
	(segment
		(start 138.507238 123.872379)
		(end 138.496144 123.904083)
		(width 0.15)
		(layer "In2.Cu")
		(net 323)
	)
	(segment
		(start 137.614759 123.872379)
		(end 137.610999 123.839001)
		(width 0.15)
		(layer "In2.Cu")
		(net 323)
	)
	(segment
		(start 137.596144 123.111121)
		(end 137.578273 123.08268)
		(width 0.15)
		(layer "In2.Cu")
		(net 323)
	)
	(segment
		(start 137.554522 123.058929)
		(end 137.526081 123.041058)
		(width 0.15)
		(layer "In2.Cu")
		(net 323)
	)
	(segment
		(start 137.314759 123.142825)
		(end 137.310999 123.176204)
		(width 0.15)
		(layer "In2.Cu")
		(net 323)
	)
	(segment
		(start 137.610999 123.839001)
		(end 137.610999 123.176204)
		(width 0.15)
		(layer "In2.Cu")
		(net 323)
	)
	(segment
		(start 137.395916 123.041058)
		(end 137.367475 123.058929)
		(width 0.15)
		(layer "In2.Cu")
		(net 323)
	)
	(segment
		(start 139.594377 123.98524)
		(end 139.560999 123.989001)
		(width 0.15)
		(layer "In2.Cu")
		(net 323)
	)
	(segment
		(start 104.275 113.675)
		(end 104.750001 114.150001)
		(width 0.15)
		(layer "In2.Cu")
		(net 323)
	)
	(segment
		(start 138.960999 123.989001)
		(end 138.92762 123.98524)
		(width 0.15)
		(layer "In2.Cu")
		(net 323)
	)
	(segment
		(start 140.043724 123.932524)
		(end 140.025853 123.904083)
		(width 0.15)
		(layer "In2.Cu")
		(net 323)
	)
	(segment
		(start 137.42762 123.029964)
		(end 137.395916 123.041058)
		(width 0.15)
		(layer "In2.Cu")
		(net 323)
	)
	(segment
		(start 138.267475 123.956275)
		(end 138.243724 123.932524)
		(width 0.15)
		(layer "In2.Cu")
		(net 323)
	)
	(segment
		(start 141.274 121.014)
		(end 141.274 121.024)
		(width 0.15)
		(layer "F.Cu")
		(net 324)
	)
	(segment
		(start 141.274 121.024)
		(end 141.774 121.524)
		(width 0.15)
		(layer "F.Cu")
		(net 324)
	)
	(segment
		(start 141.284 121.034)
		(end 141.774 121.524)
		(width 0.1)
		(layer "F.Cu")
		(net 324)
	)
	(segment
		(start 107.775 113.175)
		(end 108.275 113.675)
		(width 0.15)
		(layer "F.Cu")
		(net 324)
	)
	(via
		(at 141.774 121.524)
		(size 0.5)
		(drill 0.2)
		(layers "F.Cu" "B.Cu")
		(net 324)
	)
	(via blind
		(at 108.275 113.675)
		(size 0.5)
		(drill 0.2)
		(layers "F.Cu" "In2.Cu")
		(net 324)
	)
	(segment
		(start 141.269 121.019)
		(end 141.774 121.524)
		(width 0.15)
		(layer "B.Cu")
		(net 324)
	)
	(segment
		(start 127.971249 120.29242)
		(end 127.97501 120.259042)
		(width 0.15)
		(layer "In2.Cu")
		(net 324)
	)
	(segment
		(start 125.790092 119.639864)
		(end 125.818533 119.657735)
		(width 0.15)
		(layer "In2.Cu")
		(net 324)
	)
	(segment
		(start 127.342284 120.352565)
		(end 127.360155 120.324124)
		(width 0.15)
		(layer "In2.Cu")
		(net 324)
	)
	(segment
		(start 125.289864 120.324124)
		(end 125.307735 120.352565)
		(width 0.15)
		(layer "In2.Cu")
		(net 324)
	)
	(segment
		(start 126.760155 120.324124)
		(end 126.771249 120.29242)
		(width 0.15)
		(layer "In2.Cu")
		(net 324)
	)
	(segment
		(start 127.858388 120.405281)
		(end 127.890092 120.394187)
		(width 0.15)
		(layer "In2.Cu")
		(net 324)
	)
	(segment
		(start 127.67877 120.29242)
		(end 127.689864 120.324124)
		(width 0.15)
		(layer "In2.Cu")
		(net 324)
	)
	(segment
		(start 127.759927 120.394187)
		(end 127.791631 120.405281)
		(width 0.15)
		(layer "In2.Cu")
		(net 324)
	)
	(segment
		(start 125.87501 119.77501)
		(end 125.87501 120.259042)
		(width 0.15)
		(layer "In2.Cu")
		(net 324)
	)
	(segment
		(start 125.190092 119.639864)
		(end 125.218533 119.657735)
		(width 0.15)
		(layer "In2.Cu")
		(net 324)
	)
	(segment
		(start 126.189864 119.709927)
		(end 126.207735 119.681486)
		(width 0.15)
		(layer "In2.Cu")
		(net 324)
	)
	(segment
		(start 127.159927 120.394187)
		(end 127.191631 120.405281)
		(width 0.15)
		(layer "In2.Cu")
		(net 324)
	)
	(segment
		(start 125.959927 120.394187)
		(end 125.991631 120.405281)
		(width 0.15)
		(layer "In2.Cu")
		(net 324)
	)
	(segment
		(start 125.659927 119.639864)
		(end 125.691631 119.62877)
		(width 0.15)
		(layer "In2.Cu")
		(net 324)
	)
	(segment
		(start 127.960155 120.324124)
		(end 127.971249 120.29242)
		(width 0.15)
		(layer "In2.Cu")
		(net 324)
	)
	(segment
		(start 125.518533 120.376316)
		(end 125.542284 120.352565)
		(width 0.15)
		(layer "In2.Cu")
		(net 324)
	)
	(segment
		(start 126.77877 119.741631)
		(end 126.789864 119.709927)
		(width 0.15)
		(layer "In2.Cu")
		(net 324)
	)
	(segment
		(start 126.658388 120.405281)
		(end 126.690092 120.394187)
		(width 0.15)
		(layer "In2.Cu")
		(net 324)
	)
	(segment
		(start 125.242284 119.681486)
		(end 125.260155 119.709927)
		(width 0.15)
		(layer "In2.Cu")
		(net 324)
	)
	(segment
		(start 127.371249 120.29242)
		(end 127.37501 120.259042)
		(width 0.15)
		(layer "In2.Cu")
		(net 324)
	)
	(segment
		(start 126.17501 120.259042)
		(end 126.17501 119.77501)
		(width 0.15)
		(layer "In2.Cu")
		(net 324)
	)
	(segment
		(start 125.560155 120.324124)
		(end 125.571249 120.29242)
		(width 0.15)
		(layer "In2.Cu")
		(net 324)
	)
	(segment
		(start 125.907735 120.352565)
		(end 125.931486 120.376316)
		(width 0.15)
		(layer "In2.Cu")
		(net 324)
	)
	(segment
		(start 108.275 113.675)
		(end 109.67495 115.07495)
		(width 0.15)
		(layer "In2.Cu")
		(net 324)
	)
	(segment
		(start 126.17501 119.77501)
		(end 126.17877 119.741631)
		(width 0.15)
		(layer "In2.Cu")
		(net 324)
	)
	(segment
		(start 127.989864 119.709927)
		(end 128.007735 119.681486)
		(width 0.15)
		(layer "In2.Cu")
		(net 324)
	)
	(segment
		(start 126.291631 119.62877)
		(end 126.32501 119.62501)
		(width 0.15)
		(layer "In2.Cu")
		(net 324)
	)
	(segment
		(start 126.958388 119.62877)
		(end 126.990092 119.639864)
		(width 0.15)
		(layer "In2.Cu")
		(net 324)
	)
	(segment
		(start 127.407735 119.681486)
		(end 127.431486 119.657735)
		(width 0.15)
		(layer "In2.Cu")
		(net 324)
	)
	(segment
		(start 127.942284 120.352565)
		(end 127.960155 120.324124)
		(width 0.15)
		(layer "In2.Cu")
		(net 324)
	)
	(segment
		(start 125.12501 119.62501)
		(end 125.158388 119.62877)
		(width 0.15)
		(layer "In2.Cu")
		(net 324)
	)
	(segment
		(start 126.789864 119.709927)
		(end 126.807735 119.681486)
		(width 0.15)
		(layer "In2.Cu")
		(net 324)
	)
	(segment
		(start 125.271249 119.741631)
		(end 125.27501 119.77501)
		(width 0.15)
		(layer "In2.Cu")
		(net 324)
	)
	(segment
		(start 125.331486 120.376316)
		(end 125.359927 120.394187)
		(width 0.15)
		(layer "In2.Cu")
		(net 324)
	)
	(segment
		(start 127.042284 119.681486)
		(end 127.060155 119.709927)
		(width 0.15)
		(layer "In2.Cu")
		(net 324)
	)
	(segment
		(start 125.607735 119.681486)
		(end 125.631486 119.657735)
		(width 0.15)
		(layer "In2.Cu")
		(net 324)
	)
	(segment
		(start 127.37501 119.77501)
		(end 127.37877 119.741631)
		(width 0.15)
		(layer "In2.Cu")
		(net 324)
	)
	(segment
		(start 128.32501 119.62501)
		(end 129.14898 120.44898)
		(width 0.15)
		(layer "In2.Cu")
		(net 324)
	)
	(segment
		(start 125.860155 119.709927)
		(end 125.871249 119.741631)
		(width 0.15)
		(layer "In2.Cu")
		(net 324)
	)
	(segment
		(start 115.574949 115.07495)
		(end 120.12501 119.62501)
		(width 0.15)
		(layer "In2.Cu")
		(net 324)
	)
	(segment
		(start 126.090092 120.394187)
		(end 126.118533 120.376316)
		(width 0.15)
		(layer "In2.Cu")
		(net 324)
	)
	(segment
		(start 127.07501 120.259042)
		(end 127.07877 120.29242)
		(width 0.15)
		(layer "In2.Cu")
		(net 324)
	)
	(segment
		(start 127.731486 120.376316)
		(end 127.759927 120.394187)
		(width 0.15)
		(layer "In2.Cu")
		(net 324)
	)
	(segment
		(start 126.259927 119.639864)
		(end 126.291631 119.62877)
		(width 0.15)
		(layer "In2.Cu")
		(net 324)
	)
	(segment
		(start 126.990092 119.639864)
		(end 127.018533 119.657735)
		(width 0.15)
		(layer "In2.Cu")
		(net 324)
	)
	(segment
		(start 125.490092 120.394187)
		(end 125.518533 120.376316)
		(width 0.15)
		(layer "In2.Cu")
		(net 324)
	)
	(segment
		(start 126.92501 119.62501)
		(end 126.958388 119.62877)
		(width 0.15)
		(layer "In2.Cu")
		(net 324)
	)
	(segment
		(start 129.14898 120.44898)
		(end 140.69898 120.44898)
		(width 0.15)
		(layer "In2.Cu")
		(net 324)
	)
	(segment
		(start 126.32501 119.62501)
		(end 126.358388 119.62877)
		(width 0.15)
		(layer "In2.Cu")
		(net 324)
	)
	(segment
		(start 125.260155 119.709927)
		(end 125.271249 119.741631)
		(width 0.15)
		(layer "In2.Cu")
		(net 324)
	)
	(segment
		(start 125.87877 120.29242)
		(end 125.889864 120.324124)
		(width 0.15)
		(layer "In2.Cu")
		(net 324)
	)
	(segment
		(start 126.531486 120.376316)
		(end 126.559927 120.394187)
		(width 0.15)
		(layer "In2.Cu")
		(net 324)
	)
	(segment
		(start 125.931486 120.376316)
		(end 125.959927 120.394187)
		(width 0.15)
		(layer "In2.Cu")
		(net 324)
	)
	(segment
		(start 126.02501 120.409042)
		(end 126.058388 120.405281)
		(width 0.15)
		(layer "In2.Cu")
		(net 324)
	)
	(segment
		(start 127.82501 120.409042)
		(end 127.858388 120.405281)
		(width 0.15)
		(layer "In2.Cu")
		(net 324)
	)
	(segment
		(start 126.47501 119.77501)
		(end 126.47501 120.259042)
		(width 0.15)
		(layer "In2.Cu")
		(net 324)
	)
	(segment
		(start 125.818533 119.657735)
		(end 125.842284 119.681486)
		(width 0.15)
		(layer "In2.Cu")
		(net 324)
	)
	(segment
		(start 127.890092 120.394187)
		(end 127.918533 120.376316)
		(width 0.15)
		(layer "In2.Cu")
		(net 324)
	)
	(segment
		(start 127.318533 120.376316)
		(end 127.342284 120.352565)
		(width 0.15)
		(layer "In2.Cu")
		(net 324)
	)
	(segment
		(start 125.458388 120.405281)
		(end 125.490092 120.394187)
		(width 0.15)
		(layer "In2.Cu")
		(net 324)
	)
	(segment
		(start 126.47501 120.259042)
		(end 126.47877 120.29242)
		(width 0.15)
		(layer "In2.Cu")
		(net 324)
	)
	(segment
		(start 128.059927 119.639864)
		(end 128.091631 119.62877)
		(width 0.15)
		(layer "In2.Cu")
		(net 324)
	)
	(segment
		(start 127.918533 120.376316)
		(end 127.942284 120.352565)
		(width 0.15)
		(layer "In2.Cu")
		(net 324)
	)
	(segment
		(start 127.131486 120.376316)
		(end 127.159927 120.394187)
		(width 0.15)
		(layer "In2.Cu")
		(net 324)
	)
	(segment
		(start 128.091631 119.62877)
		(end 128.12501 119.62501)
		(width 0.15)
		(layer "In2.Cu")
		(net 324)
	)
	(segment
		(start 126.62501 120.409042)
		(end 126.658388 120.405281)
		(width 0.15)
		(layer "In2.Cu")
		(net 324)
	)
	(segment
		(start 125.631486 119.657735)
		(end 125.659927 119.639864)
		(width 0.15)
		(layer "In2.Cu")
		(net 324)
	)
	(segment
		(start 125.27501 119.77501)
		(end 125.27501 120.259042)
		(width 0.15)
		(layer "In2.Cu")
		(net 324)
	)
	(segment
		(start 127.67501 119.77501)
		(end 127.67501 120.259042)
		(width 0.15)
		(layer "In2.Cu")
		(net 324)
	)
	(segment
		(start 127.431486 119.657735)
		(end 127.459927 119.639864)
		(width 0.15)
		(layer "In2.Cu")
		(net 324)
	)
	(segment
		(start 125.542284 120.352565)
		(end 125.560155 120.324124)
		(width 0.15)
		(layer "In2.Cu")
		(net 324)
	)
	(segment
		(start 126.859927 119.639864)
		(end 126.891631 119.62877)
		(width 0.15)
		(layer "In2.Cu")
		(net 324)
	)
	(segment
		(start 125.391631 120.405281)
		(end 125.42501 120.409042)
		(width 0.15)
		(layer "In2.Cu")
		(net 324)
	)
	(segment
		(start 128.12501 119.62501)
		(end 128.32501 119.62501)
		(width 0.15)
		(layer "In2.Cu")
		(net 324)
	)
	(segment
		(start 127.389864 119.709927)
		(end 127.407735 119.681486)
		(width 0.15)
		(layer "In2.Cu")
		(net 324)
	)
	(segment
		(start 125.87501 120.259042)
		(end 125.87877 120.29242)
		(width 0.15)
		(layer "In2.Cu")
		(net 324)
	)
	(segment
		(start 127.018533 119.657735)
		(end 127.042284 119.681486)
		(width 0.15)
		(layer "In2.Cu")
		(net 324)
	)
	(segment
		(start 127.67501 120.259042)
		(end 127.67877 120.29242)
		(width 0.15)
		(layer "In2.Cu")
		(net 324)
	)
	(segment
		(start 127.52501 119.62501)
		(end 127.558388 119.62877)
		(width 0.15)
		(layer "In2.Cu")
		(net 324)
	)
	(segment
		(start 125.691631 119.62877)
		(end 125.72501 119.62501)
		(width 0.15)
		(layer "In2.Cu")
		(net 324)
	)
	(segment
		(start 126.831486 119.657735)
		(end 126.859927 119.639864)
		(width 0.15)
		(layer "In2.Cu")
		(net 324)
	)
	(segment
		(start 126.771249 120.29242)
		(end 126.77501 120.259042)
		(width 0.15)
		(layer "In2.Cu")
		(net 324)
	)
	(segment
		(start 127.07877 120.29242)
		(end 127.089864 120.324124)
		(width 0.15)
		(layer "In2.Cu")
		(net 324)
	)
	(segment
		(start 126.442284 119.681486)
		(end 126.460155 119.709927)
		(width 0.15)
		(layer "In2.Cu")
		(net 324)
	)
	(segment
		(start 127.660155 119.709927)
		(end 127.671249 119.741631)
		(width 0.15)
		(layer "In2.Cu")
		(net 324)
	)
	(segment
		(start 125.57501 119.77501)
		(end 125.57877 119.741631)
		(width 0.15)
		(layer "In2.Cu")
		(net 324)
	)
	(segment
		(start 125.158388 119.62877)
		(end 125.190092 119.639864)
		(width 0.15)
		(layer "In2.Cu")
		(net 324)
	)
	(segment
		(start 126.390092 119.639864)
		(end 126.418533 119.657735)
		(width 0.15)
		(layer "In2.Cu")
		(net 324)
	)
	(segment
		(start 127.791631 120.405281)
		(end 127.82501 120.409042)
		(width 0.15)
		(layer "In2.Cu")
		(net 324)
	)
	(segment
		(start 127.258388 120.405281)
		(end 127.290092 120.394187)
		(width 0.15)
		(layer "In2.Cu")
		(net 324)
	)
	(segment
		(start 126.171249 120.29242)
		(end 126.17501 120.259042)
		(width 0.15)
		(layer "In2.Cu")
		(net 324)
	)
	(segment
		(start 128.031486 119.657735)
		(end 128.059927 119.639864)
		(width 0.15)
		(layer "In2.Cu")
		(net 324)
	)
	(segment
		(start 127.071249 119.741631)
		(end 127.07501 119.77501)
		(width 0.15)
		(layer "In2.Cu")
		(net 324)
	)
	(segment
		(start 126.460155 119.709927)
		(end 126.471249 119.741631)
		(width 0.15)
		(layer "In2.Cu")
		(net 324)
	)
	(segment
		(start 125.571249 120.29242)
		(end 125.57501 120.259042)
		(width 0.15)
		(layer "In2.Cu")
		(net 324)
	)
	(segment
		(start 125.57877 119.741631)
		(end 125.589864 119.709927)
		(width 0.15)
		(layer "In2.Cu")
		(net 324)
	)
	(segment
		(start 126.142284 120.352565)
		(end 126.160155 120.324124)
		(width 0.15)
		(layer "In2.Cu")
		(net 324)
	)
	(segment
		(start 126.807735 119.681486)
		(end 126.831486 119.657735)
		(width 0.15)
		(layer "In2.Cu")
		(net 324)
	)
	(segment
		(start 126.358388 119.62877)
		(end 126.390092 119.639864)
		(width 0.15)
		(layer "In2.Cu")
		(net 324)
	)
	(segment
		(start 127.459927 119.639864)
		(end 127.491631 119.62877)
		(width 0.15)
		(layer "In2.Cu")
		(net 324)
	)
	(segment
		(start 127.671249 119.741631)
		(end 127.67501 119.77501)
		(width 0.15)
		(layer "In2.Cu")
		(net 324)
	)
	(segment
		(start 127.689864 120.324124)
		(end 127.707735 120.352565)
		(width 0.15)
		(layer "In2.Cu")
		(net 324)
	)
	(segment
		(start 127.37877 119.741631)
		(end 127.389864 119.709927)
		(width 0.15)
		(layer "In2.Cu")
		(net 324)
	)
	(segment
		(start 127.37501 120.259042)
		(end 127.37501 119.77501)
		(width 0.15)
		(layer "In2.Cu")
		(net 324)
	)
	(segment
		(start 126.591631 120.405281)
		(end 126.62501 120.409042)
		(width 0.15)
		(layer "In2.Cu")
		(net 324)
	)
	(segment
		(start 125.842284 119.681486)
		(end 125.860155 119.709927)
		(width 0.15)
		(layer "In2.Cu")
		(net 324)
	)
	(segment
		(start 126.471249 119.741631)
		(end 126.47501 119.77501)
		(width 0.15)
		(layer "In2.Cu")
		(net 324)
	)
	(segment
		(start 125.57501 120.259042)
		(end 125.57501 119.77501)
		(width 0.15)
		(layer "In2.Cu")
		(net 324)
	)
	(segment
		(start 125.589864 119.709927)
		(end 125.607735 119.681486)
		(width 0.15)
		(layer "In2.Cu")
		(net 324)
	)
	(segment
		(start 125.42501 120.409042)
		(end 125.458388 120.405281)
		(width 0.15)
		(layer "In2.Cu")
		(net 324)
	)
	(segment
		(start 128.007735 119.681486)
		(end 128.031486 119.657735)
		(width 0.15)
		(layer "In2.Cu")
		(net 324)
	)
	(segment
		(start 126.207735 119.681486)
		(end 126.231486 119.657735)
		(width 0.15)
		(layer "In2.Cu")
		(net 324)
	)
	(segment
		(start 126.891631 119.62877)
		(end 126.92501 119.62501)
		(width 0.15)
		(layer "In2.Cu")
		(net 324)
	)
	(segment
		(start 127.642284 119.681486)
		(end 127.660155 119.709927)
		(width 0.15)
		(layer "In2.Cu")
		(net 324)
	)
	(segment
		(start 125.218533 119.657735)
		(end 125.242284 119.681486)
		(width 0.15)
		(layer "In2.Cu")
		(net 324)
	)
	(segment
		(start 126.507735 120.352565)
		(end 126.531486 120.376316)
		(width 0.15)
		(layer "In2.Cu")
		(net 324)
	)
	(segment
		(start 127.089864 120.324124)
		(end 127.107735 120.352565)
		(width 0.15)
		(layer "In2.Cu")
		(net 324)
	)
	(segment
		(start 127.97501 119.77501)
		(end 127.97877 119.741631)
		(width 0.15)
		(layer "In2.Cu")
		(net 324)
	)
	(segment
		(start 127.360155 120.324124)
		(end 127.371249 120.29242)
		(width 0.15)
		(layer "In2.Cu")
		(net 324)
	)
	(segment
		(start 125.307735 120.352565)
		(end 125.331486 120.376316)
		(width 0.15)
		(layer "In2.Cu")
		(net 324)
	)
	(segment
		(start 125.871249 119.741631)
		(end 125.87501 119.77501)
		(width 0.15)
		(layer "In2.Cu")
		(net 324)
	)
	(segment
		(start 125.27501 120.259042)
		(end 125.27877 120.29242)
		(width 0.15)
		(layer "In2.Cu")
		(net 324)
	)
	(segment
		(start 126.690092 120.394187)
		(end 126.718533 120.376316)
		(width 0.15)
		(layer "In2.Cu")
		(net 324)
	)
	(segment
		(start 126.718533 120.376316)
		(end 126.742284 120.352565)
		(width 0.15)
		(layer "In2.Cu")
		(net 324)
	)
	(segment
		(start 126.231486 119.657735)
		(end 126.259927 119.639864)
		(width 0.15)
		(layer "In2.Cu")
		(net 324)
	)
	(segment
		(start 125.27877 120.29242)
		(end 125.289864 120.324124)
		(width 0.15)
		(layer "In2.Cu")
		(net 324)
	)
	(segment
		(start 127.107735 120.352565)
		(end 127.131486 120.376316)
		(width 0.15)
		(layer "In2.Cu")
		(net 324)
	)
	(segment
		(start 126.058388 120.405281)
		(end 126.090092 120.394187)
		(width 0.15)
		(layer "In2.Cu")
		(net 324)
	)
	(segment
		(start 125.758388 119.62877)
		(end 125.790092 119.639864)
		(width 0.15)
		(layer "In2.Cu")
		(net 324)
	)
	(segment
		(start 127.060155 119.709927)
		(end 127.071249 119.741631)
		(width 0.15)
		(layer "In2.Cu")
		(net 324)
	)
	(segment
		(start 127.491631 119.62877)
		(end 127.52501 119.62501)
		(width 0.15)
		(layer "In2.Cu")
		(net 324)
	)
	(segment
		(start 140.69898 120.44898)
		(end 141.774 121.524)
		(width 0.15)
		(layer "In2.Cu")
		(net 324)
	)
	(segment
		(start 126.77501 119.77501)
		(end 126.77877 119.741631)
		(width 0.15)
		(layer "In2.Cu")
		(net 324)
	)
	(segment
		(start 120.12501 119.62501)
		(end 125.12501 119.62501)
		(width 0.15)
		(layer "In2.Cu")
		(net 324)
	)
	(segment
		(start 125.359927 120.394187)
		(end 125.391631 120.405281)
		(width 0.15)
		(layer "In2.Cu")
		(net 324)
	)
	(segment
		(start 126.118533 120.376316)
		(end 126.142284 120.352565)
		(width 0.15)
		(layer "In2.Cu")
		(net 324)
	)
	(segment
		(start 126.17877 119.741631)
		(end 126.189864 119.709927)
		(width 0.15)
		(layer "In2.Cu")
		(net 324)
	)
	(segment
		(start 127.97501 120.259042)
		(end 127.97501 119.77501)
		(width 0.15)
		(layer "In2.Cu")
		(net 324)
	)
	(segment
		(start 127.07501 119.77501)
		(end 127.07501 120.259042)
		(width 0.15)
		(layer "In2.Cu")
		(net 324)
	)
	(segment
		(start 127.707735 120.352565)
		(end 127.731486 120.376316)
		(width 0.15)
		(layer "In2.Cu")
		(net 324)
	)
	(segment
		(start 127.618533 119.657735)
		(end 127.642284 119.681486)
		(width 0.15)
		(layer "In2.Cu")
		(net 324)
	)
	(segment
		(start 127.22501 120.409042)
		(end 127.258388 120.405281)
		(width 0.15)
		(layer "In2.Cu")
		(net 324)
	)
	(segment
		(start 126.77501 120.259042)
		(end 126.77501 119.77501)
		(width 0.15)
		(layer "In2.Cu")
		(net 324)
	)
	(segment
		(start 125.889864 120.324124)
		(end 125.907735 120.352565)
		(width 0.15)
		(layer "In2.Cu")
		(net 324)
	)
	(segment
		(start 127.97877 119.741631)
		(end 127.989864 119.709927)
		(width 0.15)
		(layer "In2.Cu")
		(net 324)
	)
	(segment
		(start 126.489864 120.324124)
		(end 126.507735 120.352565)
		(width 0.15)
		(layer "In2.Cu")
		(net 324)
	)
	(segment
		(start 126.47877 120.29242)
		(end 126.489864 120.324124)
		(width 0.15)
		(layer "In2.Cu")
		(net 324)
	)
	(segment
		(start 127.558388 119.62877)
		(end 127.590092 119.639864)
		(width 0.15)
		(layer "In2.Cu")
		(net 324)
	)
	(segment
		(start 125.991631 120.405281)
		(end 126.02501 120.409042)
		(width 0.15)
		(layer "In2.Cu")
		(net 324)
	)
	(segment
		(start 109.67495 115.07495)
		(end 115.574949 115.07495)
		(width 0.15)
		(layer "In2.Cu")
		(net 324)
	)
	(segment
		(start 125.72501 119.62501)
		(end 125.758388 119.62877)
		(width 0.15)
		(layer "In2.Cu")
		(net 324)
	)
	(segment
		(start 126.418533 119.657735)
		(end 126.442284 119.681486)
		(width 0.15)
		(layer "In2.Cu")
		(net 324)
	)
	(segment
		(start 127.191631 120.405281)
		(end 127.22501 120.409042)
		(width 0.15)
		(layer "In2.Cu")
		(net 324)
	)
	(segment
		(start 127.590092 119.639864)
		(end 127.618533 119.657735)
		(width 0.15)
		(layer "In2.Cu")
		(net 324)
	)
	(segment
		(start 127.290092 120.394187)
		(end 127.318533 120.376316)
		(width 0.15)
		(layer "In2.Cu")
		(net 324)
	)
	(segment
		(start 126.160155 120.324124)
		(end 126.171249 120.29242)
		(width 0.15)
		(layer "In2.Cu")
		(net 324)
	)
	(segment
		(start 126.742284 120.352565)
		(end 126.760155 120.324124)
		(width 0.15)
		(layer "In2.Cu")
		(net 324)
	)
	(segment
		(start 126.559927 120.394187)
		(end 126.591631 120.405281)
		(width 0.15)
		(layer "In2.Cu")
		(net 324)
	)
	(segment
		(start 136.274 121.014)
		(end 136.274 121.024)
		(width 0.15)
		(layer "F.Cu")
		(net 325)
	)
	(segment
		(start 136.274 121.024)
		(end 135.774 121.524)
		(width 0.15)
		(layer "F.Cu")
		(net 325)
	)
	(segment
		(start 136.264 121.034)
		(end 135.774 121.524)
		(width 0.1)
		(layer "F.Cu")
		(net 325)
	)
	(segment
		(start 106.775 113.175)
		(end 107.275 113.675)
		(width 0.15)
		(layer "F.Cu")
		(net 325)
	)
	(via
		(at 135.774 121.524)
		(size 0.5)
		(drill 0.2)
		(layers "F.Cu" "B.Cu")
		(net 325)
	)
	(via blind
		(at 107.275 113.675)
		(size 0.5)
		(drill 0.2)
		(layers "F.Cu" "In2.Cu")
		(net 325)
	)
	(segment
		(start 136.289 121.024)
		(end 136.274 121.024)
		(width 0.15)
		(layer "B.Cu")
		(net 325)
	)
	(segment
		(start 136.274 121.024)
		(end 135.774 121.524)
		(width 0.15)
		(layer "B.Cu")
		(net 325)
	)
	(segment
		(start 121.623296 121.675256)
		(end 121.630654 121.663546)
		(width 0.15)
		(layer "In2.Cu")
		(net 325)
	)
	(segment
		(start 122.551559 121.650492)
		(end 122.556127 121.663546)
		(width 0.15)
		(layer "In2.Cu")
		(net 325)
	)
	(segment
		(start 123.450011 121.63675)
		(end 123.450011 120.651468)
		(width 0.15)
		(layer "In2.Cu")
		(net 325)
	)
	(segment
		(start 124.353771 121.458368)
		(end 124.364865 121.490072)
		(width 0.15)
		(layer "In2.Cu")
		(net 325)
	)
	(segment
		(start 123.633389 120.505229)
		(end 123.665093 120.516323)
		(width 0.15)
		(layer "In2.Cu")
		(net 325)
	)
	(segment
		(start 124.34625 120.61809)
		(end 124.350011 120.651468)
		(width 0.15)
		(layer "In2.Cu")
		(net 325)
	)
	(segment
		(start 124.200011 120.501468)
		(end 124.233389 120.505229)
		(width 0.15)
		(layer "In2.Cu")
		(net 325)
	)
	(segment
		(start 123.798028 121.696961)
		(end 123.811771 121.69851)
		(width 0.15)
		(layer "In2.Cu")
		(net 325)
	)
	(segment
		(start 121.636771 121.574989)
		(end 121.650011 121.574989)
		(width 0.15)
		(layer "In2.Cu")
		(net 325)
	)
	(segment
		(start 123.450011 120.651468)
		(end 123.453771 120.61809)
		(width 0.15)
		(layer "In2.Cu")
		(net 325)
	)
	(segment
		(start 124.166632 120.505229)
		(end 124.200011 120.501468)
		(width 0.15)
		(layer "In2.Cu")
		(net 325)
	)
	(segment
		(start 123.453771 120.61809)
		(end 123.464865 120.586386)
		(width 0.15)
		(layer "In2.Cu")
		(net 325)
	)
	(segment
		(start 122.226757 121.685035)
		(end 122.236536 121.675256)
		(width 0.15)
		(layer "In2.Cu")
		(net 325)
	)
	(segment
		(start 124.082736 120.557945)
		(end 124.106487 120.534194)
		(width 0.15)
		(layer "In2.Cu")
		(net 325)
	)
	(segment
		(start 122.853771 120.61809)
		(end 122.864865 120.586386)
		(width 0.15)
		(layer "In2.Cu")
		(net 325)
	)
	(segment
		(start 121.865093 120.516323)
		(end 121.893534 120.534194)
		(width 0.15)
		(layer "In2.Cu")
		(net 325)
	)
	(segment
		(start 122.850011 121.63675)
		(end 122.850011 120.651468)
		(width 0.15)
		(layer "In2.Cu")
		(net 325)
	)
	(segment
		(start 122.253771 120.61809)
		(end 122.264865 120.586386)
		(width 0.15)
		(layer "In2.Cu")
		(net 325)
	)
	(segment
		(start 121.288753 121.576537)
		(end 121.301807 121.581105)
		(width 0.15)
		(layer "In2.Cu")
		(net 325)
	)
	(segment
		(start 123.151559 121.650492)
		(end 123.156127 121.663546)
		(width 0.15)
		(layer "In2.Cu")
		(net 325)
	)
	(segment
		(start 121.099267 121.574989)
		(end 121.275011 121.574989)
		(width 0.15)
		(layer "In2.Cu")
		(net 325)
	)
	(segment
		(start 122.556127 121.663546)
		(end 122.563485 121.675256)
		(width 0.15)
		(layer "In2.Cu")
		(net 325)
	)
	(segment
		(start 124.434928 121.560135)
		(end 124.466632 121.571229)
		(width 0.15)
		(layer "In2.Cu")
		(net 325)
	)
	(segment
		(start 124.048462 121.650492)
		(end 124.050011 121.63675)
		(width 0.15)
		(layer "In2.Cu")
		(net 325)
	)
	(segment
		(start 123.735156 120.586386)
		(end 123.74625 120.61809)
		(width 0.15)
		(layer "In2.Cu")
		(net 325)
	)
	(segment
		(start 121.706487 120.534194)
		(end 121.734928 120.516323)
		(width 0.15)
		(layer "In2.Cu")
		(net 325)
	)
	(segment
		(start 123.506487 120.534194)
		(end 123.534928 120.516323)
		(width 0.15)
		(layer "In2.Cu")
		(net 325)
	)
	(segment
		(start 122.563485 121.675256)
		(end 122.573264 121.685035)
		(width 0.15)
		(layer "In2.Cu")
		(net 325)
	)
	(segment
		(start 122.843894 121.663546)
		(end 122.848462 121.650492)
		(width 0.15)
		(layer "In2.Cu")
		(net 325)
	)
	(segment
		(start 122.250011 121.63675)
		(end 122.250011 120.651468)
		(width 0.15)
		(layer "In2.Cu")
		(net 325)
	)
	(segment
		(start 123.000011 120.501468)
		(end 123.033389 120.505229)
		(width 0.15)
		(layer "In2.Cu")
		(net 325)
	)
	(segment
		(start 121.342887 121.663546)
		(end 121.350245 121.675256)
		(width 0.15)
		(layer "In2.Cu")
		(net 325)
	)
	(segment
		(start 121.335222 121.623006)
		(end 121.338319 121.650492)
		(width 0.15)
		(layer "In2.Cu")
		(net 325)
	)
	(segment
		(start 122.801993 121.696961)
		(end 122.815047 121.692393)
		(width 0.15)
		(layer "In2.Cu")
		(net 325)
	)
	(segment
		(start 122.535156 120.586386)
		(end 122.54625 120.61809)
		(width 0.15)
		(layer "In2.Cu")
		(net 325)
	)
	(segment
		(start 121.650011 121.574989)
		(end 121.650011 120.651468)
		(width 0.15)
		(layer "In2.Cu")
		(net 325)
	)
	(segment
		(start 122.573264 121.685035)
		(end 122.584974 121.692393)
		(width 0.15)
		(layer "In2.Cu")
		(net 325)
	)
	(segment
		(start 121.384788 121.696961)
		(end 121.398531 121.69851)
		(width 0.15)
		(layer "In2.Cu")
		(net 325)
	)
	(segment
		(start 122.517285 120.557945)
		(end 122.535156 120.586386)
		(width 0.15)
		(layer "In2.Cu")
		(net 325)
	)
	(segment
		(start 123.135156 120.586386)
		(end 123.14625 120.61809)
		(width 0.15)
		(layer "In2.Cu")
		(net 325)
	)
	(segment
		(start 127.801001 121.048999)
		(end 135.298999 121.048999)
		(width 0.15)
		(layer "In2.Cu")
		(net 325)
	)
	(segment
		(start 121.950011 120.651468)
		(end 121.950011 121.63675)
		(width 0.15)
		(layer "In2.Cu")
		(net 325)
	)
	(segment
		(start 122.400011 120.501468)
		(end 122.433389 120.505229)
		(width 0.15)
		(layer "In2.Cu")
		(net 325)
	)
	(segment
		(start 108.921417 115.67497)
		(end 115.199248 115.67497)
		(width 0.15)
		(layer "In2.Cu")
		(net 325)
	)
	(segment
		(start 115.199248 115.67497)
		(end 121.099267 121.574989)
		(width 0.15)
		(layer "In2.Cu")
		(net 325)
	)
	(segment
		(start 127.275011 121.574989)
		(end 127.801001 121.048999)
		(width 0.15)
		(layer "In2.Cu")
		(net 325)
	)
	(segment
		(start 123.693534 120.534194)
		(end 123.717285 120.557945)
		(width 0.15)
		(layer "In2.Cu")
		(net 325)
	)
	(segment
		(start 124.036536 121.675256)
		(end 124.043894 121.663546)
		(width 0.15)
		(layer "In2.Cu")
		(net 325)
	)
	(segment
		(start 123.600011 120.501468)
		(end 123.633389 120.505229)
		(width 0.15)
		(layer "In2.Cu")
		(net 325)
	)
	(segment
		(start 124.406487 121.542264)
		(end 124.434928 121.560135)
		(width 0.15)
		(layer "In2.Cu")
		(net 325)
	)
	(segment
		(start 122.864865 120.586386)
		(end 122.882736 120.557945)
		(width 0.15)
		(layer "In2.Cu")
		(net 325)
	)
	(segment
		(start 122.465093 120.516323)
		(end 122.493534 120.534194)
		(width 0.15)
		(layer "In2.Cu")
		(net 325)
	)
	(segment
		(start 121.94625 120.61809)
		(end 121.950011 120.651468)
		(width 0.15)
		(layer "In2.Cu")
		(net 325)
	)
	(segment
		(start 123.811771 121.69851)
		(end 123.988251 121.69851)
		(width 0.15)
		(layer "In2.Cu")
		(net 325)
	)
	(segment
		(start 124.064865 120.586386)
		(end 124.082736 120.557945)
		(width 0.15)
		(layer "In2.Cu")
		(net 325)
	)
	(segment
		(start 121.575011 121.69851)
		(end 121.588753 121.696961)
		(width 0.15)
		(layer "In2.Cu")
		(net 325)
	)
	(segment
		(start 123.751559 121.650492)
		(end 123.756127 121.663546)
		(width 0.15)
		(layer "In2.Cu")
		(net 325)
	)
	(segment
		(start 122.188251 121.69851)
		(end 122.201993 121.696961)
		(width 0.15)
		(layer "In2.Cu")
		(net 325)
	)
	(segment
		(start 121.766632 120.505229)
		(end 121.800011 120.501468)
		(width 0.15)
		(layer "In2.Cu")
		(net 325)
	)
	(segment
		(start 124.293534 120.534194)
		(end 124.317285 120.557945)
		(width 0.15)
		(layer "In2.Cu")
		(net 325)
	)
	(segment
		(start 123.566632 120.505229)
		(end 123.600011 120.501468)
		(width 0.15)
		(layer "In2.Cu")
		(net 325)
	)
	(segment
		(start 121.956127 121.663546)
		(end 121.963485 121.675256)
		(width 0.15)
		(layer "In2.Cu")
		(net 325)
	)
	(segment
		(start 124.350011 121.424989)
		(end 124.353771 121.458368)
		(width 0.15)
		(layer "In2.Cu")
		(net 325)
	)
	(segment
		(start 121.338319 121.650492)
		(end 121.342887 121.663546)
		(width 0.15)
		(layer "In2.Cu")
		(net 325)
	)
	(segment
		(start 121.998028 121.696961)
		(end 122.011771 121.69851)
		(width 0.15)
		(layer "In2.Cu")
		(net 325)
	)
	(segment
		(start 122.934928 120.516323)
		(end 122.966632 120.505229)
		(width 0.15)
		(layer "In2.Cu")
		(net 325)
	)
	(segment
		(start 121.613517 121.685035)
		(end 121.623296 121.675256)
		(width 0.15)
		(layer "In2.Cu")
		(net 325)
	)
	(segment
		(start 124.466632 121.571229)
		(end 124.500011 121.574989)
		(width 0.15)
		(layer "In2.Cu")
		(net 325)
	)
	(segment
		(start 135.298999 121.048999)
		(end 135.774 121.524)
		(width 0.15)
		(layer "In2.Cu")
		(net 325)
	)
	(segment
		(start 122.011771 121.69851)
		(end 122.188251 121.69851)
		(width 0.15)
		(layer "In2.Cu")
		(net 325)
	)
	(segment
		(start 122.788251 121.69851)
		(end 122.801993 121.696961)
		(width 0.15)
		(layer "In2.Cu")
		(net 325)
	)
	(segment
		(start 121.601807 121.692393)
		(end 121.613517 121.685035)
		(width 0.15)
		(layer "In2.Cu")
		(net 325)
	)
	(segment
		(start 121.653771 120.61809)
		(end 121.664865 120.586386)
		(width 0.15)
		(layer "In2.Cu")
		(net 325)
	)
	(segment
		(start 121.635222 121.650492)
		(end 121.636771 121.636749)
		(width 0.15)
		(layer "In2.Cu")
		(net 325)
	)
	(segment
		(start 124.233389 120.505229)
		(end 124.265093 120.516323)
		(width 0.15)
		(layer "In2.Cu")
		(net 325)
	)
	(segment
		(start 123.117285 120.557945)
		(end 123.135156 120.586386)
		(width 0.15)
		(layer "In2.Cu")
		(net 325)
	)
	(segment
		(start 123.464865 120.586386)
		(end 123.482736 120.557945)
		(width 0.15)
		(layer "In2.Cu")
		(net 325)
	)
	(segment
		(start 123.74625 120.61809)
		(end 123.750011 120.651468)
		(width 0.15)
		(layer "In2.Cu")
		(net 325)
	)
	(segment
		(start 123.534928 120.516323)
		(end 123.566632 120.505229)
		(width 0.15)
		(layer "In2.Cu")
		(net 325)
	)
	(segment
		(start 123.415047 121.692393)
		(end 123.426757 121.685035)
		(width 0.15)
		(layer "In2.Cu")
		(net 325)
	)
	(segment
		(start 124.335156 120.586386)
		(end 124.34625 120.61809)
		(width 0.15)
		(layer "In2.Cu")
		(net 325)
	)
	(segment
		(start 123.750011 121.63675)
		(end 123.751559 121.650492)
		(width 0.15)
		(layer "In2.Cu")
		(net 325)
	)
	(segment
		(start 121.630654 121.663546)
		(end 121.635222 121.650492)
		(width 0.15)
		(layer "In2.Cu")
		(net 325)
	)
	(segment
		(start 123.065093 120.516323)
		(end 123.093534 120.534194)
		(width 0.15)
		(layer "In2.Cu")
		(net 325)
	)
	(segment
		(start 121.323296 121.598242)
		(end 121.330654 121.609952)
		(width 0.15)
		(layer "In2.Cu")
		(net 325)
	)
	(segment
		(start 122.215047 121.692393)
		(end 122.226757 121.685035)
		(width 0.15)
		(layer "In2.Cu")
		(net 325)
	)
	(segment
		(start 123.717285 120.557945)
		(end 123.735156 120.586386)
		(width 0.15)
		(layer "In2.Cu")
		(net 325)
	)
	(segment
		(start 122.584974 121.692393)
		(end 122.598028 121.696961)
		(width 0.15)
		(layer "In2.Cu")
		(net 325)
	)
	(segment
		(start 124.050011 121.63675)
		(end 124.050011 120.651468)
		(width 0.15)
		(layer "In2.Cu")
		(net 325)
	)
	(segment
		(start 124.026757 121.685035)
		(end 124.036536 121.675256)
		(width 0.15)
		(layer "In2.Cu")
		(net 325)
	)
	(segment
		(start 121.313517 121.588463)
		(end 121.323296 121.598242)
		(width 0.15)
		(layer "In2.Cu")
		(net 325)
	)
	(segment
		(start 121.301807 121.581105)
		(end 121.313517 121.588463)
		(width 0.15)
		(layer "In2.Cu")
		(net 325)
	)
	(segment
		(start 123.401993 121.696961)
		(end 123.415047 121.692393)
		(width 0.15)
		(layer "In2.Cu")
		(net 325)
	)
	(segment
		(start 122.493534 120.534194)
		(end 122.517285 120.557945)
		(width 0.15)
		(layer "In2.Cu")
		(net 325)
	)
	(segment
		(start 123.482736 120.557945)
		(end 123.506487 120.534194)
		(width 0.15)
		(layer "In2.Cu")
		(net 325)
	)
	(segment
		(start 121.398531 121.69851)
		(end 121.575011 121.69851)
		(width 0.15)
		(layer "In2.Cu")
		(net 325)
	)
	(segment
		(start 121.360024 121.685035)
		(end 121.371734 121.692393)
		(width 0.15)
		(layer "In2.Cu")
		(net 325)
	)
	(segment
		(start 121.275011 121.574989)
		(end 121.288753 121.576537)
		(width 0.15)
		(layer "In2.Cu")
		(net 325)
	)
	(segment
		(start 121.350245 121.675256)
		(end 121.360024 121.685035)
		(width 0.15)
		(layer "In2.Cu")
		(net 325)
	)
	(segment
		(start 123.198028 121.696961)
		(end 123.211771 121.69851)
		(width 0.15)
		(layer "In2.Cu")
		(net 325)
	)
	(segment
		(start 122.826757 121.685035)
		(end 122.836536 121.675256)
		(width 0.15)
		(layer "In2.Cu")
		(net 325)
	)
	(segment
		(start 122.334928 120.516323)
		(end 122.366632 120.505229)
		(width 0.15)
		(layer "In2.Cu")
		(net 325)
	)
	(segment
		(start 122.611771 121.69851)
		(end 122.788251 121.69851)
		(width 0.15)
		(layer "In2.Cu")
		(net 325)
	)
	(segment
		(start 122.248462 121.650492)
		(end 122.250011 121.63675)
		(width 0.15)
		(layer "In2.Cu")
		(net 325)
	)
	(segment
		(start 124.015047 121.692393)
		(end 124.026757 121.685035)
		(width 0.15)
		(layer "In2.Cu")
		(net 325)
	)
	(segment
		(start 122.54625 120.61809)
		(end 122.550011 120.651468)
		(width 0.15)
		(layer "In2.Cu")
		(net 325)
	)
	(segment
		(start 123.184974 121.692393)
		(end 123.198028 121.696961)
		(width 0.15)
		(layer "In2.Cu")
		(net 325)
	)
	(segment
		(start 121.664865 120.586386)
		(end 121.682736 120.557945)
		(width 0.15)
		(layer "In2.Cu")
		(net 325)
	)
	(segment
		(start 121.951559 121.650492)
		(end 121.956127 121.663546)
		(width 0.15)
		(layer "In2.Cu")
		(net 325)
	)
	(segment
		(start 122.966632 120.505229)
		(end 123.000011 120.501468)
		(width 0.15)
		(layer "In2.Cu")
		(net 325)
	)
	(segment
		(start 121.636771 121.636749)
		(end 121.636771 121.574989)
		(width 0.15)
		(layer "In2.Cu")
		(net 325)
	)
	(segment
		(start 123.033389 120.505229)
		(end 123.065093 120.516323)
		(width 0.15)
		(layer "In2.Cu")
		(net 325)
	)
	(segment
		(start 122.236536 121.675256)
		(end 122.243894 121.663546)
		(width 0.15)
		(layer "In2.Cu")
		(net 325)
	)
	(segment
		(start 124.001993 121.696961)
		(end 124.015047 121.692393)
		(width 0.15)
		(layer "In2.Cu")
		(net 325)
	)
	(segment
		(start 123.784974 121.692393)
		(end 123.798028 121.696961)
		(width 0.15)
		(layer "In2.Cu")
		(net 325)
	)
	(segment
		(start 121.935156 120.586386)
		(end 121.94625 120.61809)
		(width 0.15)
		(layer "In2.Cu")
		(net 325)
	)
	(segment
		(start 107.275 114.028553)
		(end 108.921417 115.67497)
		(width 0.15)
		(layer "In2.Cu")
		(net 325)
	)
	(segment
		(start 123.388251 121.69851)
		(end 123.401993 121.696961)
		(width 0.15)
		(layer "In2.Cu")
		(net 325)
	)
	(segment
		(start 123.14625 120.61809)
		(end 123.150011 120.651468)
		(width 0.15)
		(layer "In2.Cu")
		(net 325)
	)
	(segment
		(start 123.173264 121.685035)
		(end 123.184974 121.692393)
		(width 0.15)
		(layer "In2.Cu")
		(net 325)
	)
	(segment
		(start 122.250011 120.651468)
		(end 122.253771 120.61809)
		(width 0.15)
		(layer "In2.Cu")
		(net 325)
	)
	(segment
		(start 122.906487 120.534194)
		(end 122.934928 120.516323)
		(width 0.15)
		(layer "In2.Cu")
		(net 325)
	)
	(segment
		(start 121.650011 120.651468)
		(end 121.653771 120.61809)
		(width 0.15)
		(layer "In2.Cu")
		(net 325)
	)
	(segment
		(start 123.756127 121.663546)
		(end 123.763485 121.675256)
		(width 0.15)
		(layer "In2.Cu")
		(net 325)
	)
	(segment
		(start 122.850011 120.651468)
		(end 122.853771 120.61809)
		(width 0.15)
		(layer "In2.Cu")
		(net 325)
	)
	(segment
		(start 123.150011 121.63675)
		(end 123.151559 121.650492)
		(width 0.15)
		(layer "In2.Cu")
		(net 325)
	)
	(segment
		(start 123.426757 121.685035)
		(end 123.436536 121.675256)
		(width 0.15)
		(layer "In2.Cu")
		(net 325)
	)
	(segment
		(start 121.984974 121.692393)
		(end 121.998028 121.696961)
		(width 0.15)
		(layer "In2.Cu")
		(net 325)
	)
	(segment
		(start 124.043894 121.663546)
		(end 124.048462 121.650492)
		(width 0.15)
		(layer "In2.Cu")
		(net 325)
	)
	(segment
		(start 124.317285 120.557945)
		(end 124.335156 120.586386)
		(width 0.15)
		(layer "In2.Cu")
		(net 325)
	)
	(segment
		(start 124.134928 120.516323)
		(end 124.166632 120.505229)
		(width 0.15)
		(layer "In2.Cu")
		(net 325)
	)
	(segment
		(start 122.836536 121.675256)
		(end 122.843894 121.663546)
		(width 0.15)
		(layer "In2.Cu")
		(net 325)
	)
	(segment
		(start 123.436536 121.675256)
		(end 123.443894 121.663546)
		(width 0.15)
		(layer "In2.Cu")
		(net 325)
	)
	(segment
		(start 123.750011 120.651468)
		(end 123.750011 121.63675)
		(width 0.15)
		(layer "In2.Cu")
		(net 325)
	)
	(segment
		(start 123.156127 121.663546)
		(end 123.163485 121.675256)
		(width 0.15)
		(layer "In2.Cu")
		(net 325)
	)
	(segment
		(start 122.848462 121.650492)
		(end 122.850011 121.63675)
		(width 0.15)
		(layer "In2.Cu")
		(net 325)
	)
	(segment
		(start 123.665093 120.516323)
		(end 123.693534 120.534194)
		(width 0.15)
		(layer "In2.Cu")
		(net 325)
	)
	(segment
		(start 123.150011 120.651468)
		(end 123.150011 121.63675)
		(width 0.15)
		(layer "In2.Cu")
		(net 325)
	)
	(segment
		(start 124.350011 120.651468)
		(end 124.350011 121.424989)
		(width 0.15)
		(layer "In2.Cu")
		(net 325)
	)
	(segment
		(start 123.988251 121.69851)
		(end 124.001993 121.696961)
		(width 0.15)
		(layer "In2.Cu")
		(net 325)
	)
	(segment
		(start 124.053771 120.61809)
		(end 124.064865 120.586386)
		(width 0.15)
		(layer "In2.Cu")
		(net 325)
	)
	(segment
		(start 121.833389 120.505229)
		(end 121.865093 120.516323)
		(width 0.15)
		(layer "In2.Cu")
		(net 325)
	)
	(segment
		(start 123.773264 121.685035)
		(end 123.784974 121.692393)
		(width 0.15)
		(layer "In2.Cu")
		(net 325)
	)
	(segment
		(start 122.598028 121.696961)
		(end 122.611771 121.69851)
		(width 0.15)
		(layer "In2.Cu")
		(net 325)
	)
	(segment
		(start 121.682736 120.557945)
		(end 121.706487 120.534194)
		(width 0.15)
		(layer "In2.Cu")
		(net 325)
	)
	(segment
		(start 122.201993 121.696961)
		(end 122.215047 121.692393)
		(width 0.15)
		(layer "In2.Cu")
		(net 325)
	)
	(segment
		(start 121.963485 121.675256)
		(end 121.973264 121.685035)
		(width 0.15)
		(layer "In2.Cu")
		(net 325)
	)
	(segment
		(start 122.366632 120.505229)
		(end 122.400011 120.501468)
		(width 0.15)
		(layer "In2.Cu")
		(net 325)
	)
	(segment
		(start 121.917285 120.557945)
		(end 121.935156 120.586386)
		(width 0.15)
		(layer "In2.Cu")
		(net 325)
	)
	(segment
		(start 121.330654 121.609952)
		(end 121.335222 121.623006)
		(width 0.15)
		(layer "In2.Cu")
		(net 325)
	)
	(segment
		(start 124.265093 120.516323)
		(end 124.293534 120.534194)
		(width 0.15)
		(layer "In2.Cu")
		(net 325)
	)
	(segment
		(start 122.882736 120.557945)
		(end 122.906487 120.534194)
		(width 0.15)
		(layer "In2.Cu")
		(net 325)
	)
	(segment
		(start 121.973264 121.685035)
		(end 121.984974 121.692393)
		(width 0.15)
		(layer "In2.Cu")
		(net 325)
	)
	(segment
		(start 122.433389 120.505229)
		(end 122.465093 120.516323)
		(width 0.15)
		(layer "In2.Cu")
		(net 325)
	)
	(segment
		(start 121.734928 120.516323)
		(end 121.766632 120.505229)
		(width 0.15)
		(layer "In2.Cu")
		(net 325)
	)
	(segment
		(start 123.443894 121.663546)
		(end 123.448462 121.650492)
		(width 0.15)
		(layer "In2.Cu")
		(net 325)
	)
	(segment
		(start 121.588753 121.696961)
		(end 121.601807 121.692393)
		(width 0.15)
		(layer "In2.Cu")
		(net 325)
	)
	(segment
		(start 124.500011 121.574989)
		(end 127.275011 121.574989)
		(width 0.15)
		(layer "In2.Cu")
		(net 325)
	)
	(segment
		(start 123.448462 121.650492)
		(end 123.450011 121.63675)
		(width 0.15)
		(layer "In2.Cu")
		(net 325)
	)
	(segment
		(start 123.763485 121.675256)
		(end 123.773264 121.685035)
		(width 0.15)
		(layer "In2.Cu")
		(net 325)
	)
	(segment
		(start 122.243894 121.663546)
		(end 122.248462 121.650492)
		(width 0.15)
		(layer "In2.Cu")
		(net 325)
	)
	(segment
		(start 124.364865 121.490072)
		(end 124.382736 121.518513)
		(width 0.15)
		(layer "In2.Cu")
		(net 325)
	)
	(segment
		(start 121.800011 120.501468)
		(end 121.833389 120.505229)
		(width 0.15)
		(layer "In2.Cu")
		(net 325)
	)
	(segment
		(start 123.211771 121.69851)
		(end 123.388251 121.69851)
		(width 0.15)
		(layer "In2.Cu")
		(net 325)
	)
	(segment
		(start 122.550011 120.651468)
		(end 122.550011 121.63675)
		(width 0.15)
		(layer "In2.Cu")
		(net 325)
	)
	(segment
		(start 124.382736 121.518513)
		(end 124.406487 121.542264)
		(width 0.15)
		(layer "In2.Cu")
		(net 325)
	)
	(segment
		(start 122.815047 121.692393)
		(end 122.826757 121.685035)
		(width 0.15)
		(layer "In2.Cu")
		(net 325)
	)
	(segment
		(start 122.282736 120.557945)
		(end 122.306487 120.534194)
		(width 0.15)
		(layer "In2.Cu")
		(net 325)
	)
	(segment
		(start 107.275 113.675)
		(end 107.275 114.028553)
		(width 0.15)
		(layer "In2.Cu")
		(net 325)
	)
	(segment
		(start 121.371734 121.692393)
		(end 121.384788 121.696961)
		(width 0.15)
		(layer "In2.Cu")
		(net 325)
	)
	(segment
		(start 123.093534 120.534194)
		(end 123.117285 120.557945)
		(width 0.15)
		(layer "In2.Cu")
		(net 325)
	)
	(segment
		(start 124.106487 120.534194)
		(end 124.134928 120.516323)
		(width 0.15)
		(layer "In2.Cu")
		(net 325)
	)
	(segment
		(start 124.050011 120.651468)
		(end 124.053771 120.61809)
		(width 0.15)
		(layer "In2.Cu")
		(net 325)
	)
	(segment
		(start 123.163485 121.675256)
		(end 123.173264 121.685035)
		(width 0.15)
		(layer "In2.Cu")
		(net 325)
	)
	(segment
		(start 122.264865 120.586386)
		(end 122.282736 120.557945)
		(width 0.15)
		(layer "In2.Cu")
		(net 325)
	)
	(segment
		(start 122.306487 120.534194)
		(end 122.334928 120.516323)
		(width 0.15)
		(layer "In2.Cu")
		(net 325)
	)
	(segment
		(start 122.550011 121.63675)
		(end 122.551559 121.650492)
		(width 0.15)
		(layer "In2.Cu")
		(net 325)
	)
	(segment
		(start 121.893534 120.534194)
		(end 121.917285 120.557945)
		(width 0.15)
		(layer "In2.Cu")
		(net 325)
	)
	(segment
		(start 121.950011 121.63675)
		(end 121.951559 121.650492)
		(width 0.15)
		(layer "In2.Cu")
		(net 325)
	)
	(segment
		(start 136.274 124.004)
		(end 135.784 123.514)
		(width 0.15)
		(layer "F.Cu")
		(net 326)
	)
	(segment
		(start 106.275 114.675)
		(end 106.19999 114.675)
		(width 0.15)
		(layer "F.Cu")
		(net 326)
	)
	(segment
		(start 106.775 114.175)
		(end 106.275 114.675)
		(width 0.15)
		(layer "F.Cu")
		(net 326)
	)
	(via
		(at 135.784 123.514)
		(size 0.5)
		(drill 0.2)
		(layers "F.Cu" "B.Cu")
		(net 326)
	)
	(via blind
		(at 106.19999 114.675)
		(size 0.5)
		(drill 0.2)
		(layers "F.Cu" "In2.Cu")
		(net 326)
	)
	(segment
		(start 135.789 124.214)
		(end 135.789 123.519)
		(width 0.15)
		(layer "B.Cu")
		(net 326)
	)
	(segment
		(start 135.789 123.519)
		(end 135.784 123.514)
		(width 0.15)
		(layer "B.Cu")
		(net 326)
	)
	(segment
		(start 134.011001 123.238999)
		(end 134.111001 123.238999)
		(width 0.15)
		(layer "In2.Cu")
		(net 326)
	)
	(segment
		(start 131.173349 123.217182)
		(end 131.189184 123.201347)
		(width 0.15)
		(layer "In2.Cu")
		(net 326)
	)
	(segment
		(start 132.954389 123.229095)
		(end 132.973349 123.217182)
		(width 0.15)
		(layer "In2.Cu")
		(net 326)
	)
	(segment
		(start 131.208493 123.161251)
		(end 131.211001 123.138999)
		(width 0.15)
		(layer "In2.Cu")
		(net 326)
	)
	(segment
		(start 134.211001 123.138999)
		(end 134.211001 122.913999)
		(width 0.15)
		(layer "In2.Cu")
		(net 326)
	)
	(segment
		(start 132.561001 122.238999)
		(end 132.594379 122.24276)
		(width 0.15)
		(layer "In2.Cu")
		(net 326)
	)
	(segment
		(start 131.808493 123.161251)
		(end 131.811001 123.138999)
		(width 0.15)
		(layer "In2.Cu")
		(net 326)
	)
	(segment
		(start 133.296146 122.323917)
		(end 133.30724 122.355621)
		(width 0.15)
		(layer "In2.Cu")
		(net 326)
	)
	(segment
		(start 132.748652 123.217182)
		(end 132.767612 123.229095)
		(width 0.15)
		(layer "In2.Cu")
		(net 326)
	)
	(segment
		(start 131.295918 122.253854)
		(end 131.327622 122.24276)
		(width 0.15)
		(layer "In2.Cu")
		(net 326)
	)
	(segment
		(start 130.854389 123.048902)
		(end 130.873349 123.060815)
		(width 0.15)
		(layer "In2.Cu")
		(net 326)
	)
	(segment
		(start 134.111001 123.238999)
		(end 134.133253 123.236491)
		(width 0.15)
		(layer "In2.Cu")
		(net 326)
	)
	(segment
		(start 130.889184 123.07665)
		(end 130.901097 123.09561)
		(width 0.15)
		(layer "In2.Cu")
		(net 326)
	)
	(segment
		(start 132.10724 122.355621)
		(end 132.111001 122.388999)
		(width 0.15)
		(layer "In2.Cu")
		(net 326)
	)
	(segment
		(start 133.608493 123.161251)
		(end 133.611001 123.138999)
		(width 0.15)
		(layer "In2.Cu")
		(net 326)
	)
	(segment
		(start 132.732817 123.201347)
		(end 132.748652 123.217182)
		(width 0.15)
		(layer "In2.Cu")
		(net 326)
	)
	(segment
		(start 131.814761 122.355621)
		(end 131.825855 122.323917)
		(width 0.15)
		(layer "In2.Cu")
		(net 326)
	)
	(segment
		(start 134.189184 123.201347)
		(end 134.201097 123.182387)
		(width 0.15)
		(layer "In2.Cu")
		(net 326)
	)
	(segment
		(start 131.825855 122.323917)
		(end 131.843726 122.295476)
		(width 0.15)
		(layer "In2.Cu")
		(net 326)
	)
	(segment
		(start 131.711001 123.238999)
		(end 131.733253 123.236491)
		(width 0.15)
		(layer "In2.Cu")
		(net 326)
	)
	(segment
		(start 131.611001 123.238999)
		(end 131.711001 123.238999)
		(width 0.15)
		(layer "In2.Cu")
		(net 326)
	)
	(segment
		(start 131.895918 122.253854)
		(end 131.927622 122.24276)
		(width 0.15)
		(layer "In2.Cu")
		(net 326)
	)
	(segment
		(start 131.011001 123.238999)
		(end 131.111001 123.238999)
		(width 0.15)
		(layer "In2.Cu")
		(net 326)
	)
	(segment
		(start 130.811001 123.038999)
		(end 130.833253 123.041506)
		(width 0.15)
		(layer "In2.Cu")
		(net 326)
	)
	(segment
		(start 131.520904 123.182387)
		(end 131.532817 123.201347)
		(width 0.15)
		(layer "In2.Cu")
		(net 326)
	)
	(segment
		(start 133.127622 122.24276)
		(end 133.161001 122.238999)
		(width 0.15)
		(layer "In2.Cu")
		(net 326)
	)
	(segment
		(start 130.908493 123.116746)
		(end 130.913508 123.161251)
		(width 0.15)
		(layer "In2.Cu")
		(net 326)
	)
	(segment
		(start 134.463937 122.816271)
		(end 134.483729 122.836063)
		(width 0.15)
		(layer "In2.Cu")
		(net 326)
	)
	(segment
		(start 134.201097 123.182387)
		(end 134.208493 123.161251)
		(width 0.15)
		(layer "In2.Cu")
		(net 326)
	)
	(segment
		(start 131.532817 123.201347)
		(end 131.548652 123.217182)
		(width 0.15)
		(layer "In2.Cu")
		(net 326)
	)
	(segment
		(start 133.388748 123.236491)
		(end 133.411001 123.238999)
		(width 0.15)
		(layer "In2.Cu")
		(net 326)
	)
	(segment
		(start 132.054524 122.271725)
		(end 132.078275 122.295476)
		(width 0.15)
		(layer "In2.Cu")
		(net 326)
	)
	(segment
		(start 132.111001 122.388999)
		(end 132.111001 123.138999)
		(width 0.15)
		(layer "In2.Cu")
		(net 326)
	)
	(segment
		(start 133.614761 122.355621)
		(end 133.625855 122.323917)
		(width 0.15)
		(layer "In2.Cu")
		(net 326)
	)
	(segment
		(start 132.425855 122.323917)
		(end 132.443726 122.295476)
		(width 0.15)
		(layer "In2.Cu")
		(net 326)
	)
	(segment
		(start 131.243726 122.295476)
		(end 131.267477 122.271725)
		(width 0.15)
		(layer "In2.Cu")
		(net 326)
	)
	(segment
		(start 131.111001 123.238999)
		(end 131.133253 123.236491)
		(width 0.15)
		(layer "In2.Cu")
		(net 326)
	)
	(segment
		(start 133.794379 122.24276)
		(end 133.826083 122.253854)
		(width 0.15)
		(layer "In2.Cu")
		(net 326)
	)
	(segment
		(start 133.761001 122.238999)
		(end 133.794379 122.24276)
		(width 0.15)
		(layer "In2.Cu")
		(net 326)
	)
	(segment
		(start 134.258064 122.816271)
		(end 134.281765 122.801378)
		(width 0.15)
		(layer "In2.Cu")
		(net 326)
	)
	(segment
		(start 131.225855 122.323917)
		(end 131.243726 122.295476)
		(width 0.15)
		(layer "In2.Cu")
		(net 326)
	)
	(segment
		(start 132.333253 123.236491)
		(end 132.354389 123.229095)
		(width 0.15)
		(layer "In2.Cu")
		(net 326)
	)
	(segment
		(start 131.327622 122.24276)
		(end 131.361001 122.238999)
		(width 0.15)
		(layer "In2.Cu")
		(net 326)
	)
	(segment
		(start 133.601097 123.182387)
		(end 133.608493 123.161251)
		(width 0.15)
		(layer "In2.Cu")
		(net 326)
	)
	(segment
		(start 133.911001 123.138999)
		(end 133.913508 123.161251)
		(width 0.15)
		(layer "In2.Cu")
		(net 326)
	)
	(segment
		(start 133.913508 123.161251)
		(end 133.920904 123.182387)
		(width 0.15)
		(layer "In2.Cu")
		(net 326)
	)
	(segment
		(start 130.833253 123.041506)
		(end 130.854389 123.048902)
		(width 0.15)
		(layer "In2.Cu")
		(net 326)
	)
	(segment
		(start 132.788748 123.236491)
		(end 132.811001 123.238999)
		(width 0.15)
		(layer "In2.Cu")
		(net 326)
	)
	(segment
		(start 131.811001 122.388999)
		(end 131.814761 122.355621)
		(width 0.15)
		(layer "In2.Cu")
		(net 326)
	)
	(segment
		(start 130.920904 123.182387)
		(end 130.932817 123.201347)
		(width 0.15)
		(layer "In2.Cu")
		(net 326)
	)
	(segment
		(start 133.043726 122.295476)
		(end 133.067477 122.271725)
		(width 0.15)
		(layer "In2.Cu")
		(net 326)
	)
	(segment
		(start 132.188748 123.236491)
		(end 132.211001 123.238999)
		(width 0.15)
		(layer "In2.Cu")
		(net 326)
	)
	(segment
		(start 131.789184 123.201347)
		(end 131.801097 123.182387)
		(width 0.15)
		(layer "In2.Cu")
		(net 326)
	)
	(segment
		(start 133.008493 123.161251)
		(end 133.011001 123.138999)
		(width 0.15)
		(layer "In2.Cu")
		(net 326)
	)
	(segment
		(start 131.454524 122.271725)
		(end 131.478275 122.295476)
		(width 0.15)
		(layer "In2.Cu")
		(net 326)
	)
	(segment
		(start 131.426083 122.253854)
		(end 131.454524 122.271725)
		(width 0.15)
		(layer "In2.Cu")
		(net 326)
	)
	(segment
		(start 133.554389 123.229095)
		(end 133.573349 123.217182)
		(width 0.15)
		(layer "In2.Cu")
		(net 326)
	)
	(segment
		(start 134.523379 122.968235)
		(end 134.538272 122.991936)
		(width 0.15)
		(layer "In2.Cu")
		(net 326)
	)
	(segment
		(start 134.211001 122.913999)
		(end 134.214135 122.886184)
		(width 0.15)
		(layer "In2.Cu")
		(net 326)
	)
	(segment
		(start 131.994379 122.24276)
		(end 132.026083 122.253854)
		(width 0.15)
		(layer "In2.Cu")
		(net 326)
	)
	(segment
		(start 134.336001 122.788999)
		(end 134.386001 122.788999)
		(width 0.15)
		(layer "In2.Cu")
		(net 326)
	)
	(segment
		(start 132.443726 122.295476)
		(end 132.467477 122.271725)
		(width 0.15)
		(layer "In2.Cu")
		(net 326)
	)
	(segment
		(start 131.961001 122.238999)
		(end 131.994379 122.24276)
		(width 0.15)
		(layer "In2.Cu")
		(net 326)
	)
	(segment
		(start 130.932817 123.201347)
		(end 130.948652 123.217182)
		(width 0.15)
		(layer "In2.Cu")
		(net 326)
	)
	(segment
		(start 132.373349 123.217182)
		(end 132.389184 123.201347)
		(width 0.15)
		(layer "In2.Cu")
		(net 326)
	)
	(segment
		(start 131.211001 123.138999)
		(end 131.211001 122.388999)
		(width 0.15)
		(layer "In2.Cu")
		(net 326)
	)
	(segment
		(start 133.878275 122.295476)
		(end 133.896146 122.323917)
		(width 0.15)
		(layer "In2.Cu")
		(net 326)
	)
	(segment
		(start 133.311001 123.138999)
		(end 133.313508 123.161251)
		(width 0.15)
		(layer "In2.Cu")
		(net 326)
	)
	(segment
		(start 135.308999 123.038999)
		(end 135.784 123.514)
		(width 0.15)
		(layer "In2.Cu")
		(net 326)
	)
	(segment
		(start 134.133253 123.236491)
		(end 134.154389 123.229095)
		(width 0.15)
		(layer "In2.Cu")
		(net 326)
	)
	(segment
		(start 131.843726 122.295476)
		(end 131.867477 122.271725)
		(width 0.15)
		(layer "In2.Cu")
		(net 326)
	)
	(segment
		(start 133.611001 123.138999)
		(end 133.611001 122.388999)
		(width 0.15)
		(layer "In2.Cu")
		(net 326)
	)
	(segment
		(start 132.111001 123.138999)
		(end 132.113508 123.161251)
		(width 0.15)
		(layer "In2.Cu")
		(net 326)
	)
	(segment
		(start 134.281765 122.801378)
		(end 134.308185 122.792134)
		(width 0.15)
		(layer "In2.Cu")
		(net 326)
	)
	(segment
		(start 132.594379 122.24276)
		(end 132.626083 122.253854)
		(width 0.15)
		(layer "In2.Cu")
		(net 326)
	)
	(segment
		(start 131.133253 123.236491)
		(end 131.154389 123.229095)
		(width 0.15)
		(layer "In2.Cu")
		(net 326)
	)
	(segment
		(start 107.399237 116.474959)
		(end 115.147794 116.474959)
		(width 0.15)
		(layer "In2.Cu")
		(net 326)
	)
	(segment
		(start 134.413816 122.792134)
		(end 134.440236 122.801378)
		(width 0.15)
		(layer "In2.Cu")
		(net 326)
	)
	(segment
		(start 133.411001 123.238999)
		(end 133.511001 123.238999)
		(width 0.15)
		(layer "In2.Cu")
		(net 326)
	)
	(segment
		(start 133.854524 122.271725)
		(end 133.878275 122.295476)
		(width 0.15)
		(layer "In2.Cu")
		(net 326)
	)
	(segment
		(start 134.308185 122.792134)
		(end 134.336001 122.788999)
		(width 0.15)
		(layer "In2.Cu")
		(net 326)
	)
	(segment
		(start 132.911001 123.238999)
		(end 132.933253 123.236491)
		(width 0.15)
		(layer "In2.Cu")
		(net 326)
	)
	(segment
		(start 132.096146 122.323917)
		(end 132.10724 122.355621)
		(width 0.15)
		(layer "In2.Cu")
		(net 326)
	)
	(segment
		(start 133.667477 122.271725)
		(end 133.695918 122.253854)
		(width 0.15)
		(layer "In2.Cu")
		(net 326)
	)
	(segment
		(start 131.513508 123.161251)
		(end 131.520904 123.182387)
		(width 0.15)
		(layer "In2.Cu")
		(net 326)
	)
	(segment
		(start 134.514135 122.941815)
		(end 134.523379 122.968235)
		(width 0.15)
		(layer "In2.Cu")
		(net 326)
	)
	(segment
		(start 134.498622 122.859764)
		(end 134.507866 122.886184)
		(width 0.15)
		(layer "In2.Cu")
		(net 326)
	)
	(segment
		(start 133.643726 122.295476)
		(end 133.667477 122.271725)
		(width 0.15)
		(layer "In2.Cu")
		(net 326)
	)
	(segment
		(start 131.189184 123.201347)
		(end 131.201097 123.182387)
		(width 0.15)
		(layer "In2.Cu")
		(net 326)
	)
	(segment
		(start 133.001097 123.182387)
		(end 133.008493 123.161251)
		(width 0.15)
		(layer "In2.Cu")
		(net 326)
	)
	(segment
		(start 134.507866 122.886184)
		(end 134.514135 122.941815)
		(width 0.15)
		(layer "In2.Cu")
		(net 326)
	)
	(segment
		(start 133.511001 123.238999)
		(end 133.533253 123.236491)
		(width 0.15)
		(layer "In2.Cu")
		(net 326)
	)
	(segment
		(start 132.120904 123.182387)
		(end 132.132817 123.201347)
		(width 0.15)
		(layer "In2.Cu")
		(net 326)
	)
	(segment
		(start 130.948652 123.217182)
		(end 130.967612 123.229095)
		(width 0.15)
		(layer "In2.Cu")
		(net 326)
	)
	(segment
		(start 131.267477 122.271725)
		(end 131.295918 122.253854)
		(width 0.15)
		(layer "In2.Cu")
		(net 326)
	)
	(segment
		(start 131.394379 122.24276)
		(end 131.426083 122.253854)
		(width 0.15)
		(layer "In2.Cu")
		(net 326)
	)
	(segment
		(start 133.320904 123.182387)
		(end 133.332817 123.201347)
		(width 0.15)
		(layer "In2.Cu")
		(net 326)
	)
	(segment
		(start 132.354389 123.229095)
		(end 132.373349 123.217182)
		(width 0.15)
		(layer "In2.Cu")
		(net 326)
	)
	(segment
		(start 132.389184 123.201347)
		(end 132.401097 123.182387)
		(width 0.15)
		(layer "In2.Cu")
		(net 326)
	)
	(segment
		(start 132.414761 122.355621)
		(end 132.425855 122.323917)
		(width 0.15)
		(layer "In2.Cu")
		(net 326)
	)
	(segment
		(start 132.767612 123.229095)
		(end 132.788748 123.236491)
		(width 0.15)
		(layer "In2.Cu")
		(net 326)
	)
	(segment
		(start 133.194379 122.24276)
		(end 133.226083 122.253854)
		(width 0.15)
		(layer "In2.Cu")
		(net 326)
	)
	(segment
		(start 133.348652 123.217182)
		(end 133.367612 123.229095)
		(width 0.15)
		(layer "In2.Cu")
		(net 326)
	)
	(segment
		(start 131.361001 122.238999)
		(end 131.394379 122.24276)
		(width 0.15)
		(layer "In2.Cu")
		(net 326)
	)
	(segment
		(start 130.988748 123.236491)
		(end 131.011001 123.238999)
		(width 0.15)
		(layer "In2.Cu")
		(net 326)
	)
	(segment
		(start 134.558064 123.011728)
		(end 134.581765 123.026621)
		(width 0.15)
		(layer "In2.Cu")
		(net 326)
	)
	(segment
		(start 132.696146 122.323917)
		(end 132.70724 122.355621)
		(width 0.15)
		(layer "In2.Cu")
		(net 326)
	)
	(segment
		(start 132.211001 123.238999)
		(end 132.311001 123.238999)
		(width 0.15)
		(layer "In2.Cu")
		(net 326)
	)
	(segment
		(start 131.801097 123.182387)
		(end 131.808493 123.161251)
		(width 0.15)
		(layer "In2.Cu")
		(net 326)
	)
	(segment
		(start 133.011001 122.388999)
		(end 133.014761 122.355621)
		(width 0.15)
		(layer "In2.Cu")
		(net 326)
	)
	(segment
		(start 134.214135 122.886184)
		(end 134.223379 122.859764)
		(width 0.15)
		(layer "In2.Cu")
		(net 326)
	)
	(segment
		(start 132.527622 122.24276)
		(end 132.561001 122.238999)
		(width 0.15)
		(layer "In2.Cu")
		(net 326)
	)
	(segment
		(start 131.773349 123.217182)
		(end 131.789184 123.201347)
		(width 0.15)
		(layer "In2.Cu")
		(net 326)
	)
	(segment
		(start 132.720904 123.182387)
		(end 132.732817 123.201347)
		(width 0.15)
		(layer "In2.Cu")
		(net 326)
	)
	(segment
		(start 132.401097 123.182387)
		(end 132.408493 123.161251)
		(width 0.15)
		(layer "In2.Cu")
		(net 326)
	)
	(segment
		(start 134.386001 122.788999)
		(end 134.413816 122.792134)
		(width 0.15)
		(layer "In2.Cu")
		(net 326)
	)
	(segment
		(start 134.223379 122.859764)
		(end 134.238272 122.836063)
		(width 0.15)
		(layer "In2.Cu")
		(net 326)
	)
	(segment
		(start 132.989184 123.201347)
		(end 133.001097 123.182387)
		(width 0.15)
		(layer "In2.Cu")
		(net 326)
	)
	(segment
		(start 131.567612 123.229095)
		(end 131.588748 123.236491)
		(width 0.15)
		(layer "In2.Cu")
		(net 326)
	)
	(segment
		(start 131.811001 123.138999)
		(end 131.811001 122.388999)
		(width 0.15)
		(layer "In2.Cu")
		(net 326)
	)
	(segment
		(start 131.478275 122.295476)
		(end 131.496146 122.323917)
		(width 0.15)
		(layer "In2.Cu")
		(net 326)
	)
	(segment
		(start 132.678275 122.295476)
		(end 132.696146 122.323917)
		(width 0.15)
		(layer "In2.Cu")
		(net 326)
	)
	(segment
		(start 132.467477 122.271725)
		(end 132.495918 122.253854)
		(width 0.15)
		(layer "In2.Cu")
		(net 326)
	)
	(segment
		(start 132.311001 123.238999)
		(end 132.333253 123.236491)
		(width 0.15)
		(layer "In2.Cu")
		(net 326)
	)
	(segment
		(start 132.70724 122.355621)
		(end 132.711001 122.388999)
		(width 0.15)
		(layer "In2.Cu")
		(net 326)
	)
	(segment
		(start 121.047835 122.375)
		(end 129.875 122.375)
		(width 0.15)
		(layer "In2.Cu")
		(net 326)
	)
	(segment
		(start 131.548652 123.217182)
		(end 131.567612 123.229095)
		(width 0.15)
		(layer "In2.Cu")
		(net 326)
	)
	(segment
		(start 132.408493 123.161251)
		(end 132.411001 123.138999)
		(width 0.15)
		(layer "In2.Cu")
		(net 326)
	)
	(segment
		(start 131.511001 122.388999)
		(end 131.511001 123.138999)
		(width 0.15)
		(layer "In2.Cu")
		(net 326)
	)
	(segment
		(start 133.90724 122.355621)
		(end 133.911001 122.388999)
		(width 0.15)
		(layer "In2.Cu")
		(net 326)
	)
	(segment
		(start 133.988748 123.236491)
		(end 134.011001 123.238999)
		(width 0.15)
		(layer "In2.Cu")
		(net 326)
	)
	(segment
		(start 132.711001 123.138999)
		(end 132.713508 123.161251)
		(width 0.15)
		(layer "In2.Cu")
		(net 326)
	)
	(segment
		(start 132.113508 123.161251)
		(end 132.120904 123.182387)
		(width 0.15)
		(layer "In2.Cu")
		(net 326)
	)
	(segment
		(start 133.313508 123.161251)
		(end 133.320904 123.182387)
		(width 0.15)
		(layer "In2.Cu")
		(net 326)
	)
	(segment
		(start 106.19999 115.275712)
		(end 107.399237 116.474959)
		(width 0.15)
		(layer "In2.Cu")
		(net 326)
	)
	(segment
		(start 132.713508 123.161251)
		(end 132.720904 123.182387)
		(width 0.15)
		(layer "In2.Cu")
		(net 326)
	)
	(segment
		(start 115.147794 116.474959)
		(end 121.047835 122.375)
		(width 0.15)
		(layer "In2.Cu")
		(net 326)
	)
	(segment
		(start 131.754389 123.229095)
		(end 131.773349 123.217182)
		(width 0.15)
		(layer "In2.Cu")
		(net 326)
	)
	(segment
		(start 133.014761 122.355621)
		(end 133.025855 122.323917)
		(width 0.15)
		(layer "In2.Cu")
		(net 326)
	)
	(segment
		(start 131.588748 123.236491)
		(end 131.611001 123.238999)
		(width 0.15)
		(layer "In2.Cu")
		(net 326)
	)
	(segment
		(start 132.654524 122.271725)
		(end 132.678275 122.295476)
		(width 0.15)
		(layer "In2.Cu")
		(net 326)
	)
	(segment
		(start 132.167612 123.229095)
		(end 132.188748 123.236491)
		(width 0.15)
		(layer "In2.Cu")
		(net 326)
	)
	(segment
		(start 133.278275 122.295476)
		(end 133.296146 122.323917)
		(width 0.15)
		(layer "In2.Cu")
		(net 326)
	)
	(segment
		(start 130.967612 123.229095)
		(end 130.988748 123.236491)
		(width 0.15)
		(layer "In2.Cu")
		(net 326)
	)
	(segment
		(start 134.173349 123.217182)
		(end 134.189184 123.201347)
		(width 0.15)
		(layer "In2.Cu")
		(net 326)
	)
	(segment
		(start 132.148652 123.217182)
		(end 132.167612 123.229095)
		(width 0.15)
		(layer "In2.Cu")
		(net 326)
	)
	(segment
		(start 133.920904 123.182387)
		(end 133.932817 123.201347)
		(width 0.15)
		(layer "In2.Cu")
		(net 326)
	)
	(segment
		(start 134.608185 123.035865)
		(end 134.636001 123.038999)
		(width 0.15)
		(layer "In2.Cu")
		(net 326)
	)
	(segment
		(start 133.011001 123.138999)
		(end 133.011001 122.388999)
		(width 0.15)
		(layer "In2.Cu")
		(net 326)
	)
	(segment
		(start 133.025855 122.323917)
		(end 133.043726 122.295476)
		(width 0.15)
		(layer "In2.Cu")
		(net 326)
	)
	(segment
		(start 130.901097 123.09561)
		(end 130.908493 123.116746)
		(width 0.15)
		(layer "In2.Cu")
		(net 326)
	)
	(segment
		(start 133.095918 122.253854)
		(end 133.127622 122.24276)
		(width 0.15)
		(layer "In2.Cu")
		(net 326)
	)
	(segment
		(start 132.933253 123.236491)
		(end 132.954389 123.229095)
		(width 0.15)
		(layer "In2.Cu")
		(net 326)
	)
	(segment
		(start 132.973349 123.217182)
		(end 132.989184 123.201347)
		(width 0.15)
		(layer "In2.Cu")
		(net 326)
	)
	(segment
		(start 133.573349 123.217182)
		(end 133.589184 123.201347)
		(width 0.15)
		(layer "In2.Cu")
		(net 326)
	)
	(segment
		(start 131.214761 122.355621)
		(end 131.225855 122.323917)
		(width 0.15)
		(layer "In2.Cu")
		(net 326)
	)
	(segment
		(start 130.913508 123.161251)
		(end 130.920904 123.182387)
		(width 0.15)
		(layer "In2.Cu")
		(net 326)
	)
	(segment
		(start 132.411001 122.388999)
		(end 132.414761 122.355621)
		(width 0.15)
		(layer "In2.Cu")
		(net 326)
	)
	(segment
		(start 133.948652 123.217182)
		(end 133.967612 123.229095)
		(width 0.15)
		(layer "In2.Cu")
		(net 326)
	)
	(segment
		(start 133.727622 122.24276)
		(end 133.761001 122.238999)
		(width 0.15)
		(layer "In2.Cu")
		(net 326)
	)
	(segment
		(start 133.911001 122.388999)
		(end 133.911001 123.138999)
		(width 0.15)
		(layer "In2.Cu")
		(net 326)
	)
	(segment
		(start 132.711001 122.388999)
		(end 132.711001 123.138999)
		(width 0.15)
		(layer "In2.Cu")
		(net 326)
	)
	(segment
		(start 133.30724 122.355621)
		(end 133.311001 122.388999)
		(width 0.15)
		(layer "In2.Cu")
		(net 326)
	)
	(segment
		(start 133.367612 123.229095)
		(end 133.388748 123.236491)
		(width 0.15)
		(layer "In2.Cu")
		(net 326)
	)
	(segment
		(start 132.132817 123.201347)
		(end 132.148652 123.217182)
		(width 0.15)
		(layer "In2.Cu")
		(net 326)
	)
	(segment
		(start 134.636001 123.038999)
		(end 135.308999 123.038999)
		(width 0.15)
		(layer "In2.Cu")
		(net 326)
	)
	(segment
		(start 131.211001 122.388999)
		(end 131.214761 122.355621)
		(width 0.15)
		(layer "In2.Cu")
		(net 326)
	)
	(segment
		(start 132.626083 122.253854)
		(end 132.654524 122.271725)
		(width 0.15)
		(layer "In2.Cu")
		(net 326)
	)
	(segment
		(start 133.695918 122.253854)
		(end 133.727622 122.24276)
		(width 0.15)
		(layer "In2.Cu")
		(net 326)
	)
	(segment
		(start 133.311001 122.388999)
		(end 133.311001 123.138999)
		(width 0.15)
		(layer "In2.Cu")
		(net 326)
	)
	(segment
		(start 132.078275 122.295476)
		(end 132.096146 122.323917)
		(width 0.15)
		(layer "In2.Cu")
		(net 326)
	)
	(segment
		(start 133.967612 123.229095)
		(end 133.988748 123.236491)
		(width 0.15)
		(layer "In2.Cu")
		(net 326)
	)
	(segment
		(start 133.067477 122.271725)
		(end 133.095918 122.253854)
		(width 0.15)
		(layer "In2.Cu")
		(net 326)
	)
	(segment
		(start 130.873349 123.060815)
		(end 130.889184 123.07665)
		(width 0.15)
		(layer "In2.Cu")
		(net 326)
	)
	(segment
		(start 133.589184 123.201347)
		(end 133.601097 123.182387)
		(width 0.15)
		(layer "In2.Cu")
		(net 326)
	)
	(segment
		(start 132.411001 123.138999)
		(end 132.411001 122.388999)
		(width 0.15)
		(layer "In2.Cu")
		(net 326)
	)
	(segment
		(start 133.161001 122.238999)
		(end 133.194379 122.24276)
		(width 0.15)
		(layer "In2.Cu")
		(net 326)
	)
	(segment
		(start 132.026083 122.253854)
		(end 132.054524 122.271725)
		(width 0.15)
		(layer "In2.Cu")
		(net 326)
	)
	(segment
		(start 131.50724 122.355621)
		(end 131.511001 122.388999)
		(width 0.15)
		(layer "In2.Cu")
		(net 326)
	)
	(segment
		(start 131.511001 123.138999)
		(end 131.513508 123.161251)
		(width 0.15)
		(layer "In2.Cu")
		(net 326)
	)
	(segment
		(start 133.896146 122.323917)
		(end 133.90724 122.355621)
		(width 0.15)
		(layer "In2.Cu")
		(net 326)
	)
	(segment
		(start 130.538999 123.038999)
		(end 130.811001 123.038999)
		(width 0.15)
		(layer "In2.Cu")
		(net 326)
	)
	(segment
		(start 133.611001 122.388999)
		(end 133.614761 122.355621)
		(width 0.15)
		(layer "In2.Cu")
		(net 326)
	)
	(segment
		(start 134.483729 122.836063)
		(end 134.498622 122.859764)
		(width 0.15)
		(layer "In2.Cu")
		(net 326)
	)
	(segment
		(start 133.625855 122.323917)
		(end 133.643726 122.295476)
		(width 0.15)
		(layer "In2.Cu")
		(net 326)
	)
	(segment
		(start 133.533253 123.236491)
		(end 133.554389 123.229095)
		(width 0.15)
		(layer "In2.Cu")
		(net 326)
	)
	(segment
		(start 131.733253 123.236491)
		(end 131.754389 123.229095)
		(width 0.15)
		(layer "In2.Cu")
		(net 326)
	)
	(segment
		(start 134.238272 122.836063)
		(end 134.258064 122.816271)
		(width 0.15)
		(layer "In2.Cu")
		(net 326)
	)
	(segment
		(start 134.154389 123.229095)
		(end 134.173349 123.217182)
		(width 0.15)
		(layer "In2.Cu")
		(net 326)
	)
	(segment
		(start 129.875 122.375)
		(end 130.538999 123.038999)
		(width 0.15)
		(layer "In2.Cu")
		(net 326)
	)
	(segment
		(start 131.496146 122.323917)
		(end 131.50724 122.355621)
		(width 0.15)
		(layer "In2.Cu")
		(net 326)
	)
	(segment
		(start 133.254524 122.271725)
		(end 133.278275 122.295476)
		(width 0.15)
		(layer "In2.Cu")
		(net 326)
	)
	(segment
		(start 134.440236 122.801378)
		(end 134.463937 122.816271)
		(width 0.15)
		(layer "In2.Cu")
		(net 326)
	)
	(segment
		(start 106.19999 114.675)
		(end 106.19999 115.275712)
		(width 0.15)
		(layer "In2.Cu")
		(net 326)
	)
	(segment
		(start 134.538272 122.991936)
		(end 134.558064 123.011728)
		(width 0.15)
		(layer "In2.Cu")
		(net 326)
	)
	(segment
		(start 133.332817 123.201347)
		(end 133.348652 123.217182)
		(width 0.15)
		(layer "In2.Cu")
		(net 326)
	)
	(segment
		(start 133.826083 122.253854)
		(end 133.854524 122.271725)
		(width 0.15)
		(layer "In2.Cu")
		(net 326)
	)
	(segment
		(start 133.226083 122.253854)
		(end 133.254524 122.271725)
		(width 0.15)
		(layer "In2.Cu")
		(net 326)
	)
	(segment
		(start 132.811001 123.238999)
		(end 132.911001 123.238999)
		(width 0.15)
		(layer "In2.Cu")
		(net 326)
	)
	(segment
		(start 131.927622 122.24276)
		(end 131.961001 122.238999)
		(width 0.15)
		(layer "In2.Cu")
		(net 326)
	)
	(segment
		(start 134.208493 123.161251)
		(end 134.211001 123.138999)
		(width 0.15)
		(layer "In2.Cu")
		(net 326)
	)
	(segment
		(start 132.495918 122.253854)
		(end 132.527622 122.24276)
		(width 0.15)
		(layer "In2.Cu")
		(net 326)
	)
	(segment
		(start 133.932817 123.201347)
		(end 133.948652 123.217182)
		(width 0.15)
		(layer "In2.Cu")
		(net 326)
	)
	(segment
		(start 131.201097 123.182387)
		(end 131.208493 123.161251)
		(width 0.15)
		(layer "In2.Cu")
		(net 326)
	)
	(segment
		(start 131.867477 122.271725)
		(end 131.895918 122.253854)
		(width 0.15)
		(layer "In2.Cu")
		(net 326)
	)
	(segment
		(start 131.154389 123.229095)
		(end 131.173349 123.217182)
		(width 0.15)
		(layer "In2.Cu")
		(net 326)
	)
	(segment
		(start 134.581765 123.026621)
		(end 134.608185 123.035865)
		(width 0.15)
		(layer "In2.Cu")
		(net 326)
	)
	(segment
		(start 135.274 121.014)
		(end 135.274 121.024)
		(width 0.15)
		(layer "F.Cu")
		(net 327)
	)
	(segment
		(start 135.274 121.024)
		(end 134.774 121.524)
		(width 0.15)
		(layer "F.Cu")
		(net 327)
	)
	(segment
		(start 135.264 121.034)
		(end 134.774 121.524)
		(width 0.1)
		(layer "F.Cu")
		(net 327)
	)
	(segment
		(start 105.775 113.175)
		(end 106.275 113.675)
		(width 0.15)
		(layer "F.Cu")
		(net 327)
	)
	(via
		(at 134.774 121.524)
		(size 0.5)
		(drill 0.2)
		(layers "F.Cu" "B.Cu")
		(net 327)
	)
	(via blind
		(at 106.275 113.675)
		(size 0.5)
		(drill 0.2)
		(layers "F.Cu" "In2.Cu")
		(net 327)
	)
	(segment
		(start 134.804 121.494)
		(end 134.774 121.524)
		(width 0.1)
		(layer "B.Cu")
		(net 327)
	)
	(segment
		(start 134.804 120.927)
		(end 134.804 121.494)
		(width 0.1)
		(layer "B.Cu")
		(net 327)
	)
	(segment
		(start 131.25 121.48719)
		(end 131.25376 121.453812)
		(width 0.15)
		(layer "In2.Cu")
		(net 327)
	)
	(segment
		(start 131.764854 121.422108)
		(end 131.782725 121.393667)
		(width 0.15)
		(layer "In2.Cu")
		(net 327)
	)
	(segment
		(start 132.2 121.975)
		(end 132.1 121.975)
		(width 0.15)
		(layer "In2.Cu")
		(net 327)
	)
	(segment
		(start 128.465082 121.352045)
		(end 128.493523 121.369916)
		(width 0.15)
		(layer "In2.Cu")
		(net 327)
	)
	(segment
		(start 129.775943 122.097777)
		(end 129.789008 122.105986)
		(width 0.15)
		(layer "In2.Cu")
		(net 327)
	)
	(segment
		(start 131.782725 121.393667)
		(end 131.806476 121.369916)
		(width 0.15)
		(layer "In2.Cu")
		(net 327)
	)
	(segment
		(start 131.264854 121.422108)
		(end 131.282725 121.393667)
		(width 0.15)
		(layer "In2.Cu")
		(net 327)
	)
	(segment
		(start 115.175 116.075)
		(end 121.075 121.975)
		(width 0.15)
		(layer "In2.Cu")
		(net 327)
	)
	(segment
		(start 130.05376 121.453812)
		(end 130.064854 121.422108)
		(width 0.15)
		(layer "In2.Cu")
		(net 327)
	)
	(segment
		(start 121.075 121.975)
		(end 127.875 121.975)
		(width 0.15)
		(layer "In2.Cu")
		(net 327)
	)
	(segment
		(start 131.133378 121.97124)
		(end 131.165082 121.960146)
		(width 0.15)
		(layer "In2.Cu")
		(net 327)
	)
	(segment
		(start 132.306476 121.369916)
		(end 132.334917 121.352045)
		(width 0.15)
		(layer "In2.Cu")
		(net 327)
	)
	(segment
		(start 128.843176 122.073801)
		(end 128.848272 122.059237)
		(width 0.15)
		(layer "In2.Cu")
		(net 327)
	)
	(segment
		(start 129.981095 122.11281)
		(end 129.996427 122.111082)
		(width 0.15)
		(layer "In2.Cu")
		(net 327)
	)
	(segment
		(start 131.6 121.975)
		(end 131.633378 121.97124)
		(width 0.15)
		(layer "In2.Cu")
		(net 327)
	)
	(segment
		(start 128.217961 122.097777)
		(end 128.228872 122.086866)
		(width 0.15)
		(layer "In2.Cu")
		(net 327)
	)
	(segment
		(start 128.4 121.33719)
		(end 128.433378 121.340951)
		(width 0.15)
		(layer "In2.Cu")
		(net 327)
	)
	(segment
		(start 130.565082 122.547955)
		(end 130.593523 122.530084)
		(width 0.15)
		(layer "In2.Cu")
		(net 327)
	)
	(segment
		(start 129.448272 122.059237)
		(end 129.45 122.043905)
		(width 0.15)
		(layer "In2.Cu")
		(net 327)
	)
	(segment
		(start 129.789008 122.105986)
		(end 129.803572 122.111082)
		(width 0.15)
		(layer "In2.Cu")
		(net 327)
	)
	(segment
		(start 131.246239 121.858379)
		(end 131.25 121.825)
		(width 0.15)
		(layer "In2.Cu")
		(net 327)
	)
	(segment
		(start 128.966621 121.340951)
		(end 129 121.33719)
		(width 0.15)
		(layer "In2.Cu")
		(net 327)
	)
	(segment
		(start 132.55 121.48719)
		(end 132.55 121.825)
		(width 0.15)
		(layer "In2.Cu")
		(net 327)
	)
	(segment
		(start 129.117274 121.393667)
		(end 129.135145 121.422108)
		(width 0.15)
		(layer "In2.Cu")
		(net 327)
	)
	(segment
		(start 130.982725 121.918524)
		(end 131.006476 121.942275)
		(width 0.15)
		(layer "In2.Cu")
		(net 327)
	)
	(segment
		(start 129.6 121.33719)
		(end 129.633378 121.340951)
		(width 0.15)
		(layer "In2.Cu")
		(net 327)
	)
	(segment
		(start 131.517274 121.393667)
		(end 131.535145 121.422108)
		(width 0.15)
		(layer "In2.Cu")
		(net 327)
	)
	(segment
		(start 130.35 121.48719)
		(end 130.35 122.41281)
		(width 0.15)
		(layer "In2.Cu")
		(net 327)
	)
	(segment
		(start 128.228872 122.086866)
		(end 128.237081 122.073801)
		(width 0.15)
		(layer "In2.Cu")
		(net 327)
	)
	(segment
		(start 129.203572 122.111082)
		(end 129.218905 122.11281)
		(width 0.15)
		(layer "In2.Cu")
		(net 327)
	)
	(segment
		(start 129.434967 122.086866)
		(end 129.443176 122.073801)
		(width 0.15)
		(layer "In2.Cu")
		(net 327)
	)
	(segment
		(start 128.882725 121.393667)
		(end 128.906476 121.369916)
		(width 0.15)
		(layer "In2.Cu")
		(net 327)
	)
	(segment
		(start 128.306476 121.369916)
		(end 128.334917 121.352045)
		(width 0.15)
		(layer "In2.Cu")
		(net 327)
	)
	(segment
		(start 131.75 121.48719)
		(end 131.75376 121.453812)
		(width 0.15)
		(layer "In2.Cu")
		(net 327)
	)
	(segment
		(start 130.010991 122.105986)
		(end 130.024056 122.097777)
		(width 0.15)
		(layer "In2.Cu")
		(net 327)
	)
	(segment
		(start 131.55376 121.858379)
		(end 131.564854 121.890083)
		(width 0.15)
		(layer "In2.Cu")
		(net 327)
	)
	(segment
		(start 131.465082 121.352045)
		(end 131.493523 121.369916)
		(width 0.15)
		(layer "In2.Cu")
		(net 327)
	)
	(segment
		(start 129.093523 121.369916)
		(end 129.117274 121.393667)
		(width 0.15)
		(layer "In2.Cu")
		(net 327)
	)
	(segment
		(start 128.834967 122.086866)
		(end 128.843176 122.073801)
		(width 0.15)
		(layer "In2.Cu")
		(net 327)
	)
	(segment
		(start 131.433378 121.340951)
		(end 131.465082 121.352045)
		(width 0.15)
		(layer "In2.Cu")
		(net 327)
	)
	(segment
		(start 131.965082 121.352045)
		(end 131.993523 121.369916)
		(width 0.15)
		(layer "In2.Cu")
		(net 327)
	)
	(segment
		(start 131.834917 121.352045)
		(end 131.866621 121.340951)
		(width 0.15)
		(layer "In2.Cu")
		(net 327)
	)
	(segment
		(start 129.156823 122.073801)
		(end 129.165032 122.086866)
		(width 0.15)
		(layer "In2.Cu")
		(net 327)
	)
	(segment
		(start 129.218905 122.11281)
		(end 129.381095 122.11281)
		(width 0.15)
		(layer "In2.Cu")
		(net 327)
	)
	(segment
		(start 129.146239 121.453812)
		(end 129.15 121.48719)
		(width 0.15)
		(layer "In2.Cu")
		(net 327)
	)
	(segment
		(start 129.135145 121.422108)
		(end 129.146239 121.453812)
		(width 0.15)
		(layer "In2.Cu")
		(net 327)
	)
	(segment
		(start 128.25 121.48719)
		(end 128.25376 121.453812)
		(width 0.15)
		(layer "In2.Cu")
		(net 327)
	)
	(segment
		(start 127.937081 122.014008)
		(end 127.942177 122.028572)
		(width 0.15)
		(layer "In2.Cu")
		(net 327)
	)
	(segment
		(start 131.217274 121.918524)
		(end 131.235145 121.890083)
		(width 0.15)
		(layer "In2.Cu")
		(net 327)
	)
	(segment
		(start 129.381095 122.11281)
		(end 129.396427 122.111082)
		(width 0.15)
		(layer "In2.Cu")
		(net 327)
	)
	(segment
		(start 132.264854 121.422108)
		(end 132.282725 121.393667)
		(width 0.15)
		(layer "In2.Cu")
		(net 327)
	)
	(segment
		(start 132.05 121.48719)
		(end 132.05 121.825)
		(width 0.15)
		(layer "In2.Cu")
		(net 327)
	)
	(segment
		(start 130.893523 121.369916)
		(end 130.917274 121.393667)
		(width 0.15)
		(layer "In2.Cu")
		(net 327)
	)
	(segment
		(start 132.05 121.825)
		(end 132.05376 121.858379)
		(width 0.15)
		(layer "In2.Cu")
		(net 327)
	)
	(segment
		(start 128.264854 121.422108)
		(end 128.282725 121.393667)
		(width 0.15)
		(layer "In2.Cu")
		(net 327)
	)
	(segment
		(start 127.904896 121.981823)
		(end 127.917961 121.990032)
		(width 0.15)
		(layer "In2.Cu")
		(net 327)
	)
	(segment
		(start 132.235145 121.890083)
		(end 132.246239 121.858379)
		(width 0.15)
		(layer "In2.Cu")
		(net 327)
	)
	(segment
		(start 128.864854 121.422108)
		(end 128.882725 121.393667)
		(width 0.15)
		(layer "In2.Cu")
		(net 327)
	)
	(segment
		(start 127.982913 122.105986)
		(end 127.997477 122.111082)
		(width 0.15)
		(layer "In2.Cu")
		(net 327)
	)
	(segment
		(start 129.746239 121.453812)
		(end 129.75 121.48719)
		(width 0.15)
		(layer "In2.Cu")
		(net 327)
	)
	(segment
		(start 129.45376 121.453812)
		(end 129.464854 121.422108)
		(width 0.15)
		(layer "In2.Cu")
		(net 327)
	)
	(segment
		(start 128.517274 121.393667)
		(end 128.535145 121.422108)
		(width 0.15)
		(layer "In2.Cu")
		(net 327)
	)
	(segment
		(start 129.15 122.043905)
		(end 129.151727 122.059237)
		(width 0.15)
		(layer "In2.Cu")
		(net 327)
	)
	(segment
		(start 130.664854 121.422108)
		(end 130.682725 121.393667)
		(width 0.15)
		(layer "In2.Cu")
		(net 327)
	)
	(segment
		(start 130.335145 121.422108)
		(end 130.346239 121.453812)
		(width 0.15)
		(layer "In2.Cu")
		(net 327)
	)
	(segment
		(start 130.593523 122.530084)
		(end 130.617274 122.506333)
		(width 0.15)
		(layer "In2.Cu")
		(net 327)
	)
	(segment
		(start 129.45 121.48719)
		(end 129.45376 121.453812)
		(width 0.15)
		(layer "In2.Cu")
		(net 327)
	)
	(segment
		(start 130.2 121.33719)
		(end 130.233378 121.340951)
		(width 0.15)
		(layer "In2.Cu")
		(net 327)
	)
	(segment
		(start 131.193523 121.942275)
		(end 131.217274 121.918524)
		(width 0.15)
		(layer "In2.Cu")
		(net 327)
	)
	(segment
		(start 130.466621 122.559049)
		(end 130.5 122.56281)
		(width 0.15)
		(layer "In2.Cu")
		(net 327)
	)
	(segment
		(start 129.665082 121.352045)
		(end 129.693523 121.369916)
		(width 0.15)
		(layer "In2.Cu")
		(net 327)
	)
	(segment
		(start 129.15 121.48719)
		(end 129.15 122.043905)
		(width 0.15)
		(layer "In2.Cu")
		(net 327)
	)
	(segment
		(start 132.606476 121.942275)
		(end 132.634917 121.960146)
		(width 0.15)
		(layer "In2.Cu")
		(net 327)
	)
	(segment
		(start 132.046239 121.453812)
		(end 132.05 121.48719)
		(width 0.15)
		(layer "In2.Cu")
		(net 327)
	)
	(segment
		(start 128.824056 122.097777)
		(end 128.834967 122.086866)
		(width 0.15)
		(layer "In2.Cu")
		(net 327)
	)
	(segment
		(start 131.4 121.33719)
		(end 131.433378 121.340951)
		(width 0.15)
		(layer "In2.Cu")
		(net 327)
	)
	(segment
		(start 131.746239 121.858379)
		(end 131.75 121.825)
		(width 0.15)
		(layer "In2.Cu")
		(net 327)
	)
	(segment
		(start 130.734917 121.352045)
		(end 130.766621 121.340951)
		(width 0.15)
		(layer "In2.Cu")
		(net 327)
	)
	(segment
		(start 132.282725 121.393667)
		(end 132.306476 121.369916)
		(width 0.15)
		(layer "In2.Cu")
		(net 327)
	)
	(segment
		(start 132.366621 121.340951)
		(end 132.4 121.33719)
		(width 0.15)
		(layer "In2.Cu")
		(net 327)
	)
	(segment
		(start 131.693523 121.942275)
		(end 131.717274 121.918524)
		(width 0.15)
		(layer "In2.Cu")
		(net 327)
	)
	(segment
		(start 128.781095 122.11281)
		(end 128.796427 122.111082)
		(width 0.15)
		(layer "In2.Cu")
		(net 327)
	)
	(segment
		(start 131.006476 121.942275)
		(end 131.034917 121.960146)
		(width 0.15)
		(layer "In2.Cu")
		(net 327)
	)
	(segment
		(start 131.55 121.825)
		(end 131.55376 121.858379)
		(width 0.15)
		(layer "In2.Cu")
		(net 327)
	)
	(segment
		(start 130.317274 121.393667)
		(end 130.335145 121.422108)
		(width 0.15)
		(layer "In2.Cu")
		(net 327)
	)
	(segment
		(start 129.165032 122.086866)
		(end 129.175943 122.097777)
		(width 0.15)
		(layer "In2.Cu")
		(net 327)
	)
	(segment
		(start 128.01281 122.11281)
		(end 128.175 122.11281)
		(width 0.15)
		(layer "In2.Cu")
		(net 327)
	)
	(segment
		(start 129.151727 122.059237)
		(end 129.156823 122.073801)
		(width 0.15)
		(layer "In2.Cu")
		(net 327)
	)
	(segment
		(start 127.890332 121.976727)
		(end 127.904896 121.981823)
		(width 0.15)
		(layer "In2.Cu")
		(net 327)
	)
	(segment
		(start 130.646239 122.446188)
		(end 130.65 122.41281)
		(width 0.15)
		(layer "In2.Cu")
		(net 327)
	)
	(segment
		(start 128.589008 122.105986)
		(end 128.603572 122.111082)
		(width 0.15)
		(layer "In2.Cu")
		(net 327)
	)
	(segment
		(start 130.346239 121.453812)
		(end 130.35 121.48719)
		(width 0.15)
		(layer "In2.Cu")
		(net 327)
	)
	(segment
		(start 130.382725 122.506333)
		(end 130.406476 122.530084)
		(width 0.15)
		(layer "In2.Cu")
		(net 327)
	)
	(segment
		(start 131.235145 121.890083)
		(end 131.246239 121.858379)
		(width 0.15)
		(layer "In2.Cu")
		(net 327)
	)
	(segment
		(start 129.396427 122.111082)
		(end 129.410991 122.105986)
		(width 0.15)
		(layer "In2.Cu")
		(net 327)
	)
	(segment
		(start 129.735145 121.422108)
		(end 129.746239 121.453812)
		(width 0.15)
		(layer "In2.Cu")
		(net 327)
	)
	(segment
		(start 131.7 121.975)
		(end 131.6 121.975)
		(width 0.15)
		(layer "In2.Cu")
		(net 327)
	)
	(segment
		(start 132.05376 121.858379)
		(end 132.064854 121.890083)
		(width 0.15)
		(layer "In2.Cu")
		(net 327)
	)
	(segment
		(start 128.242177 122.059237)
		(end 128.243905 122.043905)
		(width 0.15)
		(layer "In2.Cu")
		(net 327)
	)
	(segment
		(start 132.55 121.825)
		(end 132.55376 121.858379)
		(width 0.15)
		(layer "In2.Cu")
		(net 327)
	)
	(segment
		(start 132.546239 121.453812)
		(end 132.55 121.48719)
		(width 0.15)
		(layer "In2.Cu")
		(net 327)
	)
	(segment
		(start 133.973 121.975)
		(end 134.424 121.524)
		(width 0.15)
		(layer "In2.Cu")
		(net 327)
	)
	(segment
		(start 130.166621 121.340951)
		(end 130.2 121.33719)
		(width 0.15)
		(layer "In2.Cu")
		(net 327)
	)
	(segment
		(start 129.033378 121.340951)
		(end 129.065082 121.352045)
		(width 0.15)
		(layer "In2.Cu")
		(net 327)
	)
	(segment
		(start 129.717274 121.393667)
		(end 129.735145 121.422108)
		(width 0.15)
		(layer "In2.Cu")
		(net 327)
	)
	(segment
		(start 130.043176 122.073801)
		(end 130.048272 122.059237)
		(width 0.15)
		(layer "In2.Cu")
		(net 327)
	)
	(segment
		(start 128.190332 122.111082)
		(end 128.204896 122.105986)
		(width 0.15)
		(layer "In2.Cu")
		(net 327)
	)
	(segment
		(start 128.334917 121.352045)
		(end 128.366621 121.340951)
		(width 0.15)
		(layer "In2.Cu")
		(net 327)
	)
	(segment
		(start 129.751727 122.059237)
		(end 129.756823 122.073801)
		(width 0.15)
		(layer "In2.Cu")
		(net 327)
	)
	(segment
		(start 130.364854 122.477892)
		(end 130.382725 122.506333)
		(width 0.15)
		(layer "In2.Cu")
		(net 327)
	)
	(segment
		(start 127.942177 122.028572)
		(end 127.945632 122.059237)
		(width 0.15)
		(layer "In2.Cu")
		(net 327)
	)
	(segment
		(start 132.564854 121.890083)
		(end 132.582725 121.918524)
		(width 0.15)
		(layer "In2.Cu")
		(net 327)
	)
	(segment
		(start 129.189008 122.105986)
		(end 129.203572 122.111082)
		(width 0.15)
		(layer "In2.Cu")
		(net 327)
	)
	(segment
		(start 128.603572 122.111082)
		(end 128.618905 122.11281)
		(width 0.15)
		(layer "In2.Cu")
		(net 327)
	)
	(segment
		(start 131.717274 121.918524)
		(end 131.735145 121.890083)
		(width 0.15)
		(layer "In2.Cu")
		(net 327)
	)
	(segment
		(start 130.8 121.33719)
		(end 130.833378 121.340951)
		(width 0.15)
		(layer "In2.Cu")
		(net 327)
	)
	(segment
		(start 132.55376 121.858379)
		(end 132.564854 121.890083)
		(width 0.15)
		(layer "In2.Cu")
		(net 327)
	)
	(segment
		(start 127.928872 122.000943)
		(end 127.937081 122.014008)
		(width 0.15)
		(layer "In2.Cu")
		(net 327)
	)
	(segment
		(start 127.969848 122.097777)
		(end 127.982913 122.105986)
		(width 0.15)
		(layer "In2.Cu")
		(net 327)
	)
	(segment
		(start 130.293523 121.369916)
		(end 130.317274 121.393667)
		(width 0.15)
		(layer "In2.Cu")
		(net 327)
	)
	(segment
		(start 130.35376 122.446188)
		(end 130.364854 122.477892)
		(width 0.15)
		(layer "In2.Cu")
		(net 327)
	)
	(segment
		(start 132.082725 121.918524)
		(end 132.106476 121.942275)
		(width 0.15)
		(layer "In2.Cu")
		(net 327)
	)
	(segment
		(start 132.1 121.975)
		(end 132.133378 121.97124)
		(width 0.15)
		(layer "In2.Cu")
		(net 327)
	)
	(segment
		(start 129.75 121.48719)
		(end 129.75 122.043905)
		(width 0.15)
		(layer "In2.Cu")
		(net 327)
	)
	(segment
		(start 130.265082 121.352045)
		(end 130.293523 121.369916)
		(width 0.15)
		(layer "In2.Cu")
		(net 327)
	)
	(segment
		(start 130.05 121.48719)
		(end 130.05376 121.453812)
		(width 0.15)
		(layer "In2.Cu")
		(net 327)
	)
	(segment
		(start 128.243905 121.975)
		(end 128.25 121.975)
		(width 0.15)
		(layer "In2.Cu")
		(net 327)
	)
	(segment
		(start 130.65376 121.453812)
		(end 130.664854 121.422108)
		(width 0.15)
		(layer "In2.Cu")
		(net 327)
	)
	(segment
		(start 128.848272 122.059237)
		(end 128.85 122.043905)
		(width 0.15)
		(layer "In2.Cu")
		(net 327)
	)
	(segment
		(start 132.165082 121.960146)
		(end 132.193523 121.942275)
		(width 0.15)
		(layer "In2.Cu")
		(net 327)
	)
	(segment
		(start 129.818905 122.11281)
		(end 129.981095 122.11281)
		(width 0.15)
		(layer "In2.Cu")
		(net 327)
	)
	(segment
		(start 127.917961 121.990032)
		(end 127.928872 122.000943)
		(width 0.15)
		(layer "In2.Cu")
		(net 327)
	)
	(segment
		(start 130.024056 122.097777)
		(end 130.034967 122.086866)
		(width 0.15)
		(layer "In2.Cu")
		(net 327)
	)
	(segment
		(start 132.017274 121.393667)
		(end 132.035145 121.422108)
		(width 0.15)
		(layer "In2.Cu")
		(net 327)
	)
	(segment
		(start 129.693523 121.369916)
		(end 129.717274 121.393667)
		(width 0.15)
		(layer "In2.Cu")
		(net 327)
	)
	(segment
		(start 131.564854 121.890083)
		(end 131.582725 121.918524)
		(width 0.15)
		(layer "In2.Cu")
		(net 327)
	)
	(segment
		(start 130.833378 121.340951)
		(end 130.865082 121.352045)
		(width 0.15)
		(layer "In2.Cu")
		(net 327)
	)
	(segment
		(start 131.933378 121.340951)
		(end 131.965082 121.352045)
		(width 0.15)
		(layer "In2.Cu")
		(net 327)
	)
	(segment
		(start 132.334917 121.352045)
		(end 132.366621 121.340951)
		(width 0.15)
		(layer "In2.Cu")
		(net 327)
	)
	(segment
		(start 131.75 121.825)
		(end 131.75 121.48719)
		(width 0.15)
		(layer "In2.Cu")
		(net 327)
	)
	(segment
		(start 131.9 121.33719)
		(end 131.933378 121.340951)
		(width 0.15)
		(layer "In2.Cu")
		(net 327)
	)
	(segment
		(start 127.958937 122.086866)
		(end 127.969848 122.097777)
		(width 0.15)
		(layer "In2.Cu")
		(net 327)
	)
	(segment
		(start 130.106476 121.369916)
		(end 130.134917 121.352045)
		(width 0.15)
		(layer "In2.Cu")
		(net 327)
	)
	(segment
		(start 127.945632 122.059237)
		(end 127.950728 122.073801)
		(width 0.15)
		(layer "In2.Cu")
		(net 327)
	)
	(segment
		(start 130.65 121.48719)
		(end 130.65376 121.453812)
		(width 0.15)
		(layer "In2.Cu")
		(net 327)
	)
	(segment
		(start 128.565032 122.086866)
		(end 128.575943 122.097777)
		(width 0.15)
		(layer "In2.Cu")
		(net 327)
	)
	(segment
		(start 131.334917 121.352045)
		(end 131.366621 121.340951)
		(width 0.15)
		(layer "In2.Cu")
		(net 327)
	)
	(segment
		(start 131.75376 121.453812)
		(end 131.764854 121.422108)
		(width 0.15)
		(layer "In2.Cu")
		(net 327)
	)
	(segment
		(start 129 121.33719)
		(end 129.033378 121.340951)
		(width 0.15)
		(layer "In2.Cu")
		(net 327)
	)
	(segment
		(start 128.175 122.11281)
		(end 128.190332 122.111082)
		(width 0.15)
		(layer "In2.Cu")
		(net 327)
	)
	(segment
		(start 128.535145 121.422108)
		(end 128.546239 121.453812)
		(width 0.15)
		(layer "In2.Cu")
		(net 327)
	)
	(segment
		(start 131.25376 121.453812)
		(end 131.264854 121.422108)
		(width 0.15)
		(layer "In2.Cu")
		(net 327)
	)
	(segment
		(start 131.282725 121.393667)
		(end 131.306476 121.369916)
		(width 0.15)
		(layer "In2.Cu")
		(net 327)
	)
	(segment
		(start 130.617274 122.506333)
		(end 130.635145 122.477892)
		(width 0.15)
		(layer "In2.Cu")
		(net 327)
	)
	(segment
		(start 130.682725 121.393667)
		(end 130.706476 121.369916)
		(width 0.15)
		(layer "In2.Cu")
		(net 327)
	)
	(segment
		(start 132.493523 121.369916)
		(end 132.517274 121.393667)
		(width 0.15)
		(layer "In2.Cu")
		(net 327)
	)
	(segment
		(start 131.582725 121.918524)
		(end 131.606476 121.942275)
		(width 0.15)
		(layer "In2.Cu")
		(net 327)
	)
	(segment
		(start 131.066621 121.97124)
		(end 131.1 121.975)
		(width 0.15)
		(layer "In2.Cu")
		(net 327)
	)
	(segment
		(start 128.366621 121.340951)
		(end 128.4 121.33719)
		(width 0.15)
		(layer "In2.Cu")
		(net 327)
	)
	(segment
		(start 132.433378 121.340951)
		(end 132.465082 121.352045)
		(width 0.15)
		(layer "In2.Cu")
		(net 327)
	)
	(segment
		(start 129.803572 122.111082)
		(end 129.818905 122.11281)
		(width 0.15)
		(layer "In2.Cu")
		(net 327)
	)
	(segment
		(start 130.064854 121.422108)
		(end 130.082725 121.393667)
		(width 0.15)
		(layer "In2.Cu")
		(net 327)
	)
	(segment
		(start 128.934917 121.352045)
		(end 128.966621 121.340951)
		(width 0.15)
		(layer "In2.Cu")
		(net 327)
	)
	(segment
		(start 128.85 122.043905)
		(end 128.85 121.48719)
		(width 0.15)
		(layer "In2.Cu")
		(net 327)
	)
	(segment
		(start 130.964854 121.890083)
		(end 130.982725 121.918524)
		(width 0.15)
		(layer "In2.Cu")
		(net 327)
	)
	(segment
		(start 129.534917 121.352045)
		(end 129.566621 121.340951)
		(width 0.15)
		(layer "In2.Cu")
		(net 327)
	)
	(segment
		(start 132.166621 121.97124)
		(end 132.2 121.975)
		(width 0.15)
		(layer "In2.Cu")
		(net 327)
	)
	(segment
		(start 132.4 121.33719)
		(end 132.433378 121.340951)
		(width 0.15)
		(layer "In2.Cu")
		(net 327)
	)
	(segment
		(start 128.906476 121.369916)
		(end 128.934917 121.352045)
		(width 0.15)
		(layer "In2.Cu")
		(net 327)
	)
	(segment
		(start 129.765032 122.086866)
		(end 129.775943 122.097777)
		(width 0.15)
		(layer "In2.Cu")
		(net 327)
	)
	(segment
		(start 129.464854 121.422108)
		(end 129.482725 121.393667)
		(width 0.15)
		(layer "In2.Cu")
		(net 327)
	)
	(segment
		(start 131.493523 121.369916)
		(end 131.517274 121.393667)
		(width 0.15)
		(layer "In2.Cu")
		(net 327)
	)
	(segment
		(start 128.85 121.48719)
		(end 128.85376 121.453812)
		(width 0.15)
		(layer "In2.Cu")
		(net 327)
	)
	(segment
		(start 106.275 113.675)
		(end 108.675 116.075)
		(width 0.15)
		(layer "In2.Cu")
		(net 327)
	)
	(segment
		(start 130.935145 121.422108)
		(end 130.946239 121.453812)
		(width 0.15)
		(layer "In2.Cu")
		(net 327)
	)
	(segment
		(start 128.618905 122.11281)
		(end 128.781095 122.11281)
		(width 0.15)
		(layer "In2.Cu")
		(net 327)
	)
	(segment
		(start 134.424 121.524)
		(end 134.774 121.524)
		(width 0.15)
		(layer "In2.Cu")
		(net 327)
	)
	(segment
		(start 128.55 121.48719)
		(end 128.55 122.043905)
		(width 0.15)
		(layer "In2.Cu")
		(net 327)
	)
	(segment
		(start 131.535145 121.422108)
		(end 131.546239 121.453812)
		(width 0.15)
		(layer "In2.Cu")
		(net 327)
	)
	(segment
		(start 132.25376 121.453812)
		(end 132.264854 121.422108)
		(width 0.15)
		(layer "In2.Cu")
		(net 327)
	)
	(segment
		(start 131.993523 121.369916)
		(end 132.017274 121.393667)
		(width 0.15)
		(layer "In2.Cu")
		(net 327)
	)
	(segment
		(start 127.950728 122.073801)
		(end 127.958937 122.086866)
		(width 0.15)
		(layer "In2.Cu")
		(net 327)
	)
	(segment
		(start 132.25 121.48719)
		(end 132.25376 121.453812)
		(width 0.15)
		(layer "In2.Cu")
		(net 327)
	)
	(segment
		(start 130.946239 121.453812)
		(end 130.95 121.48719)
		(width 0.15)
		(layer "In2.Cu")
		(net 327)
	)
	(segment
		(start 131.25 121.825)
		(end 131.25 121.48719)
		(width 0.15)
		(layer "In2.Cu")
		(net 327)
	)
	(segment
		(start 129.482725 121.393667)
		(end 129.506476 121.369916)
		(width 0.15)
		(layer "In2.Cu")
		(net 327)
	)
	(segment
		(start 130.434917 122.547955)
		(end 130.466621 122.559049)
		(width 0.15)
		(layer "In2.Cu")
		(net 327)
	)
	(segment
		(start 129.443176 122.073801)
		(end 129.448272 122.059237)
		(width 0.15)
		(layer "In2.Cu")
		(net 327)
	)
	(segment
		(start 128.433378 121.340951)
		(end 128.465082 121.352045)
		(width 0.15)
		(layer "In2.Cu")
		(net 327)
	)
	(segment
		(start 130.406476 122.530084)
		(end 130.434917 122.547955)
		(width 0.15)
		(layer "In2.Cu")
		(net 327)
	)
	(segment
		(start 127.997477 122.111082)
		(end 128.01281 122.11281)
		(width 0.15)
		(layer "In2.Cu")
		(net 327)
	)
	(segment
		(start 131.666621 121.97124)
		(end 131.7 121.975)
		(width 0.15)
		(layer "In2.Cu")
		(net 327)
	)
	(segment
		(start 131.165082 121.960146)
		(end 131.193523 121.942275)
		(width 0.15)
		(layer "In2.Cu")
		(net 327)
	)
	(segment
		(start 130.05 122.043905)
		(end 130.05 121.48719)
		(width 0.15)
		(layer "In2.Cu")
		(net 327)
	)
	(segment
		(start 129.410991 122.105986)
		(end 129.424056 122.097777)
		(width 0.15)
		(layer "In2.Cu")
		(net 327)
	)
	(segment
		(start 127.875 121.975)
		(end 127.890332 121.976727)
		(width 0.15)
		(layer "In2.Cu")
		(net 327)
	)
	(segment
		(start 132.582725 121.918524)
		(end 132.606476 121.942275)
		(width 0.15)
		(layer "In2.Cu")
		(net 327)
	)
	(segment
		(start 132.465082 121.352045)
		(end 132.493523 121.369916)
		(width 0.15)
		(layer "In2.Cu")
		(net 327)
	)
	(segment
		(start 130.533378 122.559049)
		(end 130.565082 122.547955)
		(width 0.15)
		(layer "In2.Cu")
		(net 327)
	)
	(segment
		(start 130.5 122.56281)
		(end 130.533378 122.559049)
		(width 0.15)
		(layer "In2.Cu")
		(net 327)
	)
	(segment
		(start 128.85376 121.453812)
		(end 128.864854 121.422108)
		(width 0.15)
		(layer "In2.Cu")
		(net 327)
	)
	(segment
		(start 132.106476 121.942275)
		(end 132.134917 121.960146)
		(width 0.15)
		(layer "In2.Cu")
		(net 327)
	)
	(segment
		(start 132.25 121.825)
		(end 132.25 121.48719)
		(width 0.15)
		(layer "In2.Cu")
		(net 327)
	)
	(segment
		(start 130.95 121.48719)
		(end 130.95 121.825)
		(width 0.15)
		(layer "In2.Cu")
		(net 327)
	)
	(segment
		(start 130.706476 121.369916)
		(end 130.734917 121.352045)
		(width 0.15)
		(layer "In2.Cu")
		(net 327)
	)
	(segment
		(start 132.517274 121.393667)
		(end 132.535145 121.422108)
		(width 0.15)
		(layer "In2.Cu")
		(net 327)
	)
	(segment
		(start 132.246239 121.858379)
		(end 132.25 121.825)
		(width 0.15)
		(layer "In2.Cu")
		(net 327)
	)
	(segment
		(start 131.634917 121.960146)
		(end 131.666621 121.97124)
		(width 0.15)
		(layer "In2.Cu")
		(net 327)
	)
	(segment
		(start 128.25 121.975)
		(end 128.25 121.48719)
		(width 0.15)
		(layer "In2.Cu")
		(net 327)
	)
	(segment
		(start 130.65 122.41281)
		(end 130.65 121.48719)
		(width 0.15)
		(layer "In2.Cu")
		(net 327)
	)
	(segment
		(start 130.95376 121.858379)
		(end 130.964854 121.890083)
		(width 0.15)
		(layer "In2.Cu")
		(net 327)
	)
	(segment
		(start 132.535145 121.422108)
		(end 132.546239 121.453812)
		(width 0.15)
		(layer "In2.Cu")
		(net 327)
	)
	(segment
		(start 129.065082 121.352045)
		(end 129.093523 121.369916)
		(width 0.15)
		(layer "In2.Cu")
		(net 327)
	)
	(segment
		(start 130.917274 121.393667)
		(end 130.935145 121.422108)
		(width 0.15)
		(layer "In2.Cu")
		(net 327)
	)
	(segment
		(start 128.551727 122.059237)
		(end 128.556823 122.073801)
		(width 0.15)
		(layer "In2.Cu")
		(net 327)
	)
	(segment
		(start 128.810991 122.105986)
		(end 128.824056 122.097777)
		(width 0.15)
		(layer "In2.Cu")
		(net 327)
	)
	(segment
		(start 130.35 122.41281)
		(end 130.35376 122.446188)
		(width 0.15)
		(layer "In2.Cu")
		(net 327)
	)
	(segment
		(start 131.606476 121.942275)
		(end 131.634917 121.960146)
		(width 0.15)
		(layer "In2.Cu")
		(net 327)
	)
	(segment
		(start 129.633378 121.340951)
		(end 129.665082 121.352045)
		(width 0.15)
		(layer "In2.Cu")
		(net 327)
	)
	(segment
		(start 129.566621 121.340951)
		(end 129.6 121.33719)
		(width 0.15)
		(layer "In2.Cu")
		(net 327)
	)
	(segment
		(start 128.237081 122.073801)
		(end 128.242177 122.059237)
		(width 0.15)
		(layer "In2.Cu")
		(net 327)
	)
	(segment
		(start 132.7 121.975)
		(end 133.973 121.975)
		(width 0.15)
		(layer "In2.Cu")
		(net 327)
	)
	(segment
		(start 128.556823 122.073801)
		(end 128.565032 122.086866)
		(width 0.15)
		(layer "In2.Cu")
		(net 327)
	)
	(segment
		(start 131.546239 121.453812)
		(end 131.55 121.48719)
		(width 0.15)
		(layer "In2.Cu")
		(net 327)
	)
	(segment
		(start 130.95 121.825)
		(end 130.95376 121.858379)
		(width 0.15)
		(layer "In2.Cu")
		(net 327)
	)
	(segment
		(start 108.675 116.075)
		(end 115.175 116.075)
		(width 0.15)
		(layer "In2.Cu")
		(net 327)
	)
	(segment
		(start 132.133378 121.97124)
		(end 132.165082 121.960146)
		(width 0.15)
		(layer "In2.Cu")
		(net 327)
	)
	(segment
		(start 129.756823 122.073801)
		(end 129.765032 122.086866)
		(width 0.15)
		(layer "In2.Cu")
		(net 327)
	)
	(segment
		(start 131.034917 121.960146)
		(end 131.066621 121.97124)
		(width 0.15)
		(layer "In2.Cu")
		(net 327)
	)
	(segment
		(start 129.996427 122.111082)
		(end 130.010991 122.105986)
		(width 0.15)
		(layer "In2.Cu")
		(net 327)
	)
	(segment
		(start 129.45 122.043905)
		(end 129.45 121.48719)
		(width 0.15)
		(layer "In2.Cu")
		(net 327)
	)
	(segment
		(start 130.865082 121.352045)
		(end 130.893523 121.369916)
		(width 0.15)
		(layer "In2.Cu")
		(net 327)
	)
	(segment
		(start 132.634917 121.960146)
		(end 132.666621 121.97124)
		(width 0.15)
		(layer "In2.Cu")
		(net 327)
	)
	(segment
		(start 132.035145 121.422108)
		(end 132.046239 121.453812)
		(width 0.15)
		(layer "In2.Cu")
		(net 327)
	)
	(segment
		(start 131.735145 121.890083)
		(end 131.746239 121.858379)
		(width 0.15)
		(layer "In2.Cu")
		(net 327)
	)
	(segment
		(start 131.306476 121.369916)
		(end 131.334917 121.352045)
		(width 0.15)
		(layer "In2.Cu")
		(net 327)
	)
	(segment
		(start 132.217274 121.918524)
		(end 132.235145 121.890083)
		(width 0.15)
		(layer "In2.Cu")
		(net 327)
	)
	(segment
		(start 131.866621 121.340951)
		(end 131.9 121.33719)
		(width 0.15)
		(layer "In2.Cu")
		(net 327)
	)
	(segment
		(start 130.233378 121.340951)
		(end 130.265082 121.352045)
		(width 0.15)
		(layer "In2.Cu")
		(net 327)
	)
	(segment
		(start 132.064854 121.890083)
		(end 132.082725 121.918524)
		(width 0.15)
		(layer "In2.Cu")
		(net 327)
	)
	(segment
		(start 130.134917 121.352045)
		(end 130.166621 121.340951)
		(width 0.15)
		(layer "In2.Cu")
		(net 327)
	)
	(segment
		(start 128.796427 122.111082)
		(end 128.810991 122.105986)
		(width 0.15)
		(layer "In2.Cu")
		(net 327)
	)
	(segment
		(start 128.575943 122.097777)
		(end 128.589008 122.105986)
		(width 0.15)
		(layer "In2.Cu")
		(net 327)
	)
	(segment
		(start 129.424056 122.097777)
		(end 129.434967 122.086866)
		(width 0.15)
		(layer "In2.Cu")
		(net 327)
	)
	(segment
		(start 129.75 122.043905)
		(end 129.751727 122.059237)
		(width 0.15)
		(layer "In2.Cu")
		(net 327)
	)
	(segment
		(start 129.175943 122.097777)
		(end 129.189008 122.105986)
		(width 0.15)
		(layer "In2.Cu")
		(net 327)
	)
	(segment
		(start 130.766621 121.340951)
		(end 130.8 121.33719)
		(width 0.15)
		(layer "In2.Cu")
		(net 327)
	)
	(segment
		(start 131.633378 121.97124)
		(end 131.665082 121.960146)
		(width 0.15)
		(layer "In2.Cu")
		(net 327)
	)
	(segment
		(start 128.25376 121.453812)
		(end 128.264854 121.422108)
		(width 0.15)
		(layer "In2.Cu")
		(net 327)
	)
	(segment
		(start 130.034967 122.086866)
		(end 130.043176 122.073801)
		(width 0.15)
		(layer "In2.Cu")
		(net 327)
	)
	(segment
		(start 130.635145 122.477892)
		(end 130.646239 122.446188)
		(width 0.15)
		(layer "In2.Cu")
		(net 327)
	)
	(segment
		(start 128.546239 121.453812)
		(end 128.55 121.48719)
		(width 0.15)
		(layer "In2.Cu")
		(net 327)
	)
	(segment
		(start 128.204896 122.105986)
		(end 128.217961 122.097777)
		(width 0.15)
		(layer "In2.Cu")
		(net 327)
	)
	(segment
		(start 128.493523 121.369916)
		(end 128.517274 121.393667)
		(width 0.15)
		(layer "In2.Cu")
		(net 327)
	)
	(segment
		(start 131.366621 121.340951)
		(end 131.4 121.33719)
		(width 0.15)
		(layer "In2.Cu")
		(net 327)
	)
	(segment
		(start 129.506476 121.369916)
		(end 129.534917 121.352045)
		(width 0.15)
		(layer "In2.Cu")
		(net 327)
	)
	(segment
		(start 131.55 121.48719)
		(end 131.55 121.825)
		(width 0.15)
		(layer "In2.Cu")
		(net 327)
	)
	(segment
		(start 130.082725 121.393667)
		(end 130.106476 121.369916)
		(width 0.15)
		(layer "In2.Cu")
		(net 327)
	)
	(segment
		(start 132.134917 121.960146)
		(end 132.166621 121.97124)
		(width 0.15)
		(layer "In2.Cu")
		(net 327)
	)
	(segment
		(start 132.193523 121.942275)
		(end 132.217274 121.918524)
		(width 0.15)
		(layer "In2.Cu")
		(net 327)
	)
	(segment
		(start 128.243905 122.043905)
		(end 128.243905 121.975)
		(width 0.15)
		(layer "In2.Cu")
		(net 327)
	)
	(segment
		(start 128.55 122.043905)
		(end 128.551727 122.059237)
		(width 0.15)
		(layer "In2.Cu")
		(net 327)
	)
	(segment
		(start 132.666621 121.97124)
		(end 132.7 121.975)
		(width 0.15)
		(layer "In2.Cu")
		(net 327)
	)
	(segment
		(start 130.048272 122.059237)
		(end 130.05 122.043905)
		(width 0.15)
		(layer "In2.Cu")
		(net 327)
	)
	(segment
		(start 128.282725 121.393667)
		(end 128.306476 121.369916)
		(width 0.15)
		(layer "In2.Cu")
		(net 327)
	)
	(segment
		(start 131.1 121.975)
		(end 131.133378 121.97124)
		(width 0.15)
		(layer "In2.Cu")
		(net 327)
	)
	(segment
		(start 131.806476 121.369916)
		(end 131.834917 121.352045)
		(width 0.15)
		(layer "In2.Cu")
		(net 327)
	)
	(segment
		(start 131.665082 121.960146)
		(end 131.693523 121.942275)
		(width 0.15)
		(layer "In2.Cu")
		(net 327)
	)
	(segment
		(start 135.274 124.004)
		(end 134.784 123.514)
		(width 0.15)
		(layer "F.Cu")
		(net 328)
	)
	(segment
		(start 104.775 114.175)
		(end 105.275 114.675)
		(width 0.15)
		(layer "F.Cu")
		(net 328)
	)
	(via
		(at 134.784 123.514)
		(size 0.5)
		(drill 0.2)
		(layers "F.Cu" "B.Cu")
		(net 328)
	)
	(via blind
		(at 105.275 114.675)
		(size 0.5)
		(drill 0.2)
		(layers "F.Cu" "In2.Cu")
		(net 328)
	)
	(segment
		(start 134.759 123.539)
		(end 134.784 123.514)
		(width 0.15)
		(layer "B.Cu")
		(net 328)
	)
	(segment
		(start 134.759 124.214)
		(end 134.759 123.539)
		(width 0.15)
		(layer "B.Cu")
		(net 328)
	)
	(segment
		(start 127.418678 123.757176)
		(end 127.442395 123.780893)
		(width 0.15)
		(layer "In2.Cu")
		(net 328)
	)
	(segment
		(start 127.170917 122.679283)
		(end 127.202621 122.668189)
		(width 0.15)
		(layer "In2.Cu")
		(net 328)
	)
	(segment
		(start 127.086 122.814428)
		(end 127.08976 122.78105)
		(width 0.15)
		(layer "In2.Cu")
		(net 328)
	)
	(segment
		(start 129.753274 122.720905)
		(end 129.771145 122.749346)
		(width 0.15)
		(layer "In2.Cu")
		(net 328)
	)
	(segment
		(start 127.08203 123.697116)
		(end 127.085786 123.663786)
		(width 0.15)
		(layer "In2.Cu")
		(net 328)
	)
	(segment
		(start 127.386 122.814428)
		(end 127.386 123.663786)
		(width 0.15)
		(layer "In2.Cu")
		(net 328)
	)
	(segment
		(start 129.771145 122.749346)
		(end 129.782239 122.78105)
		(width 0.15)
		(layer "In2.Cu")
		(net 328)
	)
	(segment
		(start 129.842476 123.481275)
		(end 129.870917 123.499146)
		(width 0.15)
		(layer "In2.Cu")
		(net 328)
	)
	(segment
		(start 128.529523 122.697154)
		(end 128.553274 122.720905)
		(width 0.15)
		(layer "In2.Cu")
		(net 328)
	)
	(segment
		(start 129.729523 122.697154)
		(end 129.753274 122.720905)
		(width 0.15)
		(layer "In2.Cu")
		(net 328)
	)
	(segment
		(start 128.135786 123.813572)
		(end 128.136214 123.813572)
		(width 0.15)
		(layer "In2.Cu")
		(net 328)
	)
	(segment
		(start 129.036 122.664428)
		(end 129.069378 122.668189)
		(width 0.15)
		(layer "In2.Cu")
		(net 328)
	)
	(segment
		(start 127.329523 122.697154)
		(end 127.353274 122.720905)
		(width 0.15)
		(layer "In2.Cu")
		(net 328)
	)
	(segment
		(start 126.935572 123.813572)
		(end 126.936 123.813572)
		(width 0.15)
		(layer "In2.Cu")
		(net 328)
	)
	(segment
		(start 128.882244 123.697116)
		(end 128.886 123.663786)
		(width 0.15)
		(layer "In2.Cu")
		(net 328)
	)
	(segment
		(start 129.200833 123.728775)
		(end 129.218678 123.757176)
		(width 0.15)
		(layer "In2.Cu")
		(net 328)
	)
	(segment
		(start 129.270796 123.798738)
		(end 129.302455 123.809816)
		(width 0.15)
		(layer "In2.Cu")
		(net 328)
	)
	(segment
		(start 127.08976 122.78105)
		(end 127.100854 122.749346)
		(width 0.15)
		(layer "In2.Cu")
		(net 328)
	)
	(segment
		(start 127.353274 122.720905)
		(end 127.371145 122.749346)
		(width 0.15)
		(layer "In2.Cu")
		(net 328)
	)
	(segment
		(start 128.136214 123.813572)
		(end 128.169544 123.809816)
		(width 0.15)
		(layer "In2.Cu")
		(net 328)
	)
	(segment
		(start 129.902621 123.51024)
		(end 129.936 123.514)
		(width 0.15)
		(layer "In2.Cu")
		(net 328)
	)
	(segment
		(start 128.000833 123.728775)
		(end 128.018678 123.757176)
		(width 0.15)
		(layer "In2.Cu")
		(net 328)
	)
	(segment
		(start 127.142476 122.697154)
		(end 127.170917 122.679283)
		(width 0.15)
		(layer "In2.Cu")
		(net 328)
	)
	(segment
		(start 128.229604 123.780893)
		(end 128.253321 123.757176)
		(width 0.15)
		(layer "In2.Cu")
		(net 328)
	)
	(segment
		(start 129.570917 122.679283)
		(end 129.602621 122.668189)
		(width 0.15)
		(layer "In2.Cu")
		(net 328)
	)
	(segment
		(start 128.501082 122.679283)
		(end 128.529523 122.697154)
		(width 0.15)
		(layer "In2.Cu")
		(net 328)
	)
	(segment
		(start 128.28976 122.78105)
		(end 128.300854 122.749346)
		(width 0.15)
		(layer "In2.Cu")
		(net 328)
	)
	(segment
		(start 105.275 114.675)
		(end 105.775 115.175)
		(width 0.15)
		(layer "In2.Cu")
		(net 328)
	)
	(segment
		(start 127.301082 122.679283)
		(end 127.329523 122.697154)
		(width 0.15)
		(layer "In2.Cu")
		(net 328)
	)
	(segment
		(start 129.186 123.663786)
		(end 129.189755 123.697116)
		(width 0.15)
		(layer "In2.Cu")
		(net 328)
	)
	(segment
		(start 127.700854 122.749346)
		(end 127.718725 122.720905)
		(width 0.15)
		(layer "In2.Cu")
		(net 328)
	)
	(segment
		(start 128.436 122.664428)
		(end 128.469378 122.668189)
		(width 0.15)
		(layer "In2.Cu")
		(net 328)
	)
	(segment
		(start 128.736214 123.813572)
		(end 128.769544 123.809816)
		(width 0.15)
		(layer "In2.Cu")
		(net 328)
	)
	(segment
		(start 128.88976 122.78105)
		(end 128.900854 122.749346)
		(width 0.15)
		(layer "In2.Cu")
		(net 328)
	)
	(segment
		(start 129.401203 123.798738)
		(end 129.429604 123.780893)
		(width 0.15)
		(layer "In2.Cu")
		(net 328)
	)
	(segment
		(start 128.642395 123.780893)
		(end 128.670796 123.798738)
		(width 0.15)
		(layer "In2.Cu")
		(net 328)
	)
	(segment
		(start 128.018678 123.757176)
		(end 128.042395 123.780893)
		(width 0.15)
		(layer "In2.Cu")
		(net 328)
	)
	(segment
		(start 126.770952 123.598796)
		(end 126.78203 123.630455)
		(width 0.15)
		(layer "In2.Cu")
		(net 328)
	)
	(segment
		(start 127.535786 123.813572)
		(end 127.536214 123.813572)
		(width 0.15)
		(layer "In2.Cu")
		(net 328)
	)
	(segment
		(start 129.002621 122.668189)
		(end 129.036 122.664428)
		(width 0.15)
		(layer "In2.Cu")
		(net 328)
	)
	(segment
		(start 126.800619 123.728775)
		(end 126.818464 123.757176)
		(width 0.15)
		(layer "In2.Cu")
		(net 328)
	)
	(segment
		(start 128.702455 123.809816)
		(end 128.735786 123.813572)
		(width 0.15)
		(layer "In2.Cu")
		(net 328)
	)
	(segment
		(start 129.518725 122.720905)
		(end 129.542476 122.697154)
		(width 0.15)
		(layer "In2.Cu")
		(net 328)
	)
	(segment
		(start 105.775 115.175)
		(end 105.775 115.275)
		(width 0.15)
		(layer "In2.Cu")
		(net 328)
	)
	(segment
		(start 127.802621 122.668189)
		(end 127.836 122.664428)
		(width 0.15)
		(layer "In2.Cu")
		(net 328)
	)
	(segment
		(start 128.886 123.663786)
		(end 128.886 122.814428)
		(width 0.15)
		(layer "In2.Cu")
		(net 328)
	)
	(segment
		(start 129.669378 122.668189)
		(end 129.701082 122.679283)
		(width 0.15)
		(layer "In2.Cu")
		(net 328)
	)
	(segment
		(start 127.070952 123.728775)
		(end 127.08203 123.697116)
		(width 0.15)
		(layer "In2.Cu")
		(net 328)
	)
	(segment
		(start 127.085786 123.663786)
		(end 127.085786 123.514)
		(width 0.15)
		(layer "In2.Cu")
		(net 328)
	)
	(segment
		(start 127.986 123.663786)
		(end 127.989755 123.697116)
		(width 0.15)
		(layer "In2.Cu")
		(net 328)
	)
	(segment
		(start 128.286 123.663786)
		(end 128.286 122.814428)
		(width 0.15)
		(layer "In2.Cu")
		(net 328)
	)
	(segment
		(start 129.782239 122.78105)
		(end 129.786 122.814428)
		(width 0.15)
		(layer "In2.Cu")
		(net 328)
	)
	(segment
		(start 128.571145 122.749346)
		(end 128.582239 122.78105)
		(width 0.15)
		(layer "In2.Cu")
		(net 328)
	)
	(segment
		(start 127.986 122.814428)
		(end 127.986 123.663786)
		(width 0.15)
		(layer "In2.Cu")
		(net 328)
	)
	(segment
		(start 121.023556 122.775)
		(end 125.275 122.775)
		(width 0.15)
		(layer "In2.Cu")
		(net 328)
	)
	(segment
		(start 128.469378 122.668189)
		(end 128.501082 122.679283)
		(width 0.15)
		(layer "In2.Cu")
		(net 328)
	)
	(segment
		(start 128.886 122.814428)
		(end 128.88976 122.78105)
		(width 0.15)
		(layer "In2.Cu")
		(net 328)
	)
	(segment
		(start 129.186 122.814428)
		(end 129.186 123.663786)
		(width 0.15)
		(layer "In2.Cu")
		(net 328)
	)
	(segment
		(start 126.96933 123.809816)
		(end 127.000989 123.798738)
		(width 0.15)
		(layer "In2.Cu")
		(net 328)
	)
	(segment
		(start 128.282244 123.697116)
		(end 128.286 123.663786)
		(width 0.15)
		(layer "In2.Cu")
		(net 328)
	)
	(segment
		(start 129.800854 123.429083)
		(end 129.818725 123.457524)
		(width 0.15)
		(layer "In2.Cu")
		(net 328)
	)
	(segment
		(start 127.100854 122.749346)
		(end 127.118725 122.720905)
		(width 0.15)
		(layer "In2.Cu")
		(net 328)
	)
	(segment
		(start 127.382239 122.78105)
		(end 127.386 122.814428)
		(width 0.15)
		(layer "In2.Cu")
		(net 328)
	)
	(segment
		(start 126.818464 123.757176)
		(end 126.842181 123.780893)
		(width 0.15)
		(layer "In2.Cu")
		(net 328)
	)
	(segment
		(start 127.118725 122.720905)
		(end 127.142476 122.697154)
		(width 0.15)
		(layer "In2.Cu")
		(net 328)
	)
	(segment
		(start 129.171145 122.749346)
		(end 129.182239 122.78105)
		(width 0.15)
		(layer "In2.Cu")
		(net 328)
	)
	(segment
		(start 127.053107 123.757176)
		(end 127.070952 123.728775)
		(width 0.15)
		(layer "In2.Cu")
		(net 328)
	)
	(segment
		(start 127.68976 122.78105)
		(end 127.700854 122.749346)
		(width 0.15)
		(layer "In2.Cu")
		(net 328)
	)
	(segment
		(start 129.500854 122.749346)
		(end 129.518725 122.720905)
		(width 0.15)
		(layer "In2.Cu")
		(net 328)
	)
	(segment
		(start 128.169544 123.809816)
		(end 128.201203 123.798738)
		(width 0.15)
		(layer "In2.Cu")
		(net 328)
	)
	(segment
		(start 129.486 122.814428)
		(end 129.48976 122.78105)
		(width 0.15)
		(layer "In2.Cu")
		(net 328)
	)
	(segment
		(start 127.569544 123.809816)
		(end 127.601203 123.798738)
		(width 0.15)
		(layer "In2.Cu")
		(net 328)
	)
	(segment
		(start 115.023526 116.77497)
		(end 121.023556 122.775)
		(width 0.15)
		(layer "In2.Cu")
		(net 328)
	)
	(segment
		(start 128.586 122.814428)
		(end 128.586 123.663786)
		(width 0.15)
		(layer "In2.Cu")
		(net 328)
	)
	(segment
		(start 127.269378 122.668189)
		(end 127.301082 122.679283)
		(width 0.15)
		(layer "In2.Cu")
		(net 328)
	)
	(segment
		(start 127.629604 123.780893)
		(end 127.653321 123.757176)
		(width 0.15)
		(layer "In2.Cu")
		(net 328)
	)
	(segment
		(start 127.470796 123.798738)
		(end 127.502455 123.809816)
		(width 0.15)
		(layer "In2.Cu")
		(net 328)
	)
	(segment
		(start 127.901082 122.679283)
		(end 127.929523 122.697154)
		(width 0.15)
		(layer "In2.Cu")
		(net 328)
	)
	(segment
		(start 128.582239 122.78105)
		(end 128.586 122.814428)
		(width 0.15)
		(layer "In2.Cu")
		(net 328)
	)
	(segment
		(start 126.842181 123.780893)
		(end 126.870582 123.798738)
		(width 0.15)
		(layer "In2.Cu")
		(net 328)
	)
	(segment
		(start 128.918725 122.720905)
		(end 128.942476 122.697154)
		(width 0.15)
		(layer "In2.Cu")
		(net 328)
	)
	(segment
		(start 129.369544 123.809816)
		(end 129.401203 123.798738)
		(width 0.15)
		(layer "In2.Cu")
		(net 328)
	)
	(segment
		(start 128.801203 123.798738)
		(end 128.829604 123.780893)
		(width 0.15)
		(layer "In2.Cu")
		(net 328)
	)
	(segment
		(start 127.386 123.663786)
		(end 127.389755 123.697116)
		(width 0.15)
		(layer "In2.Cu")
		(net 328)
	)
	(segment
		(start 129.429604 123.780893)
		(end 129.453321 123.757176)
		(width 0.15)
		(layer "In2.Cu")
		(net 328)
	)
	(segment
		(start 127.202621 122.668189)
		(end 127.236 122.664428)
		(width 0.15)
		(layer "In2.Cu")
		(net 328)
	)
	(segment
		(start 129.101082 122.679283)
		(end 129.129523 122.697154)
		(width 0.15)
		(layer "In2.Cu")
		(net 328)
	)
	(segment
		(start 125.275 122.775)
		(end 126.014 123.514)
		(width 0.15)
		(layer "In2.Cu")
		(net 328)
	)
	(segment
		(start 128.553274 122.720905)
		(end 128.571145 122.749346)
		(width 0.15)
		(layer "In2.Cu")
		(net 328)
	)
	(segment
		(start 127.086 123.514)
		(end 127.086 122.814428)
		(width 0.15)
		(layer "In2.Cu")
		(net 328)
	)
	(segment
		(start 129.78976 123.397379)
		(end 129.800854 123.429083)
		(width 0.15)
		(layer "In2.Cu")
		(net 328)
	)
	(segment
		(start 128.618678 123.757176)
		(end 128.642395 123.780893)
		(width 0.15)
		(layer "In2.Cu")
		(net 328)
	)
	(segment
		(start 129.242395 123.780893)
		(end 129.270796 123.798738)
		(width 0.15)
		(layer "In2.Cu")
		(net 328)
	)
	(segment
		(start 129.936 123.514)
		(end 134.784 123.514)
		(width 0.15)
		(layer "In2.Cu")
		(net 328)
	)
	(segment
		(start 127.836 122.664428)
		(end 127.869378 122.668189)
		(width 0.15)
		(layer "In2.Cu")
		(net 328)
	)
	(segment
		(start 129.48976 122.78105)
		(end 129.500854 122.749346)
		(width 0.15)
		(layer "In2.Cu")
		(net 328)
	)
	(segment
		(start 128.900854 122.749346)
		(end 128.918725 122.720905)
		(width 0.15)
		(layer "In2.Cu")
		(net 328)
	)
	(segment
		(start 107.27497 116.77497)
		(end 115.023526 116.77497)
		(width 0.15)
		(layer "In2.Cu")
		(net 328)
	)
	(segment
		(start 127.718725 122.720905)
		(end 127.742476 122.697154)
		(width 0.15)
		(layer "In2.Cu")
		(net 328)
	)
	(segment
		(start 129.636 122.664428)
		(end 129.669378 122.668189)
		(width 0.15)
		(layer "In2.Cu")
		(net 328)
	)
	(segment
		(start 127.971145 122.749346)
		(end 127.982239 122.78105)
		(width 0.15)
		(layer "In2.Cu")
		(net 328)
	)
	(segment
		(start 129.302455 123.809816)
		(end 129.335786 123.813572)
		(width 0.15)
		(layer "In2.Cu")
		(net 328)
	)
	(segment
		(start 128.342476 122.697154)
		(end 128.370917 122.679283)
		(width 0.15)
		(layer "In2.Cu")
		(net 328)
	)
	(segment
		(start 128.735786 123.813572)
		(end 128.736214 123.813572)
		(width 0.15)
		(layer "In2.Cu")
		(net 328)
	)
	(segment
		(start 127.671166 123.728775)
		(end 127.682244 123.697116)
		(width 0.15)
		(layer "In2.Cu")
		(net 328)
	)
	(segment
		(start 127.869378 122.668189)
		(end 127.901082 122.679283)
		(width 0.15)
		(layer "In2.Cu")
		(net 328)
	)
	(segment
		(start 127.601203 123.798738)
		(end 127.629604 123.780893)
		(width 0.15)
		(layer "In2.Cu")
		(net 328)
	)
	(segment
		(start 127.982239 122.78105)
		(end 127.986 122.814428)
		(width 0.15)
		(layer "In2.Cu")
		(net 328)
	)
	(segment
		(start 127.400833 123.728775)
		(end 127.418678 123.757176)
		(width 0.15)
		(layer "In2.Cu")
		(net 328)
	)
	(segment
		(start 127.953274 122.720905)
		(end 127.971145 122.749346)
		(width 0.15)
		(layer "In2.Cu")
		(net 328)
	)
	(segment
		(start 129.486 123.663786)
		(end 129.486 122.814428)
		(width 0.15)
		(layer "In2.Cu")
		(net 328)
	)
	(segment
		(start 127.686 123.663786)
		(end 127.686 122.814428)
		(width 0.15)
		(layer "In2.Cu")
		(net 328)
	)
	(segment
		(start 128.286 122.814428)
		(end 128.28976 122.78105)
		(width 0.15)
		(layer "In2.Cu")
		(net 328)
	)
	(segment
		(start 129.542476 122.697154)
		(end 129.570917 122.679283)
		(width 0.15)
		(layer "In2.Cu")
		(net 328)
	)
	(segment
		(start 129.786 123.364)
		(end 129.78976 123.397379)
		(width 0.15)
		(layer "In2.Cu")
		(net 328)
	)
	(segment
		(start 127.929523 122.697154)
		(end 127.953274 122.720905)
		(width 0.15)
		(layer "In2.Cu")
		(net 328)
	)
	(segment
		(start 127.000989 123.798738)
		(end 127.02939 123.780893)
		(width 0.15)
		(layer "In2.Cu")
		(net 328)
	)
	(segment
		(start 129.482244 123.697116)
		(end 129.486 123.663786)
		(width 0.15)
		(layer "In2.Cu")
		(net 328)
	)
	(segment
		(start 129.218678 123.757176)
		(end 129.242395 123.780893)
		(width 0.15)
		(layer "In2.Cu")
		(net 328)
	)
	(segment
		(start 128.853321 123.757176)
		(end 128.871166 123.728775)
		(width 0.15)
		(layer "In2.Cu")
		(net 328)
	)
	(segment
		(start 126.753107 123.570395)
		(end 126.770952 123.598796)
		(width 0.15)
		(layer "In2.Cu")
		(net 328)
	)
	(segment
		(start 126.902241 123.809816)
		(end 126.935572 123.813572)
		(width 0.15)
		(layer "In2.Cu")
		(net 328)
	)
	(segment
		(start 129.335786 123.813572)
		(end 129.336214 123.813572)
		(width 0.15)
		(layer "In2.Cu")
		(net 328)
	)
	(segment
		(start 129.153274 122.720905)
		(end 129.171145 122.749346)
		(width 0.15)
		(layer "In2.Cu")
		(net 328)
	)
	(segment
		(start 128.253321 123.757176)
		(end 128.271166 123.728775)
		(width 0.15)
		(layer "In2.Cu")
		(net 328)
	)
	(segment
		(start 127.389755 123.697116)
		(end 127.400833 123.728775)
		(width 0.15)
		(layer "In2.Cu")
		(net 328)
	)
	(segment
		(start 129.069378 122.668189)
		(end 129.101082 122.679283)
		(width 0.15)
		(layer "In2.Cu")
		(net 328)
	)
	(segment
		(start 129.189755 123.697116)
		(end 129.200833 123.728775)
		(width 0.15)
		(layer "In2.Cu")
		(net 328)
	)
	(segment
		(start 129.336214 123.813572)
		(end 129.369544 123.809816)
		(width 0.15)
		(layer "In2.Cu")
		(net 328)
	)
	(segment
		(start 127.085786 123.514)
		(end 127.086 123.514)
		(width 0.15)
		(layer "In2.Cu")
		(net 328)
	)
	(segment
		(start 127.682244 123.697116)
		(end 127.686 123.663786)
		(width 0.15)
		(layer "In2.Cu")
		(net 328)
	)
	(segment
		(start 126.936 123.813572)
		(end 126.96933 123.809816)
		(width 0.15)
		(layer "In2.Cu")
		(net 328)
	)
	(segment
		(start 127.371145 122.749346)
		(end 127.382239 122.78105)
		(width 0.15)
		(layer "In2.Cu")
		(net 328)
	)
	(segment
		(start 127.536214 123.813572)
		(end 127.569544 123.809816)
		(width 0.15)
		(layer "In2.Cu")
		(net 328)
	)
	(segment
		(start 129.701082 122.679283)
		(end 129.729523 122.697154)
		(width 0.15)
		(layer "In2.Cu")
		(net 328)
	)
	(segment
		(start 129.786 122.814428)
		(end 129.786 123.364)
		(width 0.15)
		(layer "In2.Cu")
		(net 328)
	)
	(segment
		(start 128.586 123.663786)
		(end 128.589755 123.697116)
		(width 0.15)
		(layer "In2.Cu")
		(net 328)
	)
	(segment
		(start 127.742476 122.697154)
		(end 127.770917 122.679283)
		(width 0.15)
		(layer "In2.Cu")
		(net 328)
	)
	(segment
		(start 126.700989 123.528833)
		(end 126.72939 123.546678)
		(width 0.15)
		(layer "In2.Cu")
		(net 328)
	)
	(segment
		(start 128.402621 122.668189)
		(end 128.436 122.664428)
		(width 0.15)
		(layer "In2.Cu")
		(net 328)
	)
	(segment
		(start 126.014 123.514)
		(end 126.636 123.514)
		(width 0.15)
		(layer "In2.Cu")
		(net 328)
	)
	(segment
		(start 129.182239 122.78105)
		(end 129.186 122.814428)
		(width 0.15)
		(layer "In2.Cu")
		(net 328)
	)
	(segment
		(start 128.769544 123.809816)
		(end 128.801203 123.798738)
		(width 0.15)
		(layer "In2.Cu")
		(net 328)
	)
	(segment
		(start 128.871166 123.728775)
		(end 128.882244 123.697116)
		(width 0.15)
		(layer "In2.Cu")
		(net 328)
	)
	(segment
		(start 126.870582 123.798738)
		(end 126.902241 123.809816)
		(width 0.15)
		(layer "In2.Cu")
		(net 328)
	)
	(segment
		(start 128.370917 122.679283)
		(end 128.402621 122.668189)
		(width 0.15)
		(layer "In2.Cu")
		(net 328)
	)
	(segment
		(start 126.78203 123.630455)
		(end 126.789541 123.697116)
		(width 0.15)
		(layer "In2.Cu")
		(net 328)
	)
	(segment
		(start 129.129523 122.697154)
		(end 129.153274 122.720905)
		(width 0.15)
		(layer "In2.Cu")
		(net 328)
	)
	(segment
		(start 129.602621 122.668189)
		(end 129.636 122.664428)
		(width 0.15)
		(layer "In2.Cu")
		(net 328)
	)
	(segment
		(start 126.72939 123.546678)
		(end 126.753107 123.570395)
		(width 0.15)
		(layer "In2.Cu")
		(net 328)
	)
	(segment
		(start 128.600833 123.728775)
		(end 128.618678 123.757176)
		(width 0.15)
		(layer "In2.Cu")
		(net 328)
	)
	(segment
		(start 127.686 122.814428)
		(end 127.68976 122.78105)
		(width 0.15)
		(layer "In2.Cu")
		(net 328)
	)
	(segment
		(start 128.318725 122.720905)
		(end 128.342476 122.697154)
		(width 0.15)
		(layer "In2.Cu")
		(net 328)
	)
	(segment
		(start 127.989755 123.697116)
		(end 128.000833 123.728775)
		(width 0.15)
		(layer "In2.Cu")
		(net 328)
	)
	(segment
		(start 128.589755 123.697116)
		(end 128.600833 123.728775)
		(width 0.15)
		(layer "In2.Cu")
		(net 328)
	)
	(segment
		(start 127.653321 123.757176)
		(end 127.671166 123.728775)
		(width 0.15)
		(layer "In2.Cu")
		(net 328)
	)
	(segment
		(start 129.453321 123.757176)
		(end 129.471166 123.728775)
		(width 0.15)
		(layer "In2.Cu")
		(net 328)
	)
	(segment
		(start 126.66933 123.517755)
		(end 126.700989 123.528833)
		(width 0.15)
		(layer "In2.Cu")
		(net 328)
	)
	(segment
		(start 127.502455 123.809816)
		(end 127.535786 123.813572)
		(width 0.15)
		(layer "In2.Cu")
		(net 328)
	)
	(segment
		(start 128.201203 123.798738)
		(end 128.229604 123.780893)
		(width 0.15)
		(layer "In2.Cu")
		(net 328)
	)
	(segment
		(start 128.829604 123.780893)
		(end 128.853321 123.757176)
		(width 0.15)
		(layer "In2.Cu")
		(net 328)
	)
	(segment
		(start 129.818725 123.457524)
		(end 129.842476 123.481275)
		(width 0.15)
		(layer "In2.Cu")
		(net 328)
	)
	(segment
		(start 128.070796 123.798738)
		(end 128.102455 123.809816)
		(width 0.15)
		(layer "In2.Cu")
		(net 328)
	)
	(segment
		(start 127.02939 123.780893)
		(end 127.053107 123.757176)
		(width 0.15)
		(layer "In2.Cu")
		(net 328)
	)
	(segment
		(start 129.471166 123.728775)
		(end 129.482244 123.697116)
		(width 0.15)
		(layer "In2.Cu")
		(net 328)
	)
	(segment
		(start 128.942476 122.697154)
		(end 128.970917 122.679283)
		(width 0.15)
		(layer "In2.Cu")
		(net 328)
	)
	(segment
		(start 127.770917 122.679283)
		(end 127.802621 122.668189)
		(width 0.15)
		(layer "In2.Cu")
		(net 328)
	)
	(segment
		(start 128.670796 123.798738)
		(end 128.702455 123.809816)
		(width 0.15)
		(layer "In2.Cu")
		(net 328)
	)
	(segment
		(start 105.775 115.275)
		(end 107.27497 116.77497)
		(width 0.15)
		(layer "In2.Cu")
		(net 328)
	)
	(segment
		(start 126.789541 123.697116)
		(end 126.800619 123.728775)
		(width 0.15)
		(layer "In2.Cu")
		(net 328)
	)
	(segment
		(start 128.042395 123.780893)
		(end 128.070796 123.798738)
		(width 0.15)
		(layer "In2.Cu")
		(net 328)
	)
	(segment
		(start 126.636 123.514)
		(end 126.66933 123.517755)
		(width 0.15)
		(layer "In2.Cu")
		(net 328)
	)
	(segment
		(start 128.300854 122.749346)
		(end 128.318725 122.720905)
		(width 0.15)
		(layer "In2.Cu")
		(net 328)
	)
	(segment
		(start 128.970917 122.679283)
		(end 129.002621 122.668189)
		(width 0.15)
		(layer "In2.Cu")
		(net 328)
	)
	(segment
		(start 127.236 122.664428)
		(end 127.269378 122.668189)
		(width 0.15)
		(layer "In2.Cu")
		(net 328)
	)
	(segment
		(start 127.442395 123.780893)
		(end 127.470796 123.798738)
		(width 0.15)
		(layer "In2.Cu")
		(net 328)
	)
	(segment
		(start 128.271166 123.728775)
		(end 128.282244 123.697116)
		(width 0.15)
		(layer "In2.Cu")
		(net 328)
	)
	(segment
		(start 128.102455 123.809816)
		(end 128.135786 123.813572)
		(width 0.15)
		(layer "In2.Cu")
		(net 328)
	)
	(segment
		(start 129.870917 123.499146)
		(end 129.902621 123.51024)
		(width 0.15)
		(layer "In2.Cu")
		(net 328)
	)
	(segment
		(start 139.274 119.274)
		(end 139.274 120.014)
		(width 0.15)
		(layer "F.Cu")
		(net 329)
	)
	(segment
		(start 109.775 112.175)
		(end 110.275 112.675)
		(width 0.15)
		(layer "F.Cu")
		(net 329)
	)
	(via
		(at 139.274 119.274)
		(size 0.5)
		(drill 0.2)
		(layers "F.Cu" "B.Cu")
		(net 329)
	)
	(via blind
		(at 110.275 112.675)
		(size 0.5)
		(drill 0.2)
		(layers "F.Cu" "In2.Cu")
		(net 329)
	)
	(segment
		(start 139.279 119.279)
		(end 139.274 119.274)
		(width 0.15)
		(layer "B.Cu")
		(net 329)
	)
	(segment
		(start 139.279 120.004)
		(end 139.279 119.279)
		(width 0.15)
		(layer "B.Cu")
		(net 329)
	)
	(segment
		(start 132.910145 115.92085)
		(end 132.892274 115.892409)
		(width 0.15)
		(layer "In2.Cu")
		(net 329)
	)
	(segment
		(start 133.309917 115.850787)
		(end 133.281476 115.868658)
		(width 0.15)
		(layer "In2.Cu")
		(net 329)
	)
	(segment
		(start 133.210145 117.82915)
		(end 133.192274 117.857591)
		(width 0.15)
		(layer "In2.Cu")
		(net 329)
	)
	(segment
		(start 132.240082 115.850787)
		(end 132.208378 115.839693)
		(width 0.15)
		(layer "In2.Cu")
		(net 329)
	)
	(segment
		(start 133.168523 117.881342)
		(end 133.140082 117.899213)
		(width 0.15)
		(layer "In2.Cu")
		(net 329)
	)
	(segment
		(start 131.640082 116.889855)
		(end 131.608378 116.878761)
		(width 0.15)
		(layer "In2.Cu")
		(net 329)
	)
	(segment
		(start 132.057725 115.892409)
		(end 132.039854 115.92085)
		(width 0.15)
		(layer "In2.Cu")
		(net 329)
	)
	(segment
		(start 132.32876 117.797446)
		(end 132.325 117.764067)
		(width 0.15)
		(layer "In2.Cu")
		(net 329)
	)
	(segment
		(start 131.668523 116.907726)
		(end 131.640082 116.889855)
		(width 0.15)
		(layer "In2.Cu")
		(net 329)
	)
	(segment
		(start 132.141621 115.839693)
		(end 132.109917 115.850787)
		(width 0.15)
		(layer "In2.Cu")
		(net 329)
	)
	(segment
		(start 132.021239 117.797446)
		(end 132.010145 117.82915)
		(width 0.15)
		(layer "In2.Cu")
		(net 329)
	)
	(segment
		(start 133.539854 116.790082)
		(end 133.52876 116.758378)
		(width 0.15)
		(layer "In2.Cu")
		(net 329)
	)
	(segment
		(start 131.908378 117.910307)
		(end 131.875 117.914067)
		(width 0.15)
		(layer "In2.Cu")
		(net 329)
	)
	(segment
		(start 133.675 116.875)
		(end 133.641621 116.871239)
		(width 0.15)
		(layer "In2.Cu")
		(net 329)
	)
	(segment
		(start 132.892274 115.892409)
		(end 132.868523 115.868658)
		(width 0.15)
		(layer "In2.Cu")
		(net 329)
	)
	(segment
		(start 132.02876 115.952554)
		(end 132.025 115.985933)
		(width 0.15)
		(layer "In2.Cu")
		(net 329)
	)
	(segment
		(start 133.192274 117.857591)
		(end 133.168523 117.881342)
		(width 0.15)
		(layer "In2.Cu")
		(net 329)
	)
	(segment
		(start 133.557725 116.818523)
		(end 133.539854 116.790082)
		(width 0.15)
		(layer "In2.Cu")
		(net 329)
	)
	(segment
		(start 132.92876 117.797446)
		(end 132.925 117.764067)
		(width 0.15)
		(layer "In2.Cu")
		(net 329)
	)
	(segment
		(start 132.709917 115.850787)
		(end 132.681476 115.868658)
		(width 0.15)
		(layer "In2.Cu")
		(net 329)
	)
	(segment
		(start 131.841621 117.910307)
		(end 131.809917 117.899213)
		(width 0.15)
		(layer "In2.Cu")
		(net 329)
	)
	(segment
		(start 133.239854 115.92085)
		(end 133.22876 115.952554)
		(width 0.15)
		(layer "In2.Cu")
		(net 329)
	)
	(segment
		(start 132.681476 115.868658)
		(end 132.657725 115.892409)
		(width 0.15)
		(layer "In2.Cu")
		(net 329)
	)
	(segment
		(start 132.621239 117.797446)
		(end 132.610145 117.82915)
		(width 0.15)
		(layer "In2.Cu")
		(net 329)
	)
	(segment
		(start 110.275 112.675)
		(end 111.275 112.675)
		(width 0.15)
		(layer "In2.Cu")
		(net 329)
	)
	(segment
		(start 132.357725 117.857591)
		(end 132.339854 117.82915)
		(width 0.15)
		(layer "In2.Cu")
		(net 329)
	)
	(segment
		(start 131.692274 116.931477)
		(end 131.668523 116.907726)
		(width 0.15)
		(layer "In2.Cu")
		(net 329)
	)
	(segment
		(start 132.508378 117.910307)
		(end 132.475 117.914067)
		(width 0.15)
		(layer "In2.Cu")
		(net 329)
	)
	(segment
		(start 118.775 116.875)
		(end 116.074919 114.174919)
		(width 0.15)
		(layer "In2.Cu")
		(net 329)
	)
	(segment
		(start 133.52876 116.758378)
		(end 133.525 116.725)
		(width 0.15)
		(layer "In2.Cu")
		(net 329)
	)
	(segment
		(start 132.741621 115.839693)
		(end 132.709917 115.850787)
		(width 0.15)
		(layer "In2.Cu")
		(net 329)
	)
	(segment
		(start 131.72876 117.797446)
		(end 131.725 117.764067)
		(width 0.15)
		(layer "In2.Cu")
		(net 329)
	)
	(segment
		(start 133.609917 116.860145)
		(end 133.581476 116.842274)
		(width 0.15)
		(layer "In2.Cu")
		(net 329)
	)
	(segment
		(start 133.525 116.725)
		(end 133.525 115.985933)
		(width 0.15)
		(layer "In2.Cu")
		(net 329)
	)
	(segment
		(start 131.739854 117.82915)
		(end 131.72876 117.797446)
		(width 0.15)
		(layer "In2.Cu")
		(net 329)
	)
	(segment
		(start 133.22876 115.952554)
		(end 133.225 115.985933)
		(width 0.15)
		(layer "In2.Cu")
		(net 329)
	)
	(segment
		(start 132.921239 115.952554)
		(end 132.910145 115.92085)
		(width 0.15)
		(layer "In2.Cu")
		(net 329)
	)
	(segment
		(start 133.225 115.985933)
		(end 133.225 117.764067)
		(width 0.15)
		(layer "In2.Cu")
		(net 329)
	)
	(segment
		(start 132.325 117.764067)
		(end 132.325 115.985933)
		(width 0.15)
		(layer "In2.Cu")
		(net 329)
	)
	(segment
		(start 132.039854 115.92085)
		(end 132.02876 115.952554)
		(width 0.15)
		(layer "In2.Cu")
		(net 329)
	)
	(segment
		(start 133.221239 117.797446)
		(end 133.210145 117.82915)
		(width 0.15)
		(layer "In2.Cu")
		(net 329)
	)
	(segment
		(start 132.639854 115.92085)
		(end 132.62876 115.952554)
		(width 0.15)
		(layer "In2.Cu")
		(net 329)
	)
	(segment
		(start 131.725 117.025)
		(end 131.721239 116.991622)
		(width 0.15)
		(layer "In2.Cu")
		(net 329)
	)
	(segment
		(start 132.939854 117.82915)
		(end 132.92876 117.797446)
		(width 0.15)
		(layer "In2.Cu")
		(net 329)
	)
	(segment
		(start 132.981476 117.881342)
		(end 132.957725 117.857591)
		(width 0.15)
		(layer "In2.Cu")
		(net 329)
	)
	(segment
		(start 131.992274 117.857591)
		(end 131.968523 117.881342)
		(width 0.15)
		(layer "In2.Cu")
		(net 329)
	)
	(segment
		(start 133.341621 115.839693)
		(end 133.309917 115.850787)
		(width 0.15)
		(layer "In2.Cu")
		(net 329)
	)
	(segment
		(start 131.608378 116.878761)
		(end 131.575 116.875)
		(width 0.15)
		(layer "In2.Cu")
		(net 329)
	)
	(segment
		(start 132.292274 115.892409)
		(end 132.268523 115.868658)
		(width 0.15)
		(layer "In2.Cu")
		(net 329)
	)
	(segment
		(start 132.109917 115.850787)
		(end 132.081476 115.868658)
		(width 0.15)
		(layer "In2.Cu")
		(net 329)
	)
	(segment
		(start 132.610145 117.82915)
		(end 132.592274 117.857591)
		(width 0.15)
		(layer "In2.Cu")
		(net 329)
	)
	(segment
		(start 132.175 115.835933)
		(end 132.141621 115.839693)
		(width 0.15)
		(layer "In2.Cu")
		(net 329)
	)
	(segment
		(start 132.475 117.914067)
		(end 132.441621 117.910307)
		(width 0.15)
		(layer "In2.Cu")
		(net 329)
	)
	(segment
		(start 132.441621 117.910307)
		(end 132.409917 117.899213)
		(width 0.15)
		(layer "In2.Cu")
		(net 329)
	)
	(segment
		(start 132.409917 117.899213)
		(end 132.381476 117.881342)
		(width 0.15)
		(layer "In2.Cu")
		(net 329)
	)
	(segment
		(start 132.268523 115.868658)
		(end 132.240082 115.850787)
		(width 0.15)
		(layer "In2.Cu")
		(net 329)
	)
	(segment
		(start 132.025 115.985933)
		(end 132.025 117.764067)
		(width 0.15)
		(layer "In2.Cu")
		(net 329)
	)
	(segment
		(start 133.440082 115.850787)
		(end 133.408378 115.839693)
		(width 0.15)
		(layer "In2.Cu")
		(net 329)
	)
	(segment
		(start 131.781476 117.881342)
		(end 131.757725 117.857591)
		(width 0.15)
		(layer "In2.Cu")
		(net 329)
	)
	(segment
		(start 132.540082 117.899213)
		(end 132.508378 117.910307)
		(width 0.15)
		(layer "In2.Cu")
		(net 329)
	)
	(segment
		(start 132.868523 115.868658)
		(end 132.840082 115.850787)
		(width 0.15)
		(layer "In2.Cu")
		(net 329)
	)
	(segment
		(start 132.025 117.764067)
		(end 132.021239 117.797446)
		(width 0.15)
		(layer "In2.Cu")
		(net 329)
	)
	(segment
		(start 136.875 116.875)
		(end 133.675 116.875)
		(width 0.15)
		(layer "In2.Cu")
		(net 329)
	)
	(segment
		(start 132.775 115.835933)
		(end 132.741621 115.839693)
		(width 0.15)
		(layer "In2.Cu")
		(net 329)
	)
	(segment
		(start 133.581476 116.842274)
		(end 133.557725 116.818523)
		(width 0.15)
		(layer "In2.Cu")
		(net 329)
	)
	(segment
		(start 133.521239 115.952554)
		(end 133.510145 115.92085)
		(width 0.15)
		(layer "In2.Cu")
		(net 329)
	)
	(segment
		(start 132.381476 117.881342)
		(end 132.357725 117.857591)
		(width 0.15)
		(layer "In2.Cu")
		(net 329)
	)
	(segment
		(start 132.592274 117.857591)
		(end 132.568523 117.881342)
		(width 0.15)
		(layer "In2.Cu")
		(net 329)
	)
	(segment
		(start 131.968523 117.881342)
		(end 131.940082 117.899213)
		(width 0.15)
		(layer "In2.Cu")
		(net 329)
	)
	(segment
		(start 131.940082 117.899213)
		(end 131.908378 117.910307)
		(width 0.15)
		(layer "In2.Cu")
		(net 329)
	)
	(segment
		(start 132.310145 115.92085)
		(end 132.292274 115.892409)
		(width 0.15)
		(layer "In2.Cu")
		(net 329)
	)
	(segment
		(start 131.875 117.914067)
		(end 131.841621 117.910307)
		(width 0.15)
		(layer "In2.Cu")
		(net 329)
	)
	(segment
		(start 133.375 115.835933)
		(end 133.341621 115.839693)
		(width 0.15)
		(layer "In2.Cu")
		(net 329)
	)
	(segment
		(start 132.925 115.985933)
		(end 132.921239 115.952554)
		(width 0.15)
		(layer "In2.Cu")
		(net 329)
	)
	(segment
		(start 132.325 115.985933)
		(end 132.321239 115.952554)
		(width 0.15)
		(layer "In2.Cu")
		(net 329)
	)
	(segment
		(start 133.108378 117.910307)
		(end 133.075 117.914067)
		(width 0.15)
		(layer "In2.Cu")
		(net 329)
	)
	(segment
		(start 112.774919 114.174919)
		(end 111.275 112.675)
		(width 0.15)
		(layer "In2.Cu")
		(net 329)
	)
	(segment
		(start 133.281476 115.868658)
		(end 133.257725 115.892409)
		(width 0.15)
		(layer "In2.Cu")
		(net 329)
	)
	(segment
		(start 132.081476 115.868658)
		(end 132.057725 115.892409)
		(width 0.15)
		(layer "In2.Cu")
		(net 329)
	)
	(segment
		(start 133.641621 116.871239)
		(end 133.609917 116.860145)
		(width 0.15)
		(layer "In2.Cu")
		(net 329)
	)
	(segment
		(start 132.625 117.764067)
		(end 132.621239 117.797446)
		(width 0.15)
		(layer "In2.Cu")
		(net 329)
	)
	(segment
		(start 132.010145 117.82915)
		(end 131.992274 117.857591)
		(width 0.15)
		(layer "In2.Cu")
		(net 329)
	)
	(segment
		(start 133.408378 115.839693)
		(end 133.375 115.835933)
		(width 0.15)
		(layer "In2.Cu")
		(net 329)
	)
	(segment
		(start 132.840082 115.850787)
		(end 132.808378 115.839693)
		(width 0.15)
		(layer "In2.Cu")
		(net 329)
	)
	(segment
		(start 131.725 117.764067)
		(end 131.725 117.025)
		(width 0.15)
		(layer "In2.Cu")
		(net 329)
	)
	(segment
		(start 132.957725 117.857591)
		(end 132.939854 117.82915)
		(width 0.15)
		(layer "In2.Cu")
		(net 329)
	)
	(segment
		(start 133.075 117.914067)
		(end 133.041621 117.910307)
		(width 0.15)
		(layer "In2.Cu")
		(net 329)
	)
	(segment
		(start 132.925 117.764067)
		(end 132.925 115.985933)
		(width 0.15)
		(layer "In2.Cu")
		(net 329)
	)
	(segment
		(start 132.625 115.985933)
		(end 132.625 117.764067)
		(width 0.15)
		(layer "In2.Cu")
		(net 329)
	)
	(segment
		(start 133.257725 115.892409)
		(end 133.239854 115.92085)
		(width 0.15)
		(layer "In2.Cu")
		(net 329)
	)
	(segment
		(start 133.525 115.985933)
		(end 133.521239 115.952554)
		(width 0.15)
		(layer "In2.Cu")
		(net 329)
	)
	(segment
		(start 132.208378 115.839693)
		(end 132.175 115.835933)
		(width 0.15)
		(layer "In2.Cu")
		(net 329)
	)
	(segment
		(start 131.575 116.875)
		(end 118.775 116.875)
		(width 0.15)
		(layer "In2.Cu")
		(net 329)
	)
	(segment
		(start 131.710145 116.959918)
		(end 131.692274 116.931477)
		(width 0.15)
		(layer "In2.Cu")
		(net 329)
	)
	(segment
		(start 131.809917 117.899213)
		(end 131.781476 117.881342)
		(width 0.15)
		(layer "In2.Cu")
		(net 329)
	)
	(segment
		(start 133.009917 117.899213)
		(end 132.981476 117.881342)
		(width 0.15)
		(layer "In2.Cu")
		(net 329)
	)
	(segment
		(start 133.140082 117.899213)
		(end 133.108378 117.910307)
		(width 0.15)
		(layer "In2.Cu")
		(net 329)
	)
	(segment
		(start 131.757725 117.857591)
		(end 131.739854 117.82915)
		(width 0.15)
		(layer "In2.Cu")
		(net 329)
	)
	(segment
		(start 132.321239 115.952554)
		(end 132.310145 115.92085)
		(width 0.15)
		(layer "In2.Cu")
		(net 329)
	)
	(segment
		(start 132.657725 115.892409)
		(end 132.639854 115.92085)
		(width 0.15)
		(layer "In2.Cu")
		(net 329)
	)
	(segment
		(start 139.274 119.274)
		(end 136.875 116.875)
		(width 0.15)
		(layer "In2.Cu")
		(net 329)
	)
	(segment
		(start 116.074919 114.174919)
		(end 112.774919 114.174919)
		(width 0.15)
		(layer "In2.Cu")
		(net 329)
	)
	(segment
		(start 133.225 117.764067)
		(end 133.221239 117.797446)
		(width 0.15)
		(layer "In2.Cu")
		(net 329)
	)
	(segment
		(start 132.568523 117.881342)
		(end 132.540082 117.899213)
		(width 0.15)
		(layer "In2.Cu")
		(net 329)
	)
	(segment
		(start 133.492274 115.892409)
		(end 133.468523 115.868658)
		(width 0.15)
		(layer "In2.Cu")
		(net 329)
	)
	(segment
		(start 132.62876 115.952554)
		(end 132.625 115.985933)
		(width 0.15)
		(layer "In2.Cu")
		(net 329)
	)
	(segment
		(start 133.510145 115.92085)
		(end 133.492274 115.892409)
		(width 0.15)
		(layer "In2.Cu")
		(net 329)
	)
	(segment
		(start 133.041621 117.910307)
		(end 133.009917 117.899213)
		(width 0.15)
		(layer "In2.Cu")
		(net 329)
	)
	(segment
		(start 132.808378 115.839693)
		(end 132.775 115.835933)
		(width 0.15)
		(layer "In2.Cu")
		(net 329)
	)
	(segment
		(start 133.468523 115.868658)
		(end 133.440082 115.850787)
		(width 0.15)
		(layer "In2.Cu")
		(net 329)
	)
	(segment
		(start 132.339854 117.82915)
		(end 132.32876 117.797446)
		(width 0.15)
		(layer "In2.Cu")
		(net 329)
	)
	(segment
		(start 131.721239 116.991622)
		(end 131.710145 116.959918)
		(width 0.15)
		(layer "In2.Cu")
		(net 329)
	)
	(segment
		(start 109.775 113.175)
		(end 110.275 113.675)
		(width 0.15)
		(layer "F.Cu")
		(net 330)
	)
	(via blind
		(at 110.275 113.675)
		(size 0.5)
		(drill 0.2)
		(layers "F.Cu" "In2.Cu")
		(net 330)
	)
	(via
		(at 136.69 118.565)
		(size 0.5)
		(drill 0.2)
		(layers "F.Cu" "B.Cu")
		(net 330)
	)
	(segment
		(start 137.355 118.565)
		(end 136.69 118.565)
		(width 0.15)
		(layer "B.Cu")
		(net 330)
	)
	(segment
		(start 135.541621 117.502394)
		(end 135.575 117.498633)
		(width 0.15)
		(layer "In2.Cu")
		(net 330)
	)
	(segment
		(start 135.710145 117.583551)
		(end 135.721239 117.615255)
		(width 0.15)
		(layer "In2.Cu")
		(net 330)
	)
	(segment
		(start 135.040082 117.513488)
		(end 135.068523 117.531359)
		(width 0.15)
		(layer "In2.Cu")
		(net 330)
	)
	(segment
		(start 133.939854 119.316449)
		(end 133.957725 119.34489)
		(width 0.15)
		(layer "In2.Cu")
		(net 330)
	)
	(segment
		(start 135.457725 117.55511)
		(end 135.481476 117.531359)
		(width 0.15)
		(layer "In2.Cu")
		(net 330)
	)
	(segment
		(start 136.057725 117.55511)
		(end 136.081476 117.531359)
		(width 0.15)
		(layer "In2.Cu")
		(net 330)
	)
	(segment
		(start 135.121239 117.615255)
		(end 135.125 117.648633)
		(width 0.15)
		(layer "In2.Cu")
		(net 330)
	)
	(segment
		(start 134.768523 119.018641)
		(end 134.792274 118.99489)
		(width 0.15)
		(layer "In2.Cu")
		(net 330)
	)
	(segment
		(start 135.509917 117.513488)
		(end 135.541621 117.502394)
		(width 0.15)
		(layer "In2.Cu")
		(net 330)
	)
	(segment
		(start 134.557725 118.99489)
		(end 134.581476 119.018641)
		(width 0.15)
		(layer "In2.Cu")
		(net 330)
	)
	(segment
		(start 134.309917 117.513488)
		(end 134.341621 117.502394)
		(width 0.15)
		(layer "In2.Cu")
		(net 330)
	)
	(segment
		(start 134.492274 117.55511)
		(end 134.510145 117.583551)
		(width 0.15)
		(layer "In2.Cu")
		(net 330)
	)
	(segment
		(start 134.539854 118.966449)
		(end 134.557725 118.99489)
		(width 0.15)
		(layer "In2.Cu")
		(net 330)
	)
	(segment
		(start 134.825 118.901367)
		(end 134.825 117.648633)
		(width 0.15)
		(layer "In2.Cu")
		(net 330)
	)
	(segment
		(start 134.82876 117.615255)
		(end 134.839854 117.583551)
		(width 0.15)
		(layer "In2.Cu")
		(net 330)
	)
	(segment
		(start 135.308378 119.347606)
		(end 135.340082 119.336512)
		(width 0.15)
		(layer "In2.Cu")
		(net 330)
	)
	(segment
		(start 136.175 117.498633)
		(end 136.208378 117.502394)
		(width 0.15)
		(layer "In2.Cu")
		(net 330)
	)
	(segment
		(start 134.22876 117.615255)
		(end 134.239854 117.583551)
		(width 0.15)
		(layer "In2.Cu")
		(net 330)
	)
	(segment
		(start 135.008378 117.502394)
		(end 135.040082 117.513488)
		(width 0.15)
		(layer "In2.Cu")
		(net 330)
	)
	(segment
		(start 134.740082 119.036512)
		(end 134.768523 119.018641)
		(width 0.15)
		(layer "In2.Cu")
		(net 330)
	)
	(segment
		(start 136.325 118.425)
		(end 136.32876 118.458379)
		(width 0.15)
		(layer "In2.Cu")
		(net 330)
	)
	(segment
		(start 134.510145 117.583551)
		(end 134.521239 117.615255)
		(width 0.15)
		(layer "In2.Cu")
		(net 330)
	)
	(segment
		(start 124.875 118.975)
		(end 125.275 118.575)
		(width 0.15)
		(layer "In2.Cu")
		(net 330)
	)
	(segment
		(start 133.775 118.575)
		(end 133.808378 118.57876)
		(width 0.15)
		(layer "In2.Cu")
		(net 330)
	)
	(segment
		(start 135.368523 119.318641)
		(end 135.392274 119.29489)
		(width 0.15)
		(layer "In2.Cu")
		(net 330)
	)
	(segment
		(start 133.925 119.251367)
		(end 133.92876 119.284745)
		(width 0.15)
		(layer "In2.Cu")
		(net 330)
	)
	(segment
		(start 135.125 117.648633)
		(end 135.125 119.201367)
		(width 0.15)
		(layer "In2.Cu")
		(net 330)
	)
	(segment
		(start 134.792274 118.99489)
		(end 134.810145 118.966449)
		(width 0.15)
		(layer "In2.Cu")
		(net 330)
	)
	(segment
		(start 134.075 119.401367)
		(end 134.108378 119.397606)
		(width 0.15)
		(layer "In2.Cu")
		(net 330)
	)
	(segment
		(start 133.910145 118.659917)
		(end 133.921239 118.691621)
		(width 0.15)
		(layer "In2.Cu")
		(net 330)
	)
	(segment
		(start 134.525 118.901367)
		(end 134.52876 118.934745)
		(width 0.15)
		(layer "In2.Cu")
		(net 330)
	)
	(segment
		(start 135.139854 119.266449)
		(end 135.157725 119.29489)
		(width 0.15)
		(layer "In2.Cu")
		(net 330)
	)
	(segment
		(start 135.42876 117.615255)
		(end 135.439854 117.583551)
		(width 0.15)
		(layer "In2.Cu")
		(net 330)
	)
	(segment
		(start 133.868523 118.607725)
		(end 133.892274 118.631476)
		(width 0.15)
		(layer "In2.Cu")
		(net 330)
	)
	(segment
		(start 135.392274 119.29489)
		(end 135.410145 119.266449)
		(width 0.15)
		(layer "In2.Cu")
		(net 330)
	)
	(segment
		(start 135.068523 117.531359)
		(end 135.092274 117.55511)
		(width 0.15)
		(layer "In2.Cu")
		(net 330)
	)
	(segment
		(start 111.07493 114.47493)
		(end 115.823483 114.47493)
		(width 0.15)
		(layer "In2.Cu")
		(net 330)
	)
	(segment
		(start 136.141621 117.502394)
		(end 136.175 117.498633)
		(width 0.15)
		(layer "In2.Cu")
		(net 330)
	)
	(segment
		(start 133.981476 119.368641)
		(end 134.009917 119.386512)
		(width 0.15)
		(layer "In2.Cu")
		(net 330)
	)
	(segment
		(start 135.425 117.648633)
		(end 135.42876 117.615255)
		(width 0.15)
		(layer "In2.Cu")
		(net 330)
	)
	(segment
		(start 134.609917 119.036512)
		(end 134.641621 119.047606)
		(width 0.15)
		(layer "In2.Cu")
		(net 330)
	)
	(segment
		(start 110.275 113.675)
		(end 111.07493 114.47493)
		(width 0.15)
		(layer "In2.Cu")
		(net 330)
	)
	(segment
		(start 135.209917 119.336512)
		(end 135.241621 119.347606)
		(width 0.15)
		(layer "In2.Cu")
		(net 330)
	)
	(segment
		(start 134.810145 118.966449)
		(end 134.821239 118.934745)
		(width 0.15)
		(layer "In2.Cu")
		(net 330)
	)
	(segment
		(start 134.281476 117.531359)
		(end 134.309917 117.513488)
		(width 0.15)
		(layer "In2.Cu")
		(net 330)
	)
	(segment
		(start 136.025 118.951367)
		(end 136.025 117.648633)
		(width 0.15)
		(layer "In2.Cu")
		(net 330)
	)
	(segment
		(start 134.821239 118.934745)
		(end 134.825 118.901367)
		(width 0.15)
		(layer "In2.Cu")
		(net 330)
	)
	(segment
		(start 135.757725 119.04489)
		(end 135.781476 119.068641)
		(width 0.15)
		(layer "In2.Cu")
		(net 330)
	)
	(segment
		(start 136.685146 118.560146)
		(end 136.69 118.565)
		(width 0.15)
		(layer "In2.Cu")
		(net 330)
	)
	(segment
		(start 134.140082 119.386512)
		(end 134.168523 119.368641)
		(width 0.15)
		(layer "In2.Cu")
		(net 330)
	)
	(segment
		(start 136.268523 117.531359)
		(end 136.292274 117.55511)
		(width 0.15)
		(layer "In2.Cu")
		(net 330)
	)
	(segment
		(start 134.708378 119.047606)
		(end 134.740082 119.036512)
		(width 0.15)
		(layer "In2.Cu")
		(net 330)
	)
	(segment
		(start 136.208378 117.502394)
		(end 136.240082 117.513488)
		(width 0.15)
		(layer "In2.Cu")
		(net 330)
	)
	(segment
		(start 136.310145 117.583551)
		(end 136.321239 117.615255)
		(width 0.15)
		(layer "In2.Cu")
		(net 330)
	)
	(segment
		(start 136.010145 119.016449)
		(end 136.021239 118.984745)
		(width 0.15)
		(layer "In2.Cu")
		(net 330)
	)
	(segment
		(start 136.109917 117.513488)
		(end 136.141621 117.502394)
		(width 0.15)
		(layer "In2.Cu")
		(net 330)
	)
	(segment
		(start 135.092274 117.55511)
		(end 135.110145 117.583551)
		(width 0.15)
		(layer "In2.Cu")
		(net 330)
	)
	(segment
		(start 135.968523 119.068641)
		(end 135.992274 119.04489)
		(width 0.15)
		(layer "In2.Cu")
		(net 330)
	)
	(segment
		(start 134.521239 117.615255)
		(end 134.525 117.648633)
		(width 0.15)
		(layer "In2.Cu")
		(net 330)
	)
	(segment
		(start 134.225 117.648633)
		(end 134.22876 117.615255)
		(width 0.15)
		(layer "In2.Cu")
		(net 330)
	)
	(segment
		(start 135.241621 119.347606)
		(end 135.275 119.351367)
		(width 0.15)
		(layer "In2.Cu")
		(net 330)
	)
	(segment
		(start 133.92876 119.284745)
		(end 133.939854 119.316449)
		(width 0.15)
		(layer "In2.Cu")
		(net 330)
	)
	(segment
		(start 135.692274 117.55511)
		(end 135.710145 117.583551)
		(width 0.15)
		(layer "In2.Cu")
		(net 330)
	)
	(segment
		(start 134.108378 119.397606)
		(end 134.140082 119.386512)
		(width 0.15)
		(layer "In2.Cu")
		(net 330)
	)
	(segment
		(start 135.72876 118.984745)
		(end 135.739854 119.016449)
		(width 0.15)
		(layer "In2.Cu")
		(net 330)
	)
	(segment
		(start 134.857725 117.55511)
		(end 134.881476 117.531359)
		(width 0.15)
		(layer "In2.Cu")
		(net 330)
	)
	(segment
		(start 133.840082 118.589854)
		(end 133.868523 118.607725)
		(width 0.15)
		(layer "In2.Cu")
		(net 330)
	)
	(segment
		(start 134.975 117.498633)
		(end 135.008378 117.502394)
		(width 0.15)
		(layer "In2.Cu")
		(net 330)
	)
	(segment
		(start 134.225 119.251367)
		(end 134.225 117.648633)
		(width 0.15)
		(layer "In2.Cu")
		(net 330)
	)
	(segment
		(start 135.439854 117.583551)
		(end 135.457725 117.55511)
		(width 0.15)
		(layer "In2.Cu")
		(net 330)
	)
	(segment
		(start 134.825 117.648633)
		(end 134.82876 117.615255)
		(width 0.15)
		(layer "In2.Cu")
		(net 330)
	)
	(segment
		(start 136.339854 118.490083)
		(end 136.357725 118.518524)
		(width 0.15)
		(layer "In2.Cu")
		(net 330)
	)
	(segment
		(start 135.181476 119.318641)
		(end 135.209917 119.336512)
		(width 0.15)
		(layer "In2.Cu")
		(net 330)
	)
	(segment
		(start 136.081476 117.531359)
		(end 136.109917 117.513488)
		(width 0.15)
		(layer "In2.Cu")
		(net 330)
	)
	(segment
		(start 135.940082 119.086512)
		(end 135.968523 119.068641)
		(width 0.15)
		(layer "In2.Cu")
		(net 330)
	)
	(segment
		(start 134.941621 117.502394)
		(end 134.975 117.498633)
		(width 0.15)
		(layer "In2.Cu")
		(net 330)
	)
	(segment
		(start 134.468523 117.531359)
		(end 134.492274 117.55511)
		(width 0.15)
		(layer "In2.Cu")
		(net 330)
	)
	(segment
		(start 135.125 119.201367)
		(end 135.12876 119.234745)
		(width 0.15)
		(layer "In2.Cu")
		(net 330)
	)
	(segment
		(start 133.925 118.725)
		(end 133.925 119.251367)
		(width 0.15)
		(layer "In2.Cu")
		(net 330)
	)
	(segment
		(start 135.725 118.951367)
		(end 135.72876 118.984745)
		(width 0.15)
		(layer "In2.Cu")
		(net 330)
	)
	(segment
		(start 115.823483 114.47493)
		(end 120.297552 118.948999)
		(width 0.15)
		(layer "In2.Cu")
		(net 330)
	)
	(segment
		(start 134.525 117.648633)
		(end 134.525 118.901367)
		(width 0.15)
		(layer "In2.Cu")
		(net 330)
	)
	(segment
		(start 134.675 119.051367)
		(end 134.708378 119.047606)
		(width 0.15)
		(layer "In2.Cu")
		(net 330)
	)
	(segment
		(start 135.640082 117.513488)
		(end 135.668523 117.531359)
		(width 0.15)
		(layer "In2.Cu")
		(net 330)
	)
	(segment
		(start 136.025 117.648633)
		(end 136.02876 117.615255)
		(width 0.15)
		(layer "In2.Cu")
		(net 330)
	)
	(segment
		(start 133.921239 118.691621)
		(end 133.925 118.725)
		(width 0.15)
		(layer "In2.Cu")
		(net 330)
	)
	(segment
		(start 135.575 117.498633)
		(end 135.608378 117.502394)
		(width 0.15)
		(layer "In2.Cu")
		(net 330)
	)
	(segment
		(start 135.481476 117.531359)
		(end 135.509917 117.513488)
		(width 0.15)
		(layer "In2.Cu")
		(net 330)
	)
	(segment
		(start 136.02876 117.615255)
		(end 136.039854 117.583551)
		(width 0.15)
		(layer "In2.Cu")
		(net 330)
	)
	(segment
		(start 135.992274 119.04489)
		(end 136.010145 119.016449)
		(width 0.15)
		(layer "In2.Cu")
		(net 330)
	)
	(segment
		(start 134.341621 117.502394)
		(end 134.375 117.498633)
		(width 0.15)
		(layer "In2.Cu")
		(net 330)
	)
	(segment
		(start 136.325 117.648633)
		(end 136.325 118.425)
		(width 0.15)
		(layer "In2.Cu")
		(net 330)
	)
	(segment
		(start 135.781476 119.068641)
		(end 135.809917 119.086512)
		(width 0.15)
		(layer "In2.Cu")
		(net 330)
	)
	(segment
		(start 134.192274 119.34489)
		(end 134.210145 119.316449)
		(width 0.15)
		(layer "In2.Cu")
		(net 330)
	)
	(segment
		(start 134.52876 118.934745)
		(end 134.539854 118.966449)
		(width 0.15)
		(layer "In2.Cu")
		(net 330)
	)
	(segment
		(start 134.839854 117.583551)
		(end 134.857725 117.55511)
		(width 0.15)
		(layer "In2.Cu")
		(net 330)
	)
	(segment
		(start 134.257725 117.55511)
		(end 134.281476 117.531359)
		(width 0.15)
		(layer "In2.Cu")
		(net 330)
	)
	(segment
		(start 135.340082 119.336512)
		(end 135.368523 119.318641)
		(width 0.15)
		(layer "In2.Cu")
		(net 330)
	)
	(segment
		(start 135.809917 119.086512)
		(end 135.841621 119.097606)
		(width 0.15)
		(layer "In2.Cu")
		(net 330)
	)
	(segment
		(start 134.009917 119.386512)
		(end 134.041621 119.397606)
		(width 0.15)
		(layer "In2.Cu")
		(net 330)
	)
	(segment
		(start 135.908378 119.097606)
		(end 135.940082 119.086512)
		(width 0.15)
		(layer "In2.Cu")
		(net 330)
	)
	(segment
		(start 135.841621 119.097606)
		(end 135.875 119.101367)
		(width 0.15)
		(layer "In2.Cu")
		(net 330)
	)
	(segment
		(start 136.409917 118.560146)
		(end 136.685146 118.560146)
		(width 0.15)
		(layer "In2.Cu")
		(net 330)
	)
	(segment
		(start 136.021239 118.984745)
		(end 136.025 118.951367)
		(width 0.15)
		(layer "In2.Cu")
		(net 330)
	)
	(segment
		(start 135.275 119.351367)
		(end 135.308378 119.347606)
		(width 0.15)
		(layer "In2.Cu")
		(net 330)
	)
	(segment
		(start 135.421239 119.234745)
		(end 135.425 119.201367)
		(width 0.15)
		(layer "In2.Cu")
		(net 330)
	)
	(segment
		(start 136.32876 118.458379)
		(end 136.339854 118.490083)
		(width 0.15)
		(layer "In2.Cu")
		(net 330)
	)
	(segment
		(start 134.440082 117.513488)
		(end 134.468523 117.531359)
		(width 0.15)
		(layer "In2.Cu")
		(net 330)
	)
	(segment
		(start 135.12876 119.234745)
		(end 135.139854 119.266449)
		(width 0.15)
		(layer "In2.Cu")
		(net 330)
	)
	(segment
		(start 136.381476 118.542275)
		(end 136.409917 118.560146)
		(width 0.15)
		(layer "In2.Cu")
		(net 330)
	)
	(segment
		(start 134.909917 117.513488)
		(end 134.941621 117.502394)
		(width 0.15)
		(layer "In2.Cu")
		(net 330)
	)
	(segment
		(start 135.110145 117.583551)
		(end 135.121239 117.615255)
		(width 0.15)
		(layer "In2.Cu")
		(net 330)
	)
	(segment
		(start 120.297552 118.948999)
		(end 124.875 118.975)
		(width 0.15)
		(layer "In2.Cu")
		(net 330)
	)
	(segment
		(start 135.739854 119.016449)
		(end 135.757725 119.04489)
		(width 0.15)
		(layer "In2.Cu")
		(net 330)
	)
	(segment
		(start 135.425 119.201367)
		(end 135.425 117.648633)
		(width 0.15)
		(layer "In2.Cu")
		(net 330)
	)
	(segment
		(start 134.168523 119.368641)
		(end 134.192274 119.34489)
		(width 0.15)
		(layer "In2.Cu")
		(net 330)
	)
	(segment
		(start 134.641621 119.047606)
		(end 134.675 119.051367)
		(width 0.15)
		(layer "In2.Cu")
		(net 330)
	)
	(segment
		(start 134.881476 117.531359)
		(end 134.909917 117.513488)
		(width 0.15)
		(layer "In2.Cu")
		(net 330)
	)
	(segment
		(start 133.892274 118.631476)
		(end 133.910145 118.659917)
		(width 0.15)
		(layer "In2.Cu")
		(net 330)
	)
	(segment
		(start 134.408378 117.502394)
		(end 134.440082 117.513488)
		(width 0.15)
		(layer "In2.Cu")
		(net 330)
	)
	(segment
		(start 134.221239 119.284745)
		(end 134.225 119.251367)
		(width 0.15)
		(layer "In2.Cu")
		(net 330)
	)
	(segment
		(start 133.957725 119.34489)
		(end 133.981476 119.368641)
		(width 0.15)
		(layer "In2.Cu")
		(net 330)
	)
	(segment
		(start 134.041621 119.397606)
		(end 134.075 119.401367)
		(width 0.15)
		(layer "In2.Cu")
		(net 330)
	)
	(segment
		(start 134.375 117.498633)
		(end 134.408378 117.502394)
		(width 0.15)
		(layer "In2.Cu")
		(net 330)
	)
	(segment
		(start 136.039854 117.583551)
		(end 136.057725 117.55511)
		(width 0.15)
		(layer "In2.Cu")
		(net 330)
	)
	(segment
		(start 136.357725 118.518524)
		(end 136.381476 118.542275)
		(width 0.15)
		(layer "In2.Cu")
		(net 330)
	)
	(segment
		(start 136.292274 117.55511)
		(end 136.310145 117.583551)
		(width 0.15)
		(layer "In2.Cu")
		(net 330)
	)
	(segment
		(start 136.409917 118.560146)
		(end 136.441621 118.57124)
		(width 0.15)
		(layer "In2.Cu")
		(net 330)
	)
	(segment
		(start 136.321239 117.615255)
		(end 136.325 117.648633)
		(width 0.15)
		(layer "In2.Cu")
		(net 330)
	)
	(segment
		(start 134.581476 119.018641)
		(end 134.609917 119.036512)
		(width 0.15)
		(layer "In2.Cu")
		(net 330)
	)
	(segment
		(start 135.410145 119.266449)
		(end 135.421239 119.234745)
		(width 0.15)
		(layer "In2.Cu")
		(net 330)
	)
	(segment
		(start 136.441621 118.57124)
		(end 136.475 118.575)
		(width 0.15)
		(layer "In2.Cu")
		(net 330)
	)
	(segment
		(start 134.239854 117.583551)
		(end 134.257725 117.55511)
		(width 0.15)
		(layer "In2.Cu")
		(net 330)
	)
	(segment
		(start 135.157725 119.29489)
		(end 135.181476 119.318641)
		(width 0.15)
		(layer "In2.Cu")
		(net 330)
	)
	(segment
		(start 134.210145 119.316449)
		(end 134.221239 119.284745)
		(width 0.15)
		(layer "In2.Cu")
		(net 330)
	)
	(segment
		(start 135.721239 117.615255)
		(end 135.725 117.648633)
		(width 0.15)
		(layer "In2.Cu")
		(net 330)
	)
	(segment
		(start 136.240082 117.513488)
		(end 136.268523 117.531359)
		(width 0.15)
		(layer "In2.Cu")
		(net 330)
	)
	(segment
		(start 135.875 119.101367)
		(end 135.908378 119.097606)
		(width 0.15)
		(layer "In2.Cu")
		(net 330)
	)
	(segment
		(start 135.725 117.648633)
		(end 135.725 118.951367)
		(width 0.15)
		(layer "In2.Cu")
		(net 330)
	)
	(segment
		(start 135.608378 117.502394)
		(end 135.640082 117.513488)
		(width 0.15)
		(layer "In2.Cu")
		(net 330)
	)
	(segment
		(start 133.808378 118.57876)
		(end 133.840082 118.589854)
		(width 0.15)
		(layer "In2.Cu")
		(net 330)
	)
	(segment
		(start 135.668523 117.531359)
		(end 135.692274 117.55511)
		(width 0.15)
		(layer "In2.Cu")
		(net 330)
	)
	(segment
		(start 125.275 118.575)
		(end 133.775 118.575)
		(width 0.15)
		(layer "In2.Cu")
		(net 330)
	)
	(segment
		(start 139.274 122.014)
		(end 139.863999 121.424001)
		(width 0.15)
		(layer "F.Cu")
		(net 331)
	)
	(segment
		(start 107.775 112.175)
		(end 108.275 112.675)
		(width 0.15)
		(layer "F.Cu")
		(net 331)
	)
	(via
		(at 139.774 121.474)
		(size 0.5)
		(drill 0.2)
		(layers "F.Cu" "B.Cu")
		(net 331)
	)
	(via blind
		(at 108.275 112.675)
		(size 0.5)
		(drill 0.2)
		(layers "F.Cu" "In2.Cu")
		(net 331)
	)
	(segment
		(start 139.259 122.004)
		(end 139.259 121.989)
		(width 0.15)
		(layer "B.Cu")
		(net 331)
	)
	(segment
		(start 139.259 121.989)
		(end 139.774 121.474)
		(width 0.15)
		(layer "B.Cu")
		(net 331)
	)
	(segment
		(start 109.074959 115.374959)
		(end 107.750001 114.050001)
		(width 0.15)
		(layer "In2.Cu")
		(net 331)
	)
	(segment
		(start 125.248989 120.748989)
		(end 124.475 119.975)
		(width 0.15)
		(layer "In2.Cu")
		(net 331)
	)
	(segment
		(start 119.975 119.975)
		(end 115.37496 115.37496)
		(width 0.15)
		(layer "In2.Cu")
		(net 331)
	)
	(segment
		(start 115.37496 115.37496)
		(end 109.074959 115.374959)
		(width 0.15)
		(layer "In2.Cu")
		(net 331)
	)
	(segment
		(start 107.750001 113.199999)
		(end 108.275 112.675)
		(width 0.15)
		(layer "In2.Cu")
		(net 331)
	)
	(segment
		(start 139.774 121.474)
		(end 139.048989 120.748989)
		(width 0.15)
		(layer "In2.Cu")
		(net 331)
	)
	(segment
		(start 107.750001 114.050001)
		(end 107.750001 113.199999)
		(width 0.15)
		(layer "In2.Cu")
		(net 331)
	)
	(segment
		(start 124.475 119.975)
		(end 119.975 119.975)
		(width 0.15)
		(layer "In2.Cu")
		(net 331)
	)
	(segment
		(start 139.048989 120.748989)
		(end 125.248989 120.748989)
		(width 0.15)
		(layer "In2.Cu")
		(net 331)
	)
	(segment
		(start 76.072 158.44622)
		(end 76.072 156.982)
		(width 0.15)
		(layer "F.Cu")
		(net 332)
	)
	(segment
		(start 103.775 110.175)
		(end 104.275 109.675)
		(width 0.15)
		(layer "F.Cu")
		(net 332)
	)
	(segment
		(start 76.072 156.685633)
		(end 76.067425 156.681058)
		(width 0.15)
		(layer "F.Cu")
		(net 332)
	)
	(segment
		(start 76.072 158.44622)
		(end 76.072 156.685633)
		(width 0.15)
		(layer "F.Cu")
		(net 332)
	)
	(via blind
		(at 104.275 109.675)
		(size 0.5)
		(drill 0.2)
		(layers "F.Cu" "In5.Cu")
		(net 332)
	)
	(via
		(at 76.067425 156.681058)
		(size 0.5)
		(drill 0.2)
		(layers "F.Cu" "B.Cu")
		(net 332)
	)
	(segment
		(start 76.675 157.288633)
		(end 76.067425 156.681058)
		(width 0.15)
		(layer "B.Cu")
		(net 332)
	)
	(segment
		(start 76.675 157.99)
		(end 76.675 157.288633)
		(width 0.15)
		(layer "B.Cu")
		(net 332)
	)
	(segment
		(start 103.121449 108.875002)
		(end 90.613697 108.875002)
		(width 0.15)
		(layer "In5.Cu")
		(net 332)
	)
	(segment
		(start 103.921447 109.675)
		(end 103.121449 108.875002)
		(width 0.15)
		(layer "In5.Cu")
		(net 332)
	)
	(segment
		(start 104.275 109.675)
		(end 103.921447 109.675)
		(width 0.15)
		(layer "In5.Cu")
		(net 332)
	)
	(segment
		(start 77.950025 156.175697)
		(end 77.37572 156.750002)
		(width 0.15)
		(layer "In5.Cu")
		(net 332)
	)
	(segment
		(start 77.37572 156.750002)
		(end 76.136369 156.750002)
		(width 0.15)
		(layer "In5.Cu")
		(net 332)
	)
	(segment
		(start 90.613697 108.875002)
		(end 77.950025 121.538674)
		(width 0.15)
		(layer "In5.Cu")
		(net 332)
	)
	(segment
		(start 76.136369 156.750002)
		(end 76.067425 156.681058)
		(width 0.15)
		(layer "In5.Cu")
		(net 332)
	)
	(segment
		(start 77.950025 121.538674)
		(end 77.950025 156.175697)
		(width 0.15)
		(layer "In5.Cu")
		(net 332)
	)
	(segment
		(start 75.572 158.44622)
		(end 75.572 157.186233)
		(width 0.15)
		(layer "F.Cu")
		(net 333)
	)
	(segment
		(start 75.572 157.186233)
		(end 75.565868 157.180101)
		(width 0.15)
		(layer "F.Cu")
		(net 333)
	)
	(segment
		(start 104.775 110.175)
		(end 105.275 109.675)
		(width 0.15)
		(layer "F.Cu")
		(net 333)
	)
	(via blind
		(at 105.275 109.675)
		(size 0.5)
		(drill 0.2)
		(layers "F.Cu" "In5.Cu")
		(net 333)
	)
	(via
		(at 75.565868 157.180101)
		(size 0.5)
		(drill 0.2)
		(layers "F.Cu" "B.Cu")
		(net 333)
	)
	(segment
		(start 75.575 157.189233)
		(end 75.565868 157.180101)
		(width 0.15)
		(layer "B.Cu")
		(net 333)
	)
	(segment
		(start 75.575 157.99)
		(end 75.575 157.189233)
		(width 0.15)
		(layer "B.Cu")
		(net 333)
	)
	(segment
		(start 75.565868 157.180101)
		(end 77.369899 157.180101)
		(width 0.15)
		(layer "In5.Cu")
		(net 333)
	)
	(segment
		(start 90.702979 109.209999)
		(end 78.250036 121.662942)
		(width 0.15)
		(layer "In5.Cu")
		(net 333)
	)
	(segment
		(start 78.250036 121.662942)
		(end 78.250036 156.299964)
		(width 0.15)
		(layer "In5.Cu")
		(net 333)
	)
	(segment
		(start 103.009999 109.209999)
		(end 90.702979 109.209999)
		(width 0.15)
		(layer "In5.Cu")
		(net 333)
	)
	(segment
		(start 104.775 110.175)
		(end 103.975 110.175)
		(width 0.15)
		(layer "In5.Cu")
		(net 333)
	)
	(segment
		(start 103.975 110.175)
		(end 103.009999 109.209999)
		(width 0.15)
		(layer "In5.Cu")
		(net 333)
	)
	(segment
		(start 78.250036 156.299964)
		(end 77.369899 157.180101)
		(width 0.15)
		(layer "In5.Cu")
		(net 333)
	)
	(segment
		(start 105.275 109.675)
		(end 104.775 110.175)
		(width 0.15)
		(layer "In5.Cu")
		(net 333)
	)
	(segment
		(start 103.5125 159.275)
		(end 104.79 159.275)
		(width 0.2)
		(layer "F.Cu")
		(net 334)
	)
	(segment
		(start 77.072 155.85001)
		(end 76.99999 155.778)
		(width 0.15)
		(layer "F.Cu")
		(net 335)
	)
	(segment
		(start 103.775 109.175)
		(end 104.310883 108.639117)
		(width 0.15)
		(layer "F.Cu")
		(net 335)
	)
	(segment
		(start 77.072 155.778)
		(end 76.99999 155.778)
		(width 0.15)
		(layer "F.Cu")
		(net 335)
	)
	(segment
		(start 77.072 158.44622)
		(end 77.072 155.85001)
		(width 0.15)
		(layer "F.Cu")
		(net 335)
	)
	(via
		(at 76.99999 155.778)
		(size 0.5)
		(drill 0.2)
		(layers "F.Cu" "B.Cu")
		(net 335)
	)
	(via blind
		(at 104.310883 108.639117)
		(size 0.5)
		(drill 0.2)
		(layers "F.Cu" "In5.Cu")
		(net 335)
	)
	(segment
		(start 77.350003 121.290138)
		(end 77.350003 155.427987)
		(width 0.15)
		(layer "In5.Cu")
		(net 335)
	)
	(segment
		(start 103.946746 108.27498)
		(end 90.365161 108.27498)
		(width 0.15)
		(layer "In5.Cu")
		(net 335)
	)
	(segment
		(start 104.310883 108.639117)
		(end 103.946746 108.27498)
		(width 0.15)
		(layer "In5.Cu")
		(net 335)
	)
	(segment
		(start 90.365161 108.27498)
		(end 77.350003 121.290138)
		(width 0.15)
		(layer "In5.Cu")
		(net 335)
	)
	(segment
		(start 76.99999 155.778)
		(end 77.350003 155.427987)
		(width 0.15)
		(layer "In5.Cu")
		(net 335)
	)
	(segment
		(start 76.572 156.278)
		(end 76.575 156.275)
		(width 0.15)
		(layer "F.Cu")
		(net 336)
	)
	(segment
		(start 76.572 158.44622)
		(end 76.572 156.278)
		(width 0.15)
		(layer "F.Cu")
		(net 336)
	)
	(segment
		(start 104.775 109.175)
		(end 105.275 108.675)
		(width 0.15)
		(layer "F.Cu")
		(net 336)
	)
	(via
		(at 76.575 156.275)
		(size 0.5)
		(drill 0.2)
		(layers "F.Cu" "B.Cu")
		(net 336)
	)
	(via blind
		(at 105.275 108.675)
		(size 0.5)
		(drill 0.2)
		(layers "F.Cu" "In5.Cu")
		(net 336)
	)
	(segment
		(start 103.574991 108.574991)
		(end 90.489429 108.574991)
		(width 0.15)
		(layer "In5.Cu")
		(net 336)
	)
	(segment
		(start 77.650014 155.924265)
		(end 77.299279 156.275)
		(width 0.15)
		(layer "In5.Cu")
		(net 336)
	)
	(segment
		(start 76.575 156.275)
		(end 77.299279 156.275)
		(width 0.15)
		(layer "In5.Cu")
		(net 336)
	)
	(segment
		(start 90.489429 108.574991)
		(end 77.650014 121.414406)
		(width 0.15)
		(layer "In5.Cu")
		(net 336)
	)
	(segment
		(start 105.275 108.675)
		(end 104.750001 109.199999)
		(width 0.15)
		(layer "In5.Cu")
		(net 336)
	)
	(segment
		(start 104.199999 109.199999)
		(end 103.574991 108.574991)
		(width 0.15)
		(layer "In5.Cu")
		(net 336)
	)
	(segment
		(start 104.750001 109.199999)
		(end 104.199999 109.199999)
		(width 0.15)
		(layer "In5.Cu")
		(net 336)
	)
	(segment
		(start 77.650014 121.414406)
		(end 77.650014 155.924265)
		(width 0.15)
		(layer "In5.Cu")
		(net 336)
	)
	(segment
		(start 100.55 144.4)
		(end 100.55 140.748998)
		(width 0.1)
		(layer "F.Cu")
		(net 337)
	)
	(segment
		(start 100.175 144.775)
		(end 100.55 144.4)
		(width 0.1)
		(layer "F.Cu")
		(net 337)
	)
	(segment
		(start 100.55 140.748998)
		(end 100.525001 140.723999)
		(width 0.1)
		(layer "F.Cu")
		(net 337)
	)
	(segment
		(start 90.495 163.82)
		(end 91.065 164.39)
		(width 0.15)
		(layer "F.Cu")
		(net 338)
	)
	(segment
		(start 90.495 163.365)
		(end 90.495 163.82)
		(width 0.15)
		(layer "F.Cu")
		(net 338)
	)
	(segment
		(start 98.722851 93.975)
		(end 97.925 93.975)
		(width 0.15)
		(layer "F.Cu")
		(net 339)
	)
	(segment
		(start 92.775 127.175)
		(end 92.275 127.675)
		(width 0.15)
		(layer "F.Cu")
		(net 339)
	)
	(segment
		(start 92.775 123.175)
		(end 92.275 123.675)
		(width 0.15)
		(layer "F.Cu")
		(net 339)
	)
	(segment
		(start 101.852 99.076502)
		(end 101.852 99.724)
		(width 0.15)
		(layer "F.Cu")
		(net 339)
	)
	(segment
		(start 98.672851 95.975)
		(end 97.92 95.975)
		(width 0.15)
		(layer "F.Cu")
		(net 339)
	)
	(segment
		(start 106.425 97.975)
		(end 106.5 98.05)
		(width 0.15)
		(layer "F.Cu")
		(net 339)
	)
	(segment
		(start 92.25999 125.69001)
		(end 92.275 125.69001)
		(width 0.15)
		(layer "F.Cu")
		(net 339)
	)
	(segment
		(start 97.92 95.975)
		(end 97.9 95.955)
		(width 0.15)
		(layer "F.Cu")
		(net 339)
	)
	(segment
		(start 105.527149 97.975)
		(end 106.425 97.975)
		(width 0.15)
		(layer "F.Cu")
		(net 339)
	)
	(segment
		(start 97.875 98.475)
		(end 97.85 98.5)
		(width 0.15)
		(layer "F.Cu")
		(net 339)
	)
	(segment
		(start 98.672851 98.475)
		(end 97.875 98.475)
		(width 0.15)
		(layer "F.Cu")
		(net 339)
	)
	(segment
		(start 99.851 99.098502)
		(end 99.851 99.724)
		(width 0.15)
		(layer "F.Cu")
		(net 339)
	)
	(segment
		(start 91.775 120.175)
		(end 92.283178 120.683178)
		(width 0.15)
		(layer "F.Cu")
		(net 339)
	)
	(segment
		(start 91.775 124.175)
		(end 92.275 123.675)
		(width 0.15)
		(layer "F.Cu")
		(net 339)
	)
	(segment
		(start 92.283178 120.683178)
		(end 92.283178 121.65001)
		(width 0.15)
		(layer "F.Cu")
		(net 339)
	)
	(segment
		(start 91.775 126.175)
		(end 92.25999 125.69001)
		(width 0.15)
		(layer "F.Cu")
		(net 339)
	)
	(segment
		(start 91.775 122.175)
		(end 92.275 122.675)
		(width 0.15)
		(layer "F.Cu")
		(net 339)
	)
	(segment
		(start 101.85 99.074502)
		(end 101.852 99.076502)
		(width 0.15)
		(layer "F.Cu")
		(net 339)
	)
	(segment
		(start 99.875 99.074502)
		(end 99.851 99.098502)
		(width 0.15)
		(layer "F.Cu")
		(net 339)
	)
	(via
		(at 97.9 94)
		(size 0.5)
		(drill 0.2)
		(layers "F.Cu" "B.Cu")
		(net 339)
	)
	(via
		(at 79.875 73.92)
		(size 0.5)
		(drill 0.2)
		(layers "F.Cu" "B.Cu")
		(net 339)
	)
	(via
		(at 80.735 73.92)
		(size 0.5)
		(drill 0.2)
		(layers "F.Cu" "B.Cu")
		(net 339)
	)
	(via
		(at 79.895 74.93)
		(size 0.5)
		(drill 0.2)
		(layers "F.Cu" "B.Cu")
		(net 339)
	)
	(via
		(at 92.275 127.675)
		(size 0.5)
		(drill 0.2)
		(layers "F.Cu" "B.Cu")
		(net 339)
	)
	(via
		(at 99.875 99.074502)
		(size 0.5)
		(drill 0.2)
		(layers "F.Cu" "B.Cu")
		(net 339)
	)
	(via
		(at 117.7 127.1)
		(size 0.5)
		(drill 0.2)
		(layers "F.Cu" "B.Cu")
		(net 339)
	)
	(via
		(at 106.5 98.1)
		(size 0.5)
		(drill 0.2)
		(layers "F.Cu" "B.Cu")
		(net 339)
	)
	(via
		(at 117.1 127.1)
		(size 0.5)
		(drill 0.2)
		(layers "F.Cu" "B.Cu")
		(net 339)
	)
	(via
		(at 92.275 125.69001)
		(size 0.5)
		(drill 0.2)
		(layers "F.Cu" "B.Cu")
		(net 339)
	)
	(via
		(at 92.275 122.675)
		(size 0.5)
		(drill 0.2)
		(layers "F.Cu" "B.Cu")
		(net 339)
	)
	(via
		(at 92.283178 121.65001)
		(size 0.5)
		(drill 0.2)
		(layers "F.Cu" "B.Cu")
		(net 339)
	)
	(via
		(at 116.5 127.1)
		(size 0.5)
		(drill 0.2)
		(layers "F.Cu" "B.Cu")
		(net 339)
	)
	(via
		(at 101.85 99.074502)
		(size 0.5)
		(drill 0.2)
		(layers "F.Cu" "B.Cu")
		(net 339)
	)
	(via
		(at 92.275 123.675)
		(size 0.5)
		(drill 0.2)
		(layers "F.Cu" "B.Cu")
		(net 339)
	)
	(via
		(at 107.774 91.114)
		(size 0.5)
		(drill 0.2)
		(layers "F.Cu" "B.Cu")
		(net 339)
	)
	(via
		(at 97.85 98.5)
		(size 0.5)
		(drill 0.2)
		(layers "F.Cu" "B.Cu")
		(net 339)
	)
	(via
		(at 99.374 88.914)
		(size 0.5)
		(drill 0.2)
		(layers "F.Cu" "B.Cu")
		(net 339)
	)
	(via
		(at 97.9 95.955)
		(size 0.5)
		(drill 0.2)
		(layers "F.Cu" "B.Cu")
		(net 339)
	)
	(segment
		(start 106.5 98.05)
		(end 106.89 98.05)
		(width 0.15)
		(layer "B.Cu")
		(net 339)
	)
	(segment
		(start 109.074 91.114)
		(end 107.774 91.114)
		(width 0.2)
		(layer "B.Cu")
		(net 339)
	)
	(segment
		(start 97.84 94.06)
		(end 97.9 94)
		(width 0.15)
		(layer "B.Cu")
		(net 339)
	)
	(segment
		(start 92.258188 121.675)
		(end 92.283178 121.65001)
		(width 0.15)
		(layer "B.Cu")
		(net 339)
	)
	(segment
		(start 91.66 122.675)
		(end 92.275 122.675)
		(width 0.15)
		(layer "B.Cu")
		(net 339)
	)
	(segment
		(start 92.175 125.79001)
		(end 92.175 127.575)
		(width 0.2)
		(layer "B.Cu")
		(net 339)
	)
	(segment
		(start 101.85 99.074502)
		(end 102.110498 99.074502)
		(width 0.15)
		(layer "B.Cu")
		(net 339)
	)
	(segment
		(start 97.315 98.5)
		(end 97.175 98.64)
		(width 0.15)
		(layer "B.Cu")
		(net 339)
	)
	(segment
		(start 99.66 89.2)
		(end 99.374 88.914)
		(width 0.2)
		(layer "B.Cu")
		(net 339)
	)
	(segment
		(start 97.6 96.955)
		(end 97.9 96.655)
		(width 0.15)
		(layer "B.Cu")
		(net 339)
	)
	(segment
		(start 102.110498 99.074502)
		(end 102.6 98.585)
		(width 0.15)
		(layer "B.Cu")
		(net 339)
	)
	(segment
		(start 109.574 93.071)
		(end 109.574 91.614)
		(width 0.2)
		(layer "B.Cu")
		(net 339)
	)
	(segment
		(start 108.745 93.4)
		(end 109.245 93.4)
		(width 0.2)
		(layer "B.Cu")
		(net 339)
	)
	(segment
		(start 109.574 91.614)
		(end 109.074 91.114)
		(width 0.2)
		(layer "B.Cu")
		(net 339)
	)
	(segment
		(start 92.175 125.79001)
		(end 92.275 125.69001)
		(width 0.2)
		(layer "B.Cu")
		(net 339)
	)
	(segment
		(start 97.185 96.955)
		(end 97.6 96.955)
		(width 0.15)
		(layer "B.Cu")
		(net 339)
	)
	(segment
		(start 92.26 124.375)
		(end 92.26 123.69)
		(width 0.15)
		(layer "B.Cu")
		(net 339)
	)
	(segment
		(start 91.66 121.675)
		(end 92.258188 121.675)
		(width 0.15)
		(layer "B.Cu")
		(net 339)
	)
	(segment
		(start 97.175 94.06)
		(end 97.84 94.06)
		(width 0.15)
		(layer "B.Cu")
		(net 339)
	)
	(segment
		(start 97.85 98.5)
		(end 97.315 98.5)
		(width 0.15)
		(layer "B.Cu")
		(net 339)
	)
	(segment
		(start 109.245 93.4)
		(end 109.574 93.071)
		(width 0.2)
		(layer "B.Cu")
		(net 339)
	)
	(segment
		(start 99.875 98.93)
		(end 100.2 98.605)
		(width 0.15)
		(layer "B.Cu")
		(net 339)
	)
	(segment
		(start 99.875 99.074502)
		(end 99.875 98.93)
		(width 0.15)
		(layer "B.Cu")
		(net 339)
	)
	(segment
		(start 92.26 123.69)
		(end 92.275 123.675)
		(width 0.15)
		(layer "B.Cu")
		(net 339)
	)
	(segment
		(start 93.59 122.675)
		(end 92.275 122.675)
		(width 0.15)
		(layer "B.Cu")
		(net 339)
	)
	(segment
		(start 100.2 98.605)
		(end 101.14 98.605)
		(width 0.15)
		(layer "B.Cu")
		(net 339)
	)
	(segment
		(start 107.24 98.4)
		(end 107.24 99.35)
		(width 0.15)
		(layer "B.Cu")
		(net 339)
	)
	(segment
		(start 97.175 98.64)
		(end 97.175 99.49)
		(width 0.15)
		(layer "B.Cu")
		(net 339)
	)
	(segment
		(start 99.66 89.77)
		(end 99.66 89.2)
		(width 0.2)
		(layer "B.Cu")
		(net 339)
	)
	(segment
		(start 97.9 96.655)
		(end 97.9 95.955)
		(width 0.15)
		(layer "B.Cu")
		(net 339)
	)
	(segment
		(start 106.89 98.05)
		(end 107.24 98.4)
		(width 0.15)
		(layer "B.Cu")
		(net 339)
	)
	(segment
		(start 73.635 87.867)
		(end 74.959 87.867)
		(width 0.15)
		(layer "F.Cu")
		(net 340)
	)
	(segment
		(start 74.959 87.867)
		(end 74.969 87.857)
		(width 0.15)
		(layer "F.Cu")
		(net 340)
	)
	(segment
		(start 103.5125 160.275)
		(end 104.79 160.275)
		(width 0.15)
		(layer "F.Cu")
		(net 341)
	)
	(segment
		(start 106.775 123.175)
		(end 106.275 122.675)
		(width 0.15)
		(layer "F.Cu")
		(net 342)
	)
	(via
		(at 106.275 122.675)
		(size 0.5)
		(drill 0.2)
		(layers "F.Cu" "B.Cu")
		(net 342)
	)
	(segment
		(start 107.275 122.74)
		(end 106.34 122.74)
		(width 0.2)
		(layer "B.Cu")
		(net 342)
	)
	(segment
		(start 106.34 122.74)
		(end 106.275 122.675)
		(width 0.2)
		(layer "B.Cu")
		(net 342)
	)
	(segment
		(start 88.975 90.775)
		(end 89.49 90.775)
		(width 0.15)
		(layer "F.Cu")
		(net 343)
	)
	(segment
		(start 87.68 90.185)
		(end 88.385 90.185)
		(width 0.15)
		(layer "F.Cu")
		(net 343)
	)
	(segment
		(start 88.385 90.185)
		(end 88.975 90.775)
		(width 0.15)
		(layer "F.Cu")
		(net 343)
	)
	(segment
		(start 105.775 112.175)
		(end 106.275 111.675)
		(width 0.15)
		(layer "F.Cu")
		(net 344)
	)
	(via blind
		(at 106.275 111.675)
		(size 0.5)
		(drill 0.2)
		(layers "F.Cu" "In5.Cu")
		(net 344)
	)
	(via
		(at 76.775 146.175)
		(size 0.5)
		(drill 0.2)
		(layers "F.Cu" "B.Cu")
		(net 344)
	)
	(segment
		(start 77.8675 146.175)
		(end 76.775 146.175)
		(width 0.15)
		(layer "B.Cu")
		(net 344)
	)
	(segment
		(start 78.46 147.175)
		(end 78.46 148.375)
		(width 0.15)
		(layer "B.Cu")
		(net 344)
	)
	(segment
		(start 78.46 146.7675)
		(end 77.8675 146.175)
		(width 0.15)
		(layer "B.Cu")
		(net 344)
	)
	(segment
		(start 78.46 147.175)
		(end 78.46 146.7675)
		(width 0.15)
		(layer "B.Cu")
		(net 344)
	)
	(segment
		(start 106.750001 111.199999)
		(end 106.750001 108.330001)
		(width 0.15)
		(layer "In5.Cu")
		(net 344)
	)
	(segment
		(start 77.09 121.125862)
		(end 77.09 145.86)
		(width 0.15)
		(layer "In5.Cu")
		(net 344)
	)
	(segment
		(start 106.275 111.675)
		(end 106.750001 111.199999)
		(width 0.15)
		(layer "In5.Cu")
		(net 344)
	)
	(segment
		(start 90.240893 107.974969)
		(end 77.09 121.125862)
		(width 0.15)
		(layer "In5.Cu")
		(net 344)
	)
	(segment
		(start 106.750001 108.330001)
		(end 106.394969 107.974969)
		(width 0.15)
		(layer "In5.Cu")
		(net 344)
	)
	(segment
		(start 106.394969 107.974969)
		(end 90.240893 107.974969)
		(width 0.15)
		(layer "In5.Cu")
		(net 344)
	)
	(segment
		(start 77.09 145.86)
		(end 76.775 146.175)
		(width 0.15)
		(layer "In5.Cu")
		(net 344)
	)
	(segment
		(start 105.527149 92.872851)
		(end 105.9 92.5)
		(width 0.15)
		(layer "F.Cu")
		(net 345)
	)
	(segment
		(start 105.527149 93.475)
		(end 105.527149 92.872851)
		(width 0.15)
		(layer "F.Cu")
		(net 345)
	)
	(via
		(at 105.9 92.5)
		(size 0.5)
		(drill 0.2)
		(layers "F.Cu" "B.Cu")
		(net 345)
	)
	(segment
		(start 105.9 92.5)
		(end 106.2 92.2)
		(width 0.15)
		(layer "B.Cu")
		(net 345)
	)
	(segment
		(start 106.2 92.2)
		(end 107.19 92.2)
		(width 0.15)
		(layer "B.Cu")
		(net 345)
	)
	(segment
		(start 130.85 90.8875)
		(end 130.85 90.2125)
		(width 0.1)
		(layer "F.Cu")
		(net 346)
	)
	(segment
		(start 130.85 90.2125)
		(end 130.35 89.7125)
		(width 0.1)
		(layer "F.Cu")
		(net 346)
	)
	(segment
		(start 130.35 89.7125)
		(end 127.935 89.7125)
		(width 0.1)
		(layer "F.Cu")
		(net 346)
	)
	(segment
		(start 88.45 75.35)
		(end 89.05 75.95)
		(width 0.15)
		(layer "F.Cu")
		(net 347)
	)
	(segment
		(start 89.05 75.95)
		(end 89.465 75.95)
		(width 0.15)
		(layer "F.Cu")
		(net 347)
	)
	(segment
		(start 87.645 75.35)
		(end 88.45 75.35)
		(width 0.15)
		(layer "F.Cu")
		(net 347)
	)
	(segment
		(start 128.683333 90.845833)
		(end 127.935 90.845833)
		(width 0.1)
		(layer "F.Cu")
		(net 348)
	)
	(segment
		(start 130.1875 91.55)
		(end 129.3875 91.55)
		(width 0.1)
		(layer "F.Cu")
		(net 348)
	)
	(segment
		(start 129.3875 91.55)
		(end 128.683333 90.845833)
		(width 0.1)
		(layer "F.Cu")
		(net 348)
	)
	(segment
		(start 128.005834 92.05)
		(end 127.935 91.979166)
		(width 0.1)
		(layer "F.Cu")
		(net 349)
	)
	(segment
		(start 130.1875 92.05)
		(end 128.005834 92.05)
		(width 0.1)
		(layer "F.Cu")
		(net 349)
	)
	(segment
		(start 78.572 154.34712)
		(end 78.572 149.972)
		(width 0.15)
		(layer "F.Cu")
		(net 350)
	)
	(segment
		(start 78.572 149.972)
		(end 76.775 148.175)
		(width 0.15)
		(layer "F.Cu")
		(net 350)
	)
	(via
		(at 76.775 148.175)
		(size 0.5)
		(drill 0.2)
		(layers "F.Cu" "B.Cu")
		(net 350)
	)
	(segment
		(start 77.475 148.175)
		(end 76.775 148.175)
		(width 0.15)
		(layer "B.Cu")
		(net 350)
	)
	(segment
		(start 123.375 169.046)
		(end 123.375 169.781778)
		(width 0.15)
		(layer "F.Cu")
		(net 351)
	)
	(segment
		(start 125.643222 172.05)
		(end 126.273222 172.05)
		(width 0.15)
		(layer "F.Cu")
		(net 351)
	)
	(segment
		(start 129.19 177.155)
		(end 129.19 175.864999)
		(width 0.15)
		(layer "F.Cu")
		(net 351)
	)
	(segment
		(start 129.365 175.689999)
		(end 129.365 175.141778)
		(width 0.15)
		(layer "F.Cu")
		(net 351)
	)
	(segment
		(start 129.19 175.864999)
		(end 129.365 175.689999)
		(width 0.15)
		(layer "F.Cu")
		(net 351)
	)
	(segment
		(start 123.375 169.781778)
		(end 125.643222 172.05)
		(width 0.15)
		(layer "F.Cu")
		(net 351)
	)
	(segment
		(start 126.273222 172.05)
		(end 129.365 175.141778)
		(width 0.15)
		(layer "F.Cu")
		(net 351)
	)
	(segment
		(start 122.995 168.666)
		(end 123.375 169.046)
		(width 0.15)
		(layer "F.Cu")
		(net 351)
	)
	(segment
		(start 131.165 174.571778)
		(end 131.165 175.689999)
		(width 0.15)
		(layer "F.Cu")
		(net 352)
	)
	(segment
		(start 126.375 169.781778)
		(end 131.165 174.571778)
		(width 0.15)
		(layer "F.Cu")
		(net 352)
	)
	(segment
		(start 125.995 168.666)
		(end 126.375 169.046)
		(width 0.15)
		(layer "F.Cu")
		(net 352)
	)
	(segment
		(start 130.99 175.864999)
		(end 130.99 177.155)
		(width 0.15)
		(layer "F.Cu")
		(net 352)
	)
	(segment
		(start 131.165 175.689999)
		(end 130.99 175.864999)
		(width 0.15)
		(layer "F.Cu")
		(net 352)
	)
	(segment
		(start 126.375 169.046)
		(end 126.375 169.781778)
		(width 0.15)
		(layer "F.Cu")
		(net 352)
	)
	(segment
		(start 129.79 177.155)
		(end 129.79 175.864999)
		(width 0.15)
		(layer "F.Cu")
		(net 353)
	)
	(segment
		(start 129.79 175.864999)
		(end 129.615 175.689999)
		(width 0.15)
		(layer "F.Cu")
		(net 353)
	)
	(segment
		(start 124.005 168.666)
		(end 123.625 169.046)
		(width 0.15)
		(layer "F.Cu")
		(net 353)
	)
	(segment
		(start 125.746778 171.8)
		(end 126.376778 171.8)
		(width 0.15)
		(layer "F.Cu")
		(net 353)
	)
	(segment
		(start 123.625 169.678222)
		(end 125.746778 171.8)
		(width 0.15)
		(layer "F.Cu")
		(net 353)
	)
	(segment
		(start 123.625 169.046)
		(end 123.625 169.678222)
		(width 0.15)
		(layer "F.Cu")
		(net 353)
	)
	(segment
		(start 126.376778 171.8)
		(end 129.615 175.038222)
		(width 0.15)
		(layer "F.Cu")
		(net 353)
	)
	(segment
		(start 129.615 175.689999)
		(end 129.615 175.038222)
		(width 0.15)
		(layer "F.Cu")
		(net 353)
	)
	(segment
		(start 131.415 174.468222)
		(end 131.415 175.689999)
		(width 0.15)
		(layer "F.Cu")
		(net 354)
	)
	(segment
		(start 126.625 169.678222)
		(end 131.415 174.468222)
		(width 0.15)
		(layer "F.Cu")
		(net 354)
	)
	(segment
		(start 131.59 175.864999)
		(end 131.59 177.155)
		(width 0.15)
		(layer "F.Cu")
		(net 354)
	)
	(segment
		(start 131.415 175.689999)
		(end 131.59 175.864999)
		(width 0.15)
		(layer "F.Cu")
		(net 354)
	)
	(segment
		(start 126.625 169.046)
		(end 126.625 169.678222)
		(width 0.15)
		(layer "F.Cu")
		(net 354)
	)
	(segment
		(start 127.005 168.666)
		(end 126.625 169.046)
		(width 0.15)
		(layer "F.Cu")
		(net 354)
	)
	(segment
		(start 129.3755 169.0455)
		(end 129.3755 170.092278)
		(width 0.15)
		(layer "F.Cu")
		(net 355)
	)
	(segment
		(start 129.3755 170.092278)
		(end 132.965 173.681778)
		(width 0.15)
		(layer "F.Cu")
		(net 355)
	)
	(segment
		(start 132.965 175.689999)
		(end 132.79 175.864999)
		(width 0.15)
		(layer "F.Cu")
		(net 355)
	)
	(segment
		(start 128.996 168.666)
		(end 129.3755 169.0455)
		(width 0.15)
		(layer "F.Cu")
		(net 355)
	)
	(segment
		(start 132.79 175.864999)
		(end 132.79 177.155)
		(width 0.15)
		(layer "F.Cu")
		(net 355)
	)
	(segment
		(start 132.965 173.681778)
		(end 132.965 175.689999)
		(width 0.15)
		(layer "F.Cu")
		(net 355)
	)
	(segment
		(start 131.995 168.666)
		(end 132.375 169.046)
		(width 0.15)
		(layer "F.Cu")
		(net 356)
	)
	(segment
		(start 134.765 175.689999)
		(end 134.59 175.864999)
		(width 0.15)
		(layer "F.Cu")
		(net 356)
	)
	(segment
		(start 134.59 175.864999)
		(end 134.59 177.155)
		(width 0.15)
		(layer "F.Cu")
		(net 356)
	)
	(segment
		(start 132.375 169.046)
		(end 132.375 169.981778)
		(width 0.15)
		(layer "F.Cu")
		(net 356)
	)
	(segment
		(start 132.375 169.981778)
		(end 134.765 172.371778)
		(width 0.15)
		(layer "F.Cu")
		(net 356)
	)
	(segment
		(start 134.765 172.371778)
		(end 134.765 175.689999)
		(width 0.15)
		(layer "F.Cu")
		(net 356)
	)
	(segment
		(start 133.215 175.689999)
		(end 133.39 175.864999)
		(width 0.15)
		(layer "F.Cu")
		(net 357)
	)
	(segment
		(start 129.6255 169.988722)
		(end 133.215 173.578222)
		(width 0.15)
		(layer "F.Cu")
		(net 357)
	)
	(segment
		(start 133.39 175.864999)
		(end 133.39 177.155)
		(width 0.15)
		(layer "F.Cu")
		(net 357)
	)
	(segment
		(start 129.6255 169.0455)
		(end 129.6255 169.988722)
		(width 0.15)
		(layer "F.Cu")
		(net 357)
	)
	(segment
		(start 130.005 168.666)
		(end 129.6255 169.0455)
		(width 0.15)
		(layer "F.Cu")
		(net 357)
	)
	(segment
		(start 133.215 173.578222)
		(end 133.215 175.689999)
		(width 0.15)
		(layer "F.Cu")
		(net 357)
	)
	(segment
		(start 132.625 169.878222)
		(end 135.015 172.268222)
		(width 0.15)
		(layer "F.Cu")
		(net 358)
	)
	(segment
		(start 132.625 169.046)
		(end 132.625 169.878222)
		(width 0.15)
		(layer "F.Cu")
		(net 358)
	)
	(segment
		(start 133.005 168.666)
		(end 132.625 169.046)
		(width 0.15)
		(layer "F.Cu")
		(net 358)
	)
	(segment
		(start 135.19 175.864999)
		(end 135.19 177.155)
		(width 0.15)
		(layer "F.Cu")
		(net 358)
	)
	(segment
		(start 135.015 172.268222)
		(end 135.015 175.689999)
		(width 0.15)
		(layer "F.Cu")
		(net 358)
	)
	(segment
		(start 135.015 175.689999)
		(end 135.19 175.864999)
		(width 0.15)
		(layer "F.Cu")
		(net 358)
	)
	(segment
		(start 121.75 165.912501)
		(end 121.75 164.75)
		(width 0.15)
		(layer "F.Cu")
		(net 359)
	)
	(segment
		(start 127.565 175.281778)
		(end 121.875 169.591778)
		(width 0.15)
		(layer "F.Cu")
		(net 359)
	)
	(segment
		(start 127.565 175.689999)
		(end 127.565 175.281778)
		(width 0.15)
		(layer "F.Cu")
		(net 359)
	)
	(segment
		(start 121.875 166.037501)
		(end 121.75 165.912501)
		(width 0.15)
		(layer "F.Cu")
		(net 359)
	)
	(segment
		(start 127.39 177.155)
		(end 127.39 175.864999)
		(width 0.15)
		(layer "F.Cu")
		(net 359)
	)
	(segment
		(start 127.39 175.864999)
		(end 127.565 175.689999)
		(width 0.15)
		(layer "F.Cu")
		(net 359)
	)
	(segment
		(start 121.875 169.591778)
		(end 121.875 166.037501)
		(width 0.15)
		(layer "F.Cu")
		(net 359)
	)
	(segment
		(start 127.99 175.864999)
		(end 127.815 175.689999)
		(width 0.15)
		(layer "F.Cu")
		(net 360)
	)
	(segment
		(start 127.815 175.178222)
		(end 122.125 169.488222)
		(width 0.15)
		(layer "F.Cu")
		(net 360)
	)
	(segment
		(start 127.815 175.689999)
		(end 127.815 175.178222)
		(width 0.15)
		(layer "F.Cu")
		(net 360)
	)
	(segment
		(start 127.99 177.155)
		(end 127.99 175.864999)
		(width 0.15)
		(layer "F.Cu")
		(net 360)
	)
	(segment
		(start 122.125 169.488222)
		(end 122.125 166.037501)
		(width 0.15)
		(layer "F.Cu")
		(net 360)
	)
	(segment
		(start 122.25 165.912501)
		(end 122.25 164.75)
		(width 0.15)
		(layer "F.Cu")
		(net 360)
	)
	(segment
		(start 122.125 166.037501)
		(end 122.25 165.912501)
		(width 0.15)
		(layer "F.Cu")
		(net 360)
	)
	(segment
		(start 124.75 164.75)
		(end 124.75 164.125)
		(width 0.11)
		(layer "F.Cu")
		(net 361)
	)
	(segment
		(start 124.695 163.309998)
		(end 124.875 163.489998)
		(width 0.15)
		(layer "F.Cu")
		(net 361)
	)
	(segment
		(start 124.875 164)
		(end 124.75 164.125)
		(width 0.15)
		(layer "F.Cu")
		(net 361)
	)
	(segment
		(start 124.875 163.489998)
		(end 124.875 164)
		(width 0.15)
		(layer "F.Cu")
		(net 361)
	)
	(via
		(at 124.695 163.309998)
		(size 0.5)
		(drill 0.2)
		(layers "F.Cu" "B.Cu")
		(net 361)
	)
	(segment
		(start 129.365 173.371778)
		(end 129.365 175.689999)
		(width 0.15)
		(layer "B.Cu")
		(net 361)
	)
	(segment
		(start 129.19 175.864999)
		(end 129.19 177.155)
		(width 0.15)
		(layer "B.Cu")
		(net 361)
	)
	(segment
		(start 129.365 175.689999)
		(end 129.19 175.864999)
		(width 0.15)
		(layer "B.Cu")
		(net 361)
	)
	(segment
		(start 124.695 163.309998)
		(end 124.875 163.489998)
		(width 0.15)
		(layer "B.Cu")
		(net 361)
	)
	(segment
		(start 124.875 163.489998)
		(end 124.875 168.881778)
		(width 0.15)
		(layer "B.Cu")
		(net 361)
	)
	(segment
		(start 124.875 168.881778)
		(end 129.365 173.371778)
		(width 0.15)
		(layer "B.Cu")
		(net 361)
	)
	(segment
		(start 129.19 177.345)
		(end 129.19 176.475)
		(width 0.11)
		(layer "B.Cu")
		(net 361)
	)
	(segment
		(start 125.25 164.75)
		(end 125.25 164.125)
		(width 0.11)
		(layer "F.Cu")
		(net 362)
	)
	(segment
		(start 125.305 163.309998)
		(end 125.125 163.489998)
		(width 0.15)
		(layer "F.Cu")
		(net 362)
	)
	(segment
		(start 125.125 164)
		(end 125.25 164.125)
		(width 0.15)
		(layer "F.Cu")
		(net 362)
	)
	(segment
		(start 125.125 163.489998)
		(end 125.125 164)
		(width 0.15)
		(layer "F.Cu")
		(net 362)
	)
	(via
		(at 125.305 163.309998)
		(size 0.5)
		(drill 0.2)
		(layers "F.Cu" "B.Cu")
		(net 362)
	)
	(segment
		(start 129.79 175.864999)
		(end 129.79 177.155)
		(width 0.15)
		(layer "B.Cu")
		(net 362)
	)
	(segment
		(start 125.305 163.309998)
		(end 125.125 163.489998)
		(width 0.15)
		(layer "B.Cu")
		(net 362)
	)
	(segment
		(start 125.125 163.489998)
		(end 125.125 168.778222)
		(width 0.15)
		(layer "B.Cu")
		(net 362)
	)
	(segment
		(start 129.615 173.268222)
		(end 129.615 175.689999)
		(width 0.15)
		(layer "B.Cu")
		(net 362)
	)
	(segment
		(start 129.615 175.689999)
		(end 129.79 175.864999)
		(width 0.15)
		(layer "B.Cu")
		(net 362)
	)
	(segment
		(start 125.125 168.778222)
		(end 129.615 173.268222)
		(width 0.15)
		(layer "B.Cu")
		(net 362)
	)
	(segment
		(start 129.79 177.345)
		(end 129.79 176.475)
		(width 0.11)
		(layer "B.Cu")
		(net 362)
	)
	(segment
		(start 127.875 164)
		(end 127.75 164.125)
		(width 0.15)
		(layer "F.Cu")
		(net 363)
	)
	(segment
		(start 127.75 164.125)
		(end 127.75 164.75)
		(width 0.15)
		(layer "F.Cu")
		(net 363)
	)
	(segment
		(start 127.875 163.489998)
		(end 127.875 164)
		(width 0.15)
		(layer "F.Cu")
		(net 363)
	)
	(segment
		(start 127.695 163.309998)
		(end 127.875 163.489998)
		(width 0.15)
		(layer "F.Cu")
		(net 363)
	)
	(segment
		(start 127.75 164.75)
		(end 127.75 164.125)
		(width 0.11)
		(layer "F.Cu")
		(net 363)
	)
	(via
		(at 127.695 163.309998)
		(size 0.5)
		(drill 0.2)
		(layers "F.Cu" "B.Cu")
		(net 363)
	)
	(segment
		(start 127.695 163.309998)
		(end 127.875 163.489998)
		(width 0.15)
		(layer "B.Cu")
		(net 363)
	)
	(segment
		(start 130.99 175.864999)
		(end 130.99 177.155)
		(width 0.15)
		(layer "B.Cu")
		(net 363)
	)
	(segment
		(start 131.165 171.701778)
		(end 131.165 175.689999)
		(width 0.15)
		(layer "B.Cu")
		(net 363)
	)
	(segment
		(start 127.875 163.489998)
		(end 127.875 168.411778)
		(width 0.15)
		(layer "B.Cu")
		(net 363)
	)
	(segment
		(start 127.875 168.411778)
		(end 131.165 171.701778)
		(width 0.15)
		(layer "B.Cu")
		(net 363)
	)
	(segment
		(start 131.165 175.689999)
		(end 130.99 175.864999)
		(width 0.15)
		(layer "B.Cu")
		(net 363)
	)
	(segment
		(start 130.99 177.345)
		(end 130.99 176.475)
		(width 0.11)
		(layer "B.Cu")
		(net 363)
	)
	(segment
		(start 128.125 163.489998)
		(end 128.125 164)
		(width 0.15)
		(layer "F.Cu")
		(net 364)
	)
	(segment
		(start 128.305 163.309998)
		(end 128.125 163.489998)
		(width 0.15)
		(layer "F.Cu")
		(net 364)
	)
	(segment
		(start 128.25 164.125)
		(end 128.25 164.75)
		(width 0.15)
		(layer "F.Cu")
		(net 364)
	)
	(segment
		(start 128.125 164)
		(end 128.25 164.125)
		(width 0.15)
		(layer "F.Cu")
		(net 364)
	)
	(segment
		(start 128.25 164.75)
		(end 128.25 164.125)
		(width 0.11)
		(layer "F.Cu")
		(net 364)
	)
	(via
		(at 128.305 163.309998)
		(size 0.5)
		(drill 0.2)
		(layers "F.Cu" "B.Cu")
		(net 364)
	)
	(segment
		(start 131.59 175.864999)
		(end 131.59 177.155)
		(width 0.15)
		(layer "B.Cu")
		(net 364)
	)
	(segment
		(start 131.415 175.689999)
		(end 131.59 175.864999)
		(width 0.15)
		(layer "B.Cu")
		(net 364)
	)
	(segment
		(start 128.125 168.308222)
		(end 131.415 171.598222)
		(width 0.15)
		(layer "B.Cu")
		(net 364)
	)
	(segment
		(start 131.415 171.598222)
		(end 131.415 175.689999)
		(width 0.15)
		(layer "B.Cu")
		(net 364)
	)
	(segment
		(start 128.125 163.489998)
		(end 128.125 168.308222)
		(width 0.15)
		(layer "B.Cu")
		(net 364)
	)
	(segment
		(start 128.305 163.309998)
		(end 128.125 163.489998)
		(width 0.15)
		(layer "B.Cu")
		(net 364)
	)
	(segment
		(start 131.59 177.345)
		(end 131.59 176.475)
		(width 0.11)
		(layer "B.Cu")
		(net 364)
	)
	(segment
		(start 130.875 164)
		(end 130.75 164.125)
		(width 0.15)
		(layer "F.Cu")
		(net 365)
	)
	(segment
		(start 130.695 163.309998)
		(end 130.875 163.489998)
		(width 0.15)
		(layer "F.Cu")
		(net 365)
	)
	(segment
		(start 130.75 164.125)
		(end 130.75 164.75)
		(width 0.15)
		(layer "F.Cu")
		(net 365)
	)
	(segment
		(start 130.875 163.489998)
		(end 130.875 164)
		(width 0.15)
		(layer "F.Cu")
		(net 365)
	)
	(segment
		(start 130.75 164.75)
		(end 130.75 164.125)
		(width 0.11)
		(layer "F.Cu")
		(net 365)
	)
	(via
		(at 130.695 163.309998)
		(size 0.5)
		(drill 0.2)
		(layers "F.Cu" "B.Cu")
		(net 365)
	)
	(segment
		(start 132.79 175.864999)
		(end 132.79 177.155)
		(width 0.15)
		(layer "B.Cu")
		(net 365)
	)
	(segment
		(start 132.965 170.581778)
		(end 132.965 175.689999)
		(width 0.15)
		(layer "B.Cu")
		(net 365)
	)
	(segment
		(start 132.965 175.689999)
		(end 132.79 175.864999)
		(width 0.15)
		(layer "B.Cu")
		(net 365)
	)
	(segment
		(start 130.695 163.309998)
		(end 130.875 163.489998)
		(width 0.15)
		(layer "B.Cu")
		(net 365)
	)
	(segment
		(start 130.875 163.489998)
		(end 130.875 168.491778)
		(width 0.15)
		(layer "B.Cu")
		(net 365)
	)
	(segment
		(start 130.875 168.491778)
		(end 132.965 170.581778)
		(width 0.15)
		(layer "B.Cu")
		(net 365)
	)
	(segment
		(start 132.79 177.345)
		(end 132.79 176.475)
		(width 0.11)
		(layer "B.Cu")
		(net 365)
	)
	(segment
		(start 131.125 163.489998)
		(end 131.125 164)
		(width 0.15)
		(layer "F.Cu")
		(net 366)
	)
	(segment
		(start 131.25 164.125)
		(end 131.25 164.75)
		(width 0.15)
		(layer "F.Cu")
		(net 366)
	)
	(segment
		(start 131.125 164)
		(end 131.25 164.125)
		(width 0.15)
		(layer "F.Cu")
		(net 366)
	)
	(segment
		(start 131.305 163.309998)
		(end 131.125 163.489998)
		(width 0.15)
		(layer "F.Cu")
		(net 366)
	)
	(segment
		(start 131.25 164.75)
		(end 131.25 164.125)
		(width 0.11)
		(layer "F.Cu")
		(net 366)
	)
	(via
		(at 131.305 163.309998)
		(size 0.5)
		(drill 0.2)
		(layers "F.Cu" "B.Cu")
		(net 366)
	)
	(segment
		(start 133.215 170.478222)
		(end 133.215 175.689999)
		(width 0.15)
		(layer "B.Cu")
		(net 366)
	)
	(segment
		(start 133.215 175.689999)
		(end 133.39 175.864999)
		(width 0.15)
		(layer "B.Cu")
		(net 366)
	)
	(segment
		(start 131.305 163.309998)
		(end 131.125 163.489998)
		(width 0.15)
		(layer "B.Cu")
		(net 366)
	)
	(segment
		(start 133.39 175.864999)
		(end 133.39 177.155)
		(width 0.15)
		(layer "B.Cu")
		(net 366)
	)
	(segment
		(start 131.125 163.489998)
		(end 131.125 168.388222)
		(width 0.15)
		(layer "B.Cu")
		(net 366)
	)
	(segment
		(start 131.125 168.388222)
		(end 133.215 170.478222)
		(width 0.15)
		(layer "B.Cu")
		(net 366)
	)
	(segment
		(start 133.39 177.345)
		(end 133.39 176.475)
		(width 0.11)
		(layer "B.Cu")
		(net 366)
	)
	(segment
		(start 133.875 164)
		(end 133.75 164.125)
		(width 0.15)
		(layer "F.Cu")
		(net 367)
	)
	(segment
		(start 133.695 163.309998)
		(end 133.875 163.489998)
		(width 0.15)
		(layer "F.Cu")
		(net 367)
	)
	(segment
		(start 133.75 164.125)
		(end 133.75 164.75)
		(width 0.15)
		(layer "F.Cu")
		(net 367)
	)
	(segment
		(start 133.875 163.489998)
		(end 133.875 164)
		(width 0.15)
		(layer "F.Cu")
		(net 367)
	)
	(segment
		(start 133.75 164.75)
		(end 133.75 164.125)
		(width 0.11)
		(layer "F.Cu")
		(net 367)
	)
	(via
		(at 133.695 163.309998)
		(size 0.5)
		(drill 0.2)
		(layers "F.Cu" "B.Cu")
		(net 367)
	)
	(segment
		(start 133.695 163.309998)
		(end 133.875 163.489998)
		(width 0.15)
		(layer "B.Cu")
		(net 367)
	)
	(segment
		(start 134.765 175.689999)
		(end 134.59 175.864999)
		(width 0.15)
		(layer "B.Cu")
		(net 367)
	)
	(segment
		(start 134.59 175.864999)
		(end 134.59 177.155)
		(width 0.15)
		(layer "B.Cu")
		(net 367)
	)
	(segment
		(start 133.875 163.489998)
		(end 133.875 169.471778)
		(width 0.15)
		(layer "B.Cu")
		(net 367)
	)
	(segment
		(start 134.765 170.361778)
		(end 134.765 175.689999)
		(width 0.15)
		(layer "B.Cu")
		(net 367)
	)
	(segment
		(start 133.875 169.471778)
		(end 134.765 170.361778)
		(width 0.15)
		(layer "B.Cu")
		(net 367)
	)
	(segment
		(start 134.125 163.489998)
		(end 134.125 164)
		(width 0.15)
		(layer "F.Cu")
		(net 368)
	)
	(segment
		(start 134.305 163.309998)
		(end 134.125 163.489998)
		(width 0.15)
		(layer "F.Cu")
		(net 368)
	)
	(segment
		(start 134.25 164.125)
		(end 134.25 164.75)
		(width 0.15)
		(layer "F.Cu")
		(net 368)
	)
	(segment
		(start 134.125 164)
		(end 134.25 164.125)
		(width 0.15)
		(layer "F.Cu")
		(net 368)
	)
	(segment
		(start 134.25 164.75)
		(end 134.25 164.125)
		(width 0.11)
		(layer "F.Cu")
		(net 368)
	)
	(via
		(at 134.305 163.309998)
		(size 0.5)
		(drill 0.2)
		(layers "F.Cu" "B.Cu")
		(net 368)
	)
	(segment
		(start 134.125 169.368222)
		(end 135.015 170.258222)
		(width 0.15)
		(layer "B.Cu")
		(net 368)
	)
	(segment
		(start 135.015 175.689999)
		(end 135.19 175.864999)
		(width 0.15)
		(layer "B.Cu")
		(net 368)
	)
	(segment
		(start 134.305 163.309998)
		(end 134.125 163.489998)
		(width 0.15)
		(layer "B.Cu")
		(net 368)
	)
	(segment
		(start 134.125 163.489998)
		(end 134.125 169.368222)
		(width 0.15)
		(layer "B.Cu")
		(net 368)
	)
	(segment
		(start 135.19 175.864999)
		(end 135.19 177.155)
		(width 0.15)
		(layer "B.Cu")
		(net 368)
	)
	(segment
		(start 135.015 170.258222)
		(end 135.015 175.689999)
		(width 0.15)
		(layer "B.Cu")
		(net 368)
	)
	(segment
		(start 123.375 166.037501)
		(end 123.375 167.316)
		(width 0.15)
		(layer "F.Cu")
		(net 369)
	)
	(segment
		(start 123.25 164.75)
		(end 123.25 165.912501)
		(width 0.15)
		(layer "F.Cu")
		(net 369)
	)
	(segment
		(start 123.25 165.912501)
		(end 123.375 166.037501)
		(width 0.15)
		(layer "F.Cu")
		(net 369)
	)
	(segment
		(start 123.375 167.316)
		(end 122.995 167.696)
		(width 0.15)
		(layer "F.Cu")
		(net 369)
	)
	(segment
		(start 126.375 167.316)
		(end 125.995 167.696)
		(width 0.15)
		(layer "F.Cu")
		(net 370)
	)
	(segment
		(start 126.375 166.037501)
		(end 126.375 167.316)
		(width 0.15)
		(layer "F.Cu")
		(net 370)
	)
	(segment
		(start 126.25 165.912501)
		(end 126.375 166.037501)
		(width 0.15)
		(layer "F.Cu")
		(net 370)
	)
	(segment
		(start 126.25 164.75)
		(end 126.25 165.912501)
		(width 0.15)
		(layer "F.Cu")
		(net 370)
	)
	(segment
		(start 123.625 167.316)
		(end 124.005 167.696)
		(width 0.15)
		(layer "F.Cu")
		(net 371)
	)
	(segment
		(start 123.625 166.037501)
		(end 123.625 167.316)
		(width 0.15)
		(layer "F.Cu")
		(net 371)
	)
	(segment
		(start 123.75 164.75)
		(end 123.75 165.912501)
		(width 0.15)
		(layer "F.Cu")
		(net 371)
	)
	(segment
		(start 123.75 165.912501)
		(end 123.625 166.037501)
		(width 0.15)
		(layer "F.Cu")
		(net 371)
	)
	(segment
		(start 126.75 164.75)
		(end 126.75 165.912501)
		(width 0.15)
		(layer "F.Cu")
		(net 372)
	)
	(segment
		(start 126.625 167.316)
		(end 127.005 167.696)
		(width 0.15)
		(layer "F.Cu")
		(net 372)
	)
	(segment
		(start 126.75 165.912501)
		(end 126.625 166.037501)
		(width 0.15)
		(layer "F.Cu")
		(net 372)
	)
	(segment
		(start 126.625 166.037501)
		(end 126.625 167.316)
		(width 0.15)
		(layer "F.Cu")
		(net 372)
	)
	(segment
		(start 129.385 167.316)
		(end 129.005 167.696)
		(width 0.15)
		(layer "F.Cu")
		(net 373)
	)
	(segment
		(start 129.385 166.037501)
		(end 129.385 167.316)
		(width 0.15)
		(layer "F.Cu")
		(net 373)
	)
	(segment
		(start 129.26 165.912501)
		(end 129.385 166.037501)
		(width 0.15)
		(layer "F.Cu")
		(net 373)
	)
	(segment
		(start 129.26 164.75)
		(end 129.26 165.912501)
		(width 0.15)
		(layer "F.Cu")
		(net 373)
	)
	(segment
		(start 132.375 166.037501)
		(end 132.375 167.316)
		(width 0.15)
		(layer "F.Cu")
		(net 374)
	)
	(segment
		(start 132.375 167.316)
		(end 131.995 167.696)
		(width 0.15)
		(layer "F.Cu")
		(net 374)
	)
	(segment
		(start 132.25 164.75)
		(end 132.25 165.912501)
		(width 0.15)
		(layer "F.Cu")
		(net 374)
	)
	(segment
		(start 132.25 165.912501)
		(end 132.375 166.037501)
		(width 0.15)
		(layer "F.Cu")
		(net 374)
	)
	(segment
		(start 129.76 164.75)
		(end 129.76 165.912501)
		(width 0.15)
		(layer "F.Cu")
		(net 375)
	)
	(segment
		(start 129.635 167.316)
		(end 130.015 167.696)
		(width 0.15)
		(layer "F.Cu")
		(net 375)
	)
	(segment
		(start 129.76 165.912501)
		(end 129.635 166.037501)
		(width 0.15)
		(layer "F.Cu")
		(net 375)
	)
	(segment
		(start 129.635 166.037501)
		(end 129.635 167.316)
		(width 0.15)
		(layer "F.Cu")
		(net 375)
	)
	(segment
		(start 132.625 166.037501)
		(end 132.625 167.316)
		(width 0.15)
		(layer "F.Cu")
		(net 376)
	)
	(segment
		(start 132.75 164.75)
		(end 132.75 165.912501)
		(width 0.15)
		(layer "F.Cu")
		(net 376)
	)
	(segment
		(start 132.625 167.316)
		(end 133.005 167.696)
		(width 0.15)
		(layer "F.Cu")
		(net 376)
	)
	(segment
		(start 132.75 165.912501)
		(end 132.625 166.037501)
		(width 0.15)
		(layer "F.Cu")
		(net 376)
	)
	(segment
		(start 96.715 175.689999)
		(end 96.715 167.764422)
		(width 0.15)
		(layer "B.Cu")
		(net 377)
	)
	(segment
		(start 96.89 175.864999)
		(end 96.715 175.689999)
		(width 0.15)
		(layer "B.Cu")
		(net 377)
	)
	(segment
		(start 96.89 177.155)
		(end 96.89 175.864999)
		(width 0.15)
		(layer "B.Cu")
		(net 377)
	)
	(segment
		(start 95.51 163.325)
		(end 95.885 162.95)
		(width 0.15)
		(layer "B.Cu")
		(net 377)
	)
	(segment
		(start 95.51 166.559422)
		(end 95.51 163.325)
		(width 0.15)
		(layer "B.Cu")
		(net 377)
	)
	(segment
		(start 96.715 167.764422)
		(end 95.51 166.559422)
		(width 0.15)
		(layer "B.Cu")
		(net 377)
	)
	(segment
		(start 95.26 166.662978)
		(end 95.26 163.325)
		(width 0.15)
		(layer "B.Cu")
		(net 378)
	)
	(segment
		(start 95.26 163.325)
		(end 94.885 162.95)
		(width 0.15)
		(layer "B.Cu")
		(net 378)
	)
	(segment
		(start 96.465 175.689999)
		(end 96.465 167.867978)
		(width 0.15)
		(layer "B.Cu")
		(net 378)
	)
	(segment
		(start 96.465 167.867978)
		(end 95.26 166.662978)
		(width 0.15)
		(layer "B.Cu")
		(net 378)
	)
	(segment
		(start 96.29 175.864999)
		(end 96.465 175.689999)
		(width 0.15)
		(layer "B.Cu")
		(net 378)
	)
	(segment
		(start 96.29 177.155)
		(end 96.29 175.864999)
		(width 0.15)
		(layer "B.Cu")
		(net 378)
	)
	(segment
		(start 95.775 125.175)
		(end 95.275 124.675)
		(width 0.15)
		(layer "F.Cu")
		(net 379)
	)
	(via
		(at 93.184987 163.80999)
		(size 0.5)
		(drill 0.2)
		(layers "F.Cu" "B.Cu")
		(net 379)
	)
	(via blind
		(at 95.275 124.675)
		(size 0.5)
		(drill 0.2)
		(layers "F.Cu" "In5.Cu")
		(net 379)
	)
	(segment
		(start 94.665 175.689999)
		(end 94.665 169.039778)
		(width 0.15)
		(layer "B.Cu")
		(net 379)
	)
	(segment
		(start 94.49 177.155)
		(end 94.49 175.864999)
		(width 0.15)
		(layer "B.Cu")
		(net 379)
	)
	(segment
		(start 93.449993 167.824771)
		(end 93.449993 164.074996)
		(width 0.15)
		(layer "B.Cu")
		(net 379)
	)
	(segment
		(start 94.665 169.039778)
		(end 93.449993 167.824771)
		(width 0.15)
		(layer "B.Cu")
		(net 379)
	)
	(segment
		(start 94.49 175.864999)
		(end 94.665 175.689999)
		(width 0.15)
		(layer "B.Cu")
		(net 379)
	)
	(segment
		(start 93.449993 164.074996)
		(end 93.184987 163.80999)
		(width 0.15)
		(layer "B.Cu")
		(net 379)
	)
	(segment
		(start 93.375 163.475)
		(end 93.194987 163.655013)
		(width 0.11)
		(layer "In5.Cu")
		(net 379)
	)
	(segment
		(start 90.795011 124.854989)
		(end 87.415 128.235)
		(width 0.11)
		(layer "In5.Cu")
		(net 379)
	)
	(segment
		(start 87.415 128.235)
		(end 87.415 154.115001)
		(width 0.11)
		(layer "In5.Cu")
		(net 379)
	)
	(segment
		(start 94.741458 124.854989)
		(end 90.795011 124.854989)
		(width 0.11)
		(layer "In5.Cu")
		(net 379)
	)
	(segment
		(start 93.375 160.075)
		(end 93.375 163.475)
		(width 0.11)
		(layer "In5.Cu")
		(net 379)
	)
	(segment
		(start 87.415 154.115001)
		(end 93.375 160.075)
		(width 0.11)
		(layer "In5.Cu")
		(net 379)
	)
	(segment
		(start 95.275 124.675)
		(end 94.921447 124.675)
		(width 0.11)
		(layer "In5.Cu")
		(net 379)
	)
	(segment
		(start 94.921447 124.675)
		(end 94.741458 124.854989)
		(width 0.11)
		(layer "In5.Cu")
		(net 379)
	)
	(segment
		(start 94.775 125.175)
		(end 95.275 125.675)
		(width 0.15)
		(layer "F.Cu")
		(net 380)
	)
	(via
		(at 93.965 163.80999)
		(size 0.5)
		(drill 0.2)
		(layers "F.Cu" "B.Cu")
		(net 380)
	)
	(via blind
		(at 95.275 125.675)
		(size 0.5)
		(drill 0.2)
		(layers "F.Cu" "In5.Cu")
		(net 380)
	)
	(segment
		(start 95.09 175.864999)
		(end 94.915 175.689999)
		(width 0.15)
		(layer "B.Cu")
		(net 380)
	)
	(segment
		(start 95.09 177.155)
		(end 95.09 175.864999)
		(width 0.15)
		(layer "B.Cu")
		(net 380)
	)
	(segment
		(start 94.915 168.936222)
		(end 93.699993 167.721215)
		(width 0.15)
		(layer "B.Cu")
		(net 380)
	)
	(segment
		(start 93.699993 167.721215)
		(end 93.699993 164.074996)
		(width 0.15)
		(layer "B.Cu")
		(net 380)
	)
	(segment
		(start 94.915 175.689999)
		(end 94.915 168.936222)
		(width 0.15)
		(layer "B.Cu")
		(net 380)
	)
	(segment
		(start 93.699993 164.074996)
		(end 93.964999 163.80999)
		(width 0.15)
		(layer "B.Cu")
		(net 380)
	)
	(segment
		(start 94.775 125.175)
		(end 95.275 125.675)
		(width 0.11)
		(layer "In5.Cu")
		(net 380)
	)
	(segment
		(start 87.735011 128.367551)
		(end 90.927562 125.175)
		(width 0.11)
		(layer "In5.Cu")
		(net 380)
	)
	(segment
		(start 90.927562 125.175)
		(end 94.775 125.175)
		(width 0.11)
		(layer "In5.Cu")
		(net 380)
	)
	(segment
		(start 93.975 163.80999)
		(end 93.675 163.50999)
		(width 0.11)
		(layer "In5.Cu")
		(net 380)
	)
	(segment
		(start 87.735011 153.982449)
		(end 87.735011 128.367551)
		(width 0.11)
		(layer "In5.Cu")
		(net 380)
	)
	(segment
		(start 93.675 163.50999)
		(end 93.675 159.922438)
		(width 0.11)
		(layer "In5.Cu")
		(net 380)
	)
	(segment
		(start 93.675 159.922438)
		(end 87.735011 153.982449)
		(width 0.11)
		(layer "In5.Cu")
		(net 380)
	)
	(segment
		(start 91.775 123.175)
		(end 91.275 122.675)
		(width 0.15)
		(layer "F.Cu")
		(net 381)
	)
	(via blind
		(at 91.275 122.675)
		(size 0.5)
		(drill 0.2)
		(layers "F.Cu" "In2.Cu")
		(net 381)
	)
	(via
		(at 96.81 163.80999)
		(size 0.5)
		(drill 0.2)
		(layers "F.Cu" "B.Cu")
		(net 381)
	)
	(segment
		(start 97.055 164.05499)
		(end 96.81 163.80999)
		(width 0.15)
		(layer "B.Cu")
		(net 381)
	)
	(segment
		(start 98.09 177.155)
		(end 98.09 175.864999)
		(width 0.15)
		(layer "B.Cu")
		(net 381)
	)
	(segment
		(start 98.265 166.797778)
		(end 97.055 165.587778)
		(width 0.15)
		(layer "B.Cu")
		(net 381)
	)
	(segment
		(start 98.09 175.864999)
		(end 98.265 175.689999)
		(width 0.15)
		(layer "B.Cu")
		(net 381)
	)
	(segment
		(start 98.265 175.689999)
		(end 98.265 166.797778)
		(width 0.15)
		(layer "B.Cu")
		(net 381)
	)
	(segment
		(start 97.055 165.587778)
		(end 97.055 164.05499)
		(width 0.15)
		(layer "B.Cu")
		(net 381)
	)
	(segment
		(start 96.82 163.38)
		(end 96.82 163.80999)
		(width 0.11)
		(layer "In2.Cu")
		(net 381)
	)
	(segment
		(start 89.715 124.815)
		(end 89.715 152.215)
		(width 0.11)
		(layer "In2.Cu")
		(net 381)
	)
	(segment
		(start 89.715 152.215)
		(end 97 159.5)
		(width 0.11)
		(layer "In2.Cu")
		(net 381)
	)
	(segment
		(start 91.275 122.675)
		(end 90.775 123.175)
		(width 0.11)
		(layer "In2.Cu")
		(net 381)
	)
	(segment
		(start 90.775 123.175)
		(end 90.775 123.755)
		(width 0.11)
		(layer "In2.Cu")
		(net 381)
	)
	(segment
		(start 97 159.5)
		(end 97 163.2)
		(width 0.11)
		(layer "In2.Cu")
		(net 381)
	)
	(segment
		(start 97 163.2)
		(end 96.82 163.38)
		(width 0.11)
		(layer "In2.Cu")
		(net 381)
	)
	(segment
		(start 90.775 123.755)
		(end 89.715 124.815)
		(width 0.11)
		(layer "In2.Cu")
		(net 381)
	)
	(segment
		(start 90.775 123.175)
		(end 91.275 123.675)
		(width 0.15)
		(layer "F.Cu")
		(net 382)
	)
	(via
		(at 97.52 163.80999)
		(size 0.5)
		(drill 0.2)
		(layers "F.Cu" "B.Cu")
		(net 382)
	)
	(via blind
		(at 91.275 123.675)
		(size 0.5)
		(drill 0.2)
		(layers "F.Cu" "In2.Cu")
		(net 382)
	)
	(segment
		(start 97.305 164.02499)
		(end 97.52 163.80999)
		(width 0.15)
		(layer "B.Cu")
		(net 382)
	)
	(segment
		(start 98.515 175.689999)
		(end 98.515 166.694222)
		(width 0.15)
		(layer "B.Cu")
		(net 382)
	)
	(segment
		(start 98.69 177.155)
		(end 98.69 175.864999)
		(width 0.15)
		(layer "B.Cu")
		(net 382)
	)
	(segment
		(start 98.69 175.864999)
		(end 98.515 175.689999)
		(width 0.15)
		(layer "B.Cu")
		(net 382)
	)
	(segment
		(start 98.515 166.694222)
		(end 97.305 165.484222)
		(width 0.15)
		(layer "B.Cu")
		(net 382)
	)
	(segment
		(start 97.305 165.484222)
		(end 97.305 164.02499)
		(width 0.15)
		(layer "B.Cu")
		(net 382)
	)
	(segment
		(start 97.53 163.43)
		(end 97.53 163.456437)
		(width 0.11)
		(layer "In2.Cu")
		(net 382)
	)
	(segment
		(start 97.3 163.2)
		(end 97.53 163.43)
		(width 0.11)
		(layer "In2.Cu")
		(net 382)
	)
	(segment
		(start 90.035011 152.167301)
		(end 97.3 159.43229)
		(width 0.11)
		(layer "In2.Cu")
		(net 382)
	)
	(segment
		(start 97.3 159.43229)
		(end 97.3 163.2)
		(width 0.11)
		(layer "In2.Cu")
		(net 382)
	)
	(segment
		(start 97.53 163.456437)
		(end 97.53 163.80999)
		(width 0.11)
		(layer "In2.Cu")
		(net 382)
	)
	(segment
		(start 90.035011 124.914989)
		(end 90.035011 152.167301)
		(width 0.11)
		(layer "In2.Cu")
		(net 382)
	)
	(segment
		(start 91.275 123.675)
		(end 90.035011 124.914989)
		(width 0.11)
		(layer "In2.Cu")
		(net 382)
	)
	(segment
		(start 123.935 176.33)
		(end 123.935 175.594204)
		(width 0.16)
		(layer "F.Cu")
		(net 383)
	)
	(segment
		(start 128.150001 126.13)
		(end 128.810796 126.13)
		(width 0.16)
		(layer "F.Cu")
		(net 383)
	)
	(segment
		(start 128.055001 126.225)
		(end 128.150001 126.13)
		(width 0.16)
		(layer "F.Cu")
		(net 383)
	)
	(segment
		(start 130.42 127.739204)
		(end 130.42 141.110796)
		(width 0.16)
		(layer "F.Cu")
		(net 383)
	)
	(segment
		(start 127.41 126.225)
		(end 128.055001 126.225)
		(width 0.16)
		(layer "F.Cu")
		(net 383)
	)
	(segment
		(start 123.79 177.345)
		(end 123.79 176.475)
		(width 0.16)
		(layer "F.Cu")
		(net 383)
	)
	(segment
		(start 128.810796 126.13)
		(end 130.42 127.739204)
		(width 0.16)
		(layer "F.Cu")
		(net 383)
	)
	(segment
		(start 119.37 171.029204)
		(end 119.37 152.160796)
		(width 0.16)
		(layer "F.Cu")
		(net 383)
	)
	(segment
		(start 119.37 152.160796)
		(end 130.42 141.110796)
		(width 0.16)
		(layer "F.Cu")
		(net 383)
	)
	(segment
		(start 123.79 176.475)
		(end 123.935 176.33)
		(width 0.16)
		(layer "F.Cu")
		(net 383)
	)
	(segment
		(start 123.935 175.594204)
		(end 119.37 171.029204)
		(width 0.16)
		(layer "F.Cu")
		(net 383)
	)
	(segment
		(start 124.245 176.33)
		(end 124.245 175.465796)
		(width 0.16)
		(layer "F.Cu")
		(net 384)
	)
	(segment
		(start 124.39 176.475)
		(end 124.245 176.33)
		(width 0.16)
		(layer "F.Cu")
		(net 384)
	)
	(segment
		(start 128.150001 125.82)
		(end 128.939204 125.82)
		(width 0.16)
		(layer "F.Cu")
		(net 384)
	)
	(segment
		(start 130.73 127.610796)
		(end 130.73 141.139204)
		(width 0.16)
		(layer "F.Cu")
		(net 384)
	)
	(segment
		(start 128.055001 125.725)
		(end 128.150001 125.82)
		(width 0.16)
		(layer "F.Cu")
		(net 384)
	)
	(segment
		(start 124.245 175.465796)
		(end 119.68 170.900796)
		(width 0.16)
		(layer "F.Cu")
		(net 384)
	)
	(segment
		(start 130.73 141.239204)
		(end 130.73 141.139204)
		(width 0.16)
		(layer "F.Cu")
		(net 384)
	)
	(segment
		(start 127.41 125.725)
		(end 128.055001 125.725)
		(width 0.16)
		(layer "F.Cu")
		(net 384)
	)
	(segment
		(start 124.39 177.345)
		(end 124.39 176.475)
		(width 0.16)
		(layer "F.Cu")
		(net 384)
	)
	(segment
		(start 119.68 152.289204)
		(end 130.73 141.239204)
		(width 0.16)
		(layer "F.Cu")
		(net 384)
	)
	(segment
		(start 130.73 141.22)
		(end 130.73 141.139204)
		(width 0.15)
		(layer "F.Cu")
		(net 384)
	)
	(segment
		(start 119.68 170.900796)
		(end 119.68 152.289204)
		(width 0.16)
		(layer "F.Cu")
		(net 384)
	)
	(segment
		(start 128.939204 125.82)
		(end 130.73 127.610796)
		(width 0.16)
		(layer "F.Cu")
		(net 384)
	)
	(segment
		(start 124.530796 174.92)
		(end 125.1 174.92)
		(width 0.16)
		(layer "F.Cu")
		(net 385)
	)
	(segment
		(start 125.1 174.92)
		(end 125.735 175.555)
		(width 0.16)
		(layer "F.Cu")
		(net 385)
	)
	(segment
		(start 131.158989 125.785642)
		(end 131.819 126.445652)
		(width 0.16)
		(layer "F.Cu")
		(net 385)
	)
	(segment
		(start 125.735 175.555)
		(end 125.735 175.98)
		(width 0.16)
		(layer "F.Cu")
		(net 385)
	)
	(segment
		(start 120.15 153.780796)
		(end 120.15 170.539204)
		(width 0.16)
		(layer "F.Cu")
		(net 385)
	)
	(segment
		(start 131.819989 112.039205)
		(end 131.819989 118.426011)
		(width 0.16)
		(layer "F.Cu")
		(net 385)
	)
	(segment
		(start 125.59 176.125)
		(end 125.59 177.345)
		(width 0.16)
		(layer "F.Cu")
		(net 385)
	)
	(segment
		(start 131.819989 118.426011)
		(end 131.158989 119.087011)
		(width 0.16)
		(layer "F.Cu")
		(net 385)
	)
	(segment
		(start 131.819 126.445652)
		(end 131.819 142.111796)
		(width 0.16)
		(layer "F.Cu")
		(net 385)
	)
	(segment
		(start 131.158989 119.087011)
		(end 131.158989 125.785642)
		(width 0.16)
		(layer "F.Cu")
		(net 385)
	)
	(segment
		(start 125.735 175.98)
		(end 125.59 176.125)
		(width 0.16)
		(layer "F.Cu")
		(net 385)
	)
	(segment
		(start 129.905784 110.125)
		(end 131.819989 112.039205)
		(width 0.16)
		(layer "F.Cu")
		(net 385)
	)
	(segment
		(start 120.15 170.539204)
		(end 124.530796 174.92)
		(width 0.16)
		(layer "F.Cu")
		(net 385)
	)
	(segment
		(start 127.61 110.125)
		(end 129.905784 110.125)
		(width 0.16)
		(layer "F.Cu")
		(net 385)
	)
	(segment
		(start 131.819 142.111796)
		(end 120.15 153.780796)
		(width 0.16)
		(layer "F.Cu")
		(net 385)
	)
	(segment
		(start 125.25 174.61)
		(end 124.659204 174.61)
		(width 0.16)
		(layer "F.Cu")
		(net 386)
	)
	(segment
		(start 124.659204 174.61)
		(end 120.46 170.410796)
		(width 0.16)
		(layer "F.Cu")
		(net 386)
	)
	(segment
		(start 132.129009 126.317241)
		(end 131.469 125.657232)
		(width 0.16)
		(layer "F.Cu")
		(net 386)
	)
	(segment
		(start 128.350001 109.72)
		(end 128.255001 109.625)
		(width 0.16)
		(layer "F.Cu")
		(net 386)
	)
	(segment
		(start 131.469 125.657232)
		(end 131.469 119.277)
		(width 0.16)
		(layer "F.Cu")
		(net 386)
	)
	(segment
		(start 132.13 118.616)
		(end 132.13 111.910796)
		(width 0.16)
		(layer "F.Cu")
		(net 386)
	)
	(segment
		(start 120.46 170.410796)
		(end 120.46 153.909204)
		(width 0.16)
		(layer "F.Cu")
		(net 386)
	)
	(segment
		(start 131.469 119.277)
		(end 132.13 118.616)
		(width 0.16)
		(layer "F.Cu")
		(net 386)
	)
	(segment
		(start 132.12901 126.43701)
		(end 132.129009 126.317241)
		(width 0.16)
		(layer "F.Cu")
		(net 386)
	)
	(segment
		(start 132.13 111.910796)
		(end 129.939204 109.72)
		(width 0.16)
		(layer "F.Cu")
		(net 386)
	)
	(segment
		(start 132.13 142.239204)
		(end 132.13 126.438)
		(width 0.16)
		(layer "F.Cu")
		(net 386)
	)
	(segment
		(start 126.19 176.475)
		(end 126.045 176.33)
		(width 0.16)
		(layer "F.Cu")
		(net 386)
	)
	(segment
		(start 126.045 175.405)
		(end 125.25 174.61)
		(width 0.16)
		(layer "F.Cu")
		(net 386)
	)
	(segment
		(start 129.939204 109.72)
		(end 128.350001 109.72)
		(width 0.16)
		(layer "F.Cu")
		(net 386)
	)
	(segment
		(start 128.255001 109.625)
		(end 127.61 109.625)
		(width 0.16)
		(layer "F.Cu")
		(net 386)
	)
	(segment
		(start 126.19 177.345)
		(end 126.19 176.475)
		(width 0.16)
		(layer "F.Cu")
		(net 386)
	)
	(segment
		(start 126.045 176.33)
		(end 126.045 175.405)
		(width 0.16)
		(layer "F.Cu")
		(net 386)
	)
	(segment
		(start 120.46 153.909204)
		(end 132.13 142.239204)
		(width 0.16)
		(layer "F.Cu")
		(net 386)
	)
	(segment
		(start 132.13 126.438)
		(end 132.12901 126.43701)
		(width 0.16)
		(layer "F.Cu")
		(net 386)
	)
	(segment
		(start 106.775 128.175)
		(end 107.275 128.675)
		(width 0.15)
		(layer "F.Cu")
		(net 387)
	)
	(via
		(at 116.425 154.675)
		(size 0.5)
		(drill 0.2)
		(layers "F.Cu" "B.Cu")
		(net 387)
	)
	(via blind
		(at 107.275 128.675)
		(size 0.5)
		(drill 0.2)
		(layers "F.Cu" "In2.Cu")
		(net 387)
	)
	(segment
		(start 117.06 154.675)
		(end 116.425 154.675)
		(width 0.15)
		(layer "B.Cu")
		(net 387)
	)
	(segment
		(start 113.325 154.675)
		(end 116.425 154.675)
		(width 0.15)
		(layer "In2.Cu")
		(net 387)
	)
	(segment
		(start 106.775 130.375)
		(end 107.175 130.775)
		(width 0.15)
		(layer "In2.Cu")
		(net 387)
	)
	(segment
		(start 107.175011 140.775011)
		(end 111.675 145.275)
		(width 0.15)
		(layer "In2.Cu")
		(net 387)
	)
	(segment
		(start 111.675 145.275)
		(end 111.675 153.025)
		(width 0.15)
		(layer "In2.Cu")
		(net 387)
	)
	(segment
		(start 107.275 128.675)
		(end 107.275 129.028553)
		(width 0.15)
		(layer "In2.Cu")
		(net 387)
	)
	(segment
		(start 107.175 131.075)
		(end 107.175011 131.075011)
		(width 0.15)
		(layer "In2.Cu")
		(net 387)
	)
	(segment
		(start 111.675 153.025)
		(end 113.315 154.665)
		(width 0.15)
		(layer "In2.Cu")
		(net 387)
	)
	(segment
		(start 106.775 129.528553)
		(end 106.775 130.375)
		(width 0.15)
		(layer "In2.Cu")
		(net 387)
	)
	(segment
		(start 107.175011 131.075011)
		(end 107.175011 140.775011)
		(width 0.15)
		(layer "In2.Cu")
		(net 387)
	)
	(segment
		(start 107.175 130.775)
		(end 107.175 131.075)
		(width 0.15)
		(layer "In2.Cu")
		(net 387)
	)
	(segment
		(start 107.275 129.028553)
		(end 106.775 129.528553)
		(width 0.15)
		(layer "In2.Cu")
		(net 387)
	)
	(segment
		(start 107.075 130.175)
		(end 107.600011 130.700011)
		(width 0.15)
		(layer "F.Cu")
		(net 388)
	)
	(segment
		(start 106.775 130.175)
		(end 107.075 130.175)
		(width 0.15)
		(layer "F.Cu")
		(net 388)
	)
	(segment
		(start 107.600011 130.700011)
		(end 107.600011 131.475)
		(width 0.15)
		(layer "F.Cu")
		(net 388)
	)
	(via
		(at 116.375 151.675)
		(size 0.5)
		(drill 0.2)
		(layers "F.Cu" "B.Cu")
		(net 388)
	)
	(via blind
		(at 107.600011 131.475)
		(size 0.5)
		(drill 0.2)
		(layers "F.Cu" "In2.Cu")
		(net 388)
	)
	(segment
		(start 117.01 151.675)
		(end 116.375 151.675)
		(width 0.15)
		(layer "B.Cu")
		(net 388)
	)
	(segment
		(start 107.600011 140.801795)
		(end 107.600011 131.475)
		(width 0.15)
		(layer "In2.Cu")
		(net 388)
	)
	(segment
		(start 116.375 151.675)
		(end 113.545 151.675)
		(width 0.15)
		(layer "In2.Cu")
		(net 388)
	)
	(segment
		(start 111.975 150.105)
		(end 111.975 145.176784)
		(width 0.15)
		(layer "In2.Cu")
		(net 388)
	)
	(segment
		(start 111.975 145.176784)
		(end 107.600011 140.801795)
		(width 0.15)
		(layer "In2.Cu")
		(net 388)
	)
	(segment
		(start 113.545 151.675)
		(end 111.975 150.105)
		(width 0.15)
		(layer "In2.Cu")
		(net 388)
	)
	(segment
		(start 106.775 129.175)
		(end 107.275 129.675)
		(width 0.15)
		(layer "F.Cu")
		(net 389)
	)
	(via
		(at 116.375 150.675)
		(size 0.5)
		(drill 0.2)
		(layers "F.Cu" "B.Cu")
		(net 389)
	)
	(via blind
		(at 107.275 129.675)
		(size 0.5)
		(drill 0.2)
		(layers "F.Cu" "In2.Cu")
		(net 389)
	)
	(segment
		(start 117.01 150.675)
		(end 116.375 150.675)
		(width 0.15)
		(layer "B.Cu")
		(net 389)
	)
	(segment
		(start 107.275 130.475)
		(end 107.275 129.675)
		(width 0.15)
		(layer "In2.Cu")
		(net 389)
	)
	(segment
		(start 108.025011 131.225011)
		(end 107.275 130.475)
		(width 0.15)
		(layer "In2.Cu")
		(net 389)
	)
	(segment
		(start 116.375 150.675)
		(end 113.795 150.675)
		(width 0.15)
		(layer "In2.Cu")
		(net 389)
	)
	(segment
		(start 113.795 150.675)
		(end 112.275 149.155)
		(width 0.15)
		(layer "In2.Cu")
		(net 389)
	)
	(segment
		(start 112.275 145.025)
		(end 108.025011 140.775011)
		(width 0.15)
		(layer "In2.Cu")
		(net 389)
	)
	(segment
		(start 108.025011 140.775011)
		(end 108.025011 131.225011)
		(width 0.15)
		(layer "In2.Cu")
		(net 389)
	)
	(segment
		(start 112.275 149.155)
		(end 112.275 145.025)
		(width 0.15)
		(layer "In2.Cu")
		(net 389)
	)
	(segment
		(start 107.775 128.175)
		(end 108.275 128.675)
		(width 0.15)
		(layer "F.Cu")
		(net 390)
	)
	(via
		(at 116.375 149.675)
		(size 0.5)
		(drill 0.2)
		(layers "F.Cu" "B.Cu")
		(net 390)
	)
	(via blind
		(at 108.275 128.675)
		(size 0.5)
		(drill 0.2)
		(layers "F.Cu" "In2.Cu")
		(net 390)
	)
	(segment
		(start 117.01 149.675)
		(end 116.375 149.675)
		(width 0.15)
		(layer "B.Cu")
		(net 390)
	)
	(segment
		(start 108.275022 140.575022)
		(end 108.275022 130.875022)
		(width 0.15)
		(layer "In2.Cu")
		(net 390)
	)
	(segment
		(start 116.375 149.675)
		(end 114.345 149.675)
		(width 0.15)
		(layer "In2.Cu")
		(net 390)
	)
	(segment
		(start 112.575 147.905)
		(end 112.575 144.875)
		(width 0.15)
		(layer "In2.Cu")
		(net 390)
	)
	(segment
		(start 108.275022 130.875022)
		(end 107.775 130.375)
		(width 0.15)
		(layer "In2.Cu")
		(net 390)
	)
	(segment
		(start 114.345 149.675)
		(end 112.575 147.905)
		(width 0.15)
		(layer "In2.Cu")
		(net 390)
	)
	(segment
		(start 112.575 144.875)
		(end 108.275022 140.575022)
		(width 0.15)
		(layer "In2.Cu")
		(net 390)
	)
	(segment
		(start 107.775 130.375)
		(end 107.775 129.175)
		(width 0.15)
		(layer "In2.Cu")
		(net 390)
	)
	(segment
		(start 107.775 129.175)
		(end 108.275 128.675)
		(width 0.15)
		(layer "In2.Cu")
		(net 390)
	)
	(segment
		(start 107.775 129.175)
		(end 108.275 129.675)
		(width 0.15)
		(layer "F.Cu")
		(net 391)
	)
	(via
		(at 116.375 148.675)
		(size 0.5)
		(drill 0.2)
		(layers "F.Cu" "B.Cu")
		(net 391)
	)
	(via blind
		(at 108.275 129.675)
		(size 0.5)
		(drill 0.2)
		(layers "F.Cu" "In2.Cu")
		(net 391)
	)
	(segment
		(start 117.01 148.675)
		(end 116.375 148.675)
		(width 0.15)
		(layer "B.Cu")
		(net 391)
	)
	(segment
		(start 112.875 146.875)
		(end 112.875 144.775)
		(width 0.15)
		(layer "In2.Cu")
		(net 391)
	)
	(segment
		(start 116.375 148.675)
		(end 114.675 148.675)
		(width 0.15)
		(layer "In2.Cu")
		(net 391)
	)
	(segment
		(start 114.675 148.675)
		(end 112.875 146.875)
		(width 0.15)
		(layer "In2.Cu")
		(net 391)
	)
	(segment
		(start 108.525032 129.925032)
		(end 108.524999 129.924999)
		(width 0.15)
		(layer "In2.Cu")
		(net 391)
	)
	(segment
		(start 108.525032 140.425032)
		(end 108.525032 129.925032)
		(width 0.15)
		(layer "In2.Cu")
		(net 391)
	)
	(segment
		(start 112.875 144.775)
		(end 108.525032 140.425032)
		(width 0.15)
		(layer "In2.Cu")
		(net 391)
	)
	(segment
		(start 108.524999 129.924999)
		(end 108.275 129.675)
		(width 0.15)
		(layer "In2.Cu")
		(net 391)
	)
	(segment
		(start 108.775 129.175)
		(end 109.275 129.675)
		(width 0.15)
		(layer "F.Cu")
		(net 392)
	)
	(via
		(at 116.375 147.675)
		(size 0.5)
		(drill 0.2)
		(layers "F.Cu" "B.Cu")
		(net 392)
	)
	(via blind
		(at 109.275 129.675)
		(size 0.5)
		(drill 0.2)
		(layers "F.Cu" "In2.Cu")
		(net 392)
	)
	(segment
		(start 117.01 147.675)
		(end 116.375 147.675)
		(width 0.15)
		(layer "B.Cu")
		(net 392)
	)
	(segment
		(start 113.175 146.035)
		(end 113.175 144.575)
		(width 0.15)
		(layer "In2.Cu")
		(net 392)
	)
	(segment
		(start 114.815 147.675)
		(end 113.175 146.035)
		(width 0.15)
		(layer "In2.Cu")
		(net 392)
	)
	(segment
		(start 108.849999 130.100001)
		(end 109.275 129.675)
		(width 0.15)
		(layer "In2.Cu")
		(net 392)
	)
	(segment
		(start 113.175 144.575)
		(end 108.849999 140.249999)
		(width 0.15)
		(layer "In2.Cu")
		(net 392)
	)
	(segment
		(start 116.375 147.675)
		(end 114.815 147.675)
		(width 0.15)
		(layer "In2.Cu")
		(net 392)
	)
	(segment
		(start 108.849999 140.249999)
		(end 108.849999 130.100001)
		(width 0.15)
		(layer "In2.Cu")
		(net 392)
	)
	(segment
		(start 108.775 130.175)
		(end 109.275 130.675)
		(width 0.15)
		(layer "F.Cu")
		(net 393)
	)
	(via
		(at 116.375 146.675)
		(size 0.5)
		(drill 0.2)
		(layers "F.Cu" "B.Cu")
		(net 393)
	)
	(via blind
		(at 109.275 130.675)
		(size 0.5)
		(drill 0.2)
		(layers "F.Cu" "In2.Cu")
		(net 393)
	)
	(segment
		(start 117.01 146.675)
		(end 116.375 146.675)
		(width 0.15)
		(layer "B.Cu")
		(net 393)
	)
	(segment
		(start 114.895 146.675)
		(end 113.475 145.255)
		(width 0.15)
		(layer "In2.Cu")
		(net 393)
	)
	(segment
		(start 113.475 145.255)
		(end 113.475 144.375)
		(width 0.15)
		(layer "In2.Cu")
		(net 393)
	)
	(segment
		(start 116.375 146.675)
		(end 114.895 146.675)
		(width 0.15)
		(layer "In2.Cu")
		(net 393)
	)
	(segment
		(start 109.275 140.175)
		(end 109.275 130.675)
		(width 0.15)
		(layer "In2.Cu")
		(net 393)
	)
	(segment
		(start 113.475 144.375)
		(end 109.275 140.175)
		(width 0.15)
		(layer "In2.Cu")
		(net 393)
	)
	(segment
		(start 109.775 129.175)
		(end 110.275 129.675)
		(width 0.15)
		(layer "F.Cu")
		(net 394)
	)
	(via
		(at 116.375 145.675)
		(size 0.5)
		(drill 0.2)
		(layers "F.Cu" "B.Cu")
		(net 394)
	)
	(via blind
		(at 110.275 129.675)
		(size 0.5)
		(drill 0.2)
		(layers "F.Cu" "In2.Cu")
		(net 394)
	)
	(segment
		(start 117.01 145.675)
		(end 116.375 145.675)
		(width 0.15)
		(layer "B.Cu")
		(net 394)
	)
	(segment
		(start 115.225 145.675)
		(end 109.700001 140.150001)
		(width 0.15)
		(layer "In2.Cu")
		(net 394)
	)
	(segment
		(start 109.700001 140.150001)
		(end 109.700001 130.249999)
		(width 0.15)
		(layer "In2.Cu")
		(net 394)
	)
	(segment
		(start 116.375 145.675)
		(end 115.225 145.675)
		(width 0.15)
		(layer "In2.Cu")
		(net 394)
	)
	(segment
		(start 109.700001 130.249999)
		(end 110.275 129.675)
		(width 0.15)
		(layer "In2.Cu")
		(net 394)
	)
	(segment
		(start 109.775 130.175)
		(end 110.275 130.675)
		(width 0.15)
		(layer "F.Cu")
		(net 395)
	)
	(via
		(at 116.375 144.675)
		(size 0.5)
		(drill 0.2)
		(layers "F.Cu" "B.Cu")
		(net 395)
	)
	(via blind
		(at 110.275 130.675)
		(size 0.5)
		(drill 0.2)
		(layers "F.Cu" "In2.Cu")
		(net 395)
	)
	(segment
		(start 117.01 144.675)
		(end 116.375 144.675)
		(width 0.15)
		(layer "B.Cu")
		(net 395)
	)
	(segment
		(start 114.675 144.675)
		(end 110.275 140.275)
		(width 0.15)
		(layer "In2.Cu")
		(net 395)
	)
	(segment
		(start 116.375 144.675)
		(end 114.675 144.675)
		(width 0.15)
		(layer "In2.Cu")
		(net 395)
	)
	(segment
		(start 110.275 140.275)
		(end 110.275 130.675)
		(width 0.15)
		(layer "In2.Cu")
		(net 395)
	)
	(segment
		(start 109.775 128.175)
		(end 110.275 128.675)
		(width 0.15)
		(layer "F.Cu")
		(net 396)
	)
	(via
		(at 116.375 143.675)
		(size 0.5)
		(drill 0.2)
		(layers "F.Cu" "B.Cu")
		(net 396)
	)
	(via blind
		(at 110.275 128.675)
		(size 0.5)
		(drill 0.2)
		(layers "F.Cu" "In2.Cu")
		(net 396)
	)
	(segment
		(start 117.01 143.675)
		(end 116.375 143.675)
		(width 0.15)
		(layer "B.Cu")
		(net 396)
	)
	(segment
		(start 116.375 143.675)
		(end 114.175 143.675)
		(width 0.15)
		(layer "In2.Cu")
		(net 396)
	)
	(segment
		(start 110.275 128.675)
		(end 110.700001 129.100001)
		(width 0.15)
		(layer "In2.Cu")
		(net 396)
	)
	(segment
		(start 114.175 143.675)
		(end 110.700001 140.200001)
		(width 0.15)
		(layer "In2.Cu")
		(net 396)
	)
	(segment
		(start 110.700001 140.200001)
		(end 110.700001 129.100001)
		(width 0.15)
		(layer "In2.Cu")
		(net 396)
	)
	(segment
		(start 110.775 130.175)
		(end 111.275 130.675)
		(width 0.15)
		(layer "F.Cu")
		(net 397)
	)
	(via
		(at 116.375 142.675)
		(size 0.5)
		(drill 0.2)
		(layers "F.Cu" "B.Cu")
		(net 397)
	)
	(via blind
		(at 111.275 130.675)
		(size 0.5)
		(drill 0.2)
		(layers "F.Cu" "In2.Cu")
		(net 397)
	)
	(segment
		(start 117.01 142.675)
		(end 116.375 142.675)
		(width 0.15)
		(layer "B.Cu")
		(net 397)
	)
	(segment
		(start 111.275 140.325)
		(end 113.625 142.675)
		(width 0.15)
		(layer "In2.Cu")
		(net 397)
	)
	(segment
		(start 113.625 142.675)
		(end 116.375 142.675)
		(width 0.15)
		(layer "In2.Cu")
		(net 397)
	)
	(segment
		(start 111.275 130.675)
		(end 111.275 140.325)
		(width 0.15)
		(layer "In2.Cu")
		(net 397)
	)
	(segment
		(start 111.775 130.175)
		(end 112.275 130.675)
		(width 0.15)
		(layer "F.Cu")
		(net 398)
	)
	(via
		(at 116.375 141.675)
		(size 0.5)
		(drill 0.2)
		(layers "F.Cu" "B.Cu")
		(net 398)
	)
	(via blind
		(at 112.275 130.675)
		(size 0.5)
		(drill 0.2)
		(layers "F.Cu" "In2.Cu")
		(net 398)
	)
	(segment
		(start 117.01 141.675)
		(end 116.375 141.675)
		(width 0.15)
		(layer "B.Cu")
		(net 398)
	)
	(segment
		(start 113.075 141.675)
		(end 116.375 141.675)
		(width 0.15)
		(layer "In2.Cu")
		(net 398)
	)
	(segment
		(start 112.275 130.675)
		(end 111.675 131.275)
		(width 0.15)
		(layer "In2.Cu")
		(net 398)
	)
	(segment
		(start 111.675 140.275)
		(end 113.075 141.675)
		(width 0.15)
		(layer "In2.Cu")
		(net 398)
	)
	(segment
		(start 111.675 131.275)
		(end 111.675 140.275)
		(width 0.15)
		(layer "In2.Cu")
		(net 398)
	)
	(segment
		(start 128.45 93.1125)
		(end 127.935 93.1125)
		(width 0.1)
		(layer "F.Cu")
		(net 399)
	)
	(segment
		(start 129.0125 92.55)
		(end 128.45 93.1125)
		(width 0.1)
		(layer "F.Cu")
		(net 399)
	)
	(segment
		(start 130.1875 92.55)
		(end 129.0125 92.55)
		(width 0.1)
		(layer "F.Cu")
		(net 399)
	)
	(segment
		(start 133.35 99.7125)
		(end 133.35 100.65)
		(width 0.15)
		(layer "F.Cu")
		(net 400)
	)
	(segment
		(start 133.575 100.875)
		(end 133.575 103.075)
		(width 0.15)
		(layer "F.Cu")
		(net 400)
	)
	(segment
		(start 133.35 100.65)
		(end 133.575 100.875)
		(width 0.15)
		(layer "F.Cu")
		(net 400)
	)
	(segment
		(start 133.575 103.075)
		(end 132.875 103.775)
		(width 0.15)
		(layer "F.Cu")
		(net 400)
	)
	(segment
		(start 132.875 103.775)
		(end 131.36 103.775)
		(width 0.15)
		(layer "F.Cu")
		(net 400)
	)
	(segment
		(start 133.85 104)
		(end 133.075 104.775)
		(width 0.15)
		(layer "F.Cu")
		(net 401)
	)
	(segment
		(start 133.075 104.775)
		(end 131.37 104.775)
		(width 0.15)
		(layer "F.Cu")
		(net 401)
	)
	(segment
		(start 133.85 99.7125)
		(end 133.85 104)
		(width 0.15)
		(layer "F.Cu")
		(net 401)
	)
	(segment
		(start 144.615 123.015)
		(end 144.615 114.49)
		(width 0.15)
		(layer "F.Cu")
		(net 402)
	)
	(segment
		(start 139.274 124.014)
		(end 139.775 124.515)
		(width 0.15)
		(layer "F.Cu")
		(net 402)
	)
	(segment
		(start 139.775 124.515)
		(end 143.115 124.515)
		(width 0.15)
		(layer "F.Cu")
		(net 402)
	)
	(segment
		(start 144.615 114.49)
		(end 144.54 114.415)
		(width 0.15)
		(layer "F.Cu")
		(net 402)
	)
	(segment
		(start 143.115 124.515)
		(end 144.615 123.015)
		(width 0.15)
		(layer "F.Cu")
		(net 402)
	)
	(segment
		(start 129.5125 94.05)
		(end 128.2008 95.3617)
		(width 0.1)
		(layer "F.Cu")
		(net 403)
	)
	(segment
		(start 128.2008 95.3617)
		(end 126.25 95.3617)
		(width 0.1)
		(layer "F.Cu")
		(net 403)
	)
	(segment
		(start 130.1875 94.05)
		(end 129.5125 94.05)
		(width 0.1)
		(layer "F.Cu")
		(net 403)
	)
	(segment
		(start 105.527149 95.475)
		(end 106.375 95.475)
		(width 0.15)
		(layer "F.Cu")
		(net 404)
	)
	(segment
		(start 106.375 95.475)
		(end 106.4 95.5)
		(width 0.15)
		(layer "F.Cu")
		(net 404)
	)
	(via
		(at 106.4 95.5)
		(size 0.5)
		(drill 0.2)
		(layers "F.Cu" "B.Cu")
		(net 404)
	)
	(segment
		(start 106.4 95.5)
		(end 107.19 95.5)
		(width 0.15)
		(layer "B.Cu")
		(net 404)
	)
	(segment
		(start 107.24 96.5)
		(end 107.24 93.505)
		(width 0.15)
		(layer "B.Cu")
		(net 404)
	)
	(segment
		(start 107.19 95.5)
		(end 107.24 95.55)
		(width 0.15)
		(layer "B.Cu")
		(net 404)
	)
	(segment
		(start 103.35 92.797851)
		(end 103.35 92)
		(width 0.15)
		(layer "F.Cu")
		(net 405)
	)
	(segment
		(start 100.85 92.797851)
		(end 100.85 92)
		(width 0.15)
		(layer "F.Cu")
		(net 405)
	)
	(via
		(at 100.85 92)
		(size 0.5)
		(drill 0.2)
		(layers "F.Cu" "B.Cu")
		(net 405)
	)
	(via
		(at 103.35 92)
		(size 0.5)
		(drill 0.2)
		(layers "F.Cu" "B.Cu")
		(net 405)
	)
	(segment
		(start 100.85 92)
		(end 100.85 91.255)
		(width 0.15)
		(layer "B.Cu")
		(net 405)
	)
	(segment
		(start 103.35 92)
		(end 103.6 92)
		(width 0.15)
		(layer "B.Cu")
		(net 405)
	)
	(segment
		(start 103.7 91.9)
		(end 103.7 91.25)
		(width 0.15)
		(layer "B.Cu")
		(net 405)
	)
	(segment
		(start 102.75 91.25)
		(end 100.845 91.25)
		(width 0.15)
		(layer "B.Cu")
		(net 405)
	)
	(segment
		(start 103.7 91.25)
		(end 102.75 91.25)
		(width 0.15)
		(layer "B.Cu")
		(net 405)
	)
	(segment
		(start 100.85 91.255)
		(end 100.845 91.25)
		(width 0.15)
		(layer "B.Cu")
		(net 405)
	)
	(segment
		(start 99.66 91.17)
		(end 102.67 91.17)
		(width 0.15)
		(layer "B.Cu")
		(net 405)
	)
	(segment
		(start 103.6 92)
		(end 103.7 91.9)
		(width 0.15)
		(layer "B.Cu")
		(net 405)
	)
	(segment
		(start 102.67 91.17)
		(end 102.75 91.25)
		(width 0.15)
		(layer "B.Cu")
		(net 405)
	)
	(segment
		(start 99.197851 92.797851)
		(end 98.5 92.1)
		(width 0.15)
		(layer "F.Cu")
		(net 406)
	)
	(segment
		(start 104.85 92.797851)
		(end 104.85 92)
		(width 0.15)
		(layer "F.Cu")
		(net 406)
	)
	(segment
		(start 99.35 92.797851)
		(end 99.197851 92.797851)
		(width 0.15)
		(layer "F.Cu")
		(net 406)
	)
	(via
		(at 96.674 91.214)
		(size 0.5)
		(drill 0.2)
		(layers "F.Cu" "B.Cu")
		(net 406)
	)
	(via
		(at 104.85 92)
		(size 0.5)
		(drill 0.2)
		(layers "F.Cu" "B.Cu")
		(net 406)
	)
	(via
		(at 98.5 92.1)
		(size 0.5)
		(drill 0.2)
		(layers "F.Cu" "B.Cu")
		(net 406)
	)
	(via
		(at 106.774 91.214)
		(size 0.5)
		(drill 0.2)
		(layers "F.Cu" "B.Cu")
		(net 406)
	)
	(segment
		(start 106.1 91.235)
		(end 106.753 91.235)
		(width 0.15)
		(layer "B.Cu")
		(net 406)
	)
	(segment
		(start 104.85 92)
		(end 104.85 91.2)
		(width 0.15)
		(layer "B.Cu")
		(net 406)
	)
	(segment
		(start 104.985 91.235)
		(end 104.9 91.15)
		(width 0.15)
		(layer "B.Cu")
		(net 406)
	)
	(segment
		(start 106.753 91.235)
		(end 106.774 91.214)
		(width 0.15)
		(layer "B.Cu")
		(net 406)
	)
	(segment
		(start 97.139 91.214)
		(end 96.674 91.214)
		(width 0.15)
		(layer "B.Cu")
		(net 406)
	)
	(segment
		(start 97.18 91.255)
		(end 97.139 91.214)
		(width 0.15)
		(layer "B.Cu")
		(net 406)
	)
	(segment
		(start 98.49 91.265)
		(end 97.51 91.265)
		(width 0.15)
		(layer "B.Cu")
		(net 406)
	)
	(segment
		(start 104.85 91.2)
		(end 104.9 91.15)
		(width 0.15)
		(layer "B.Cu")
		(net 406)
	)
	(segment
		(start 97.5 91.255)
		(end 97.18 91.255)
		(width 0.15)
		(layer "B.Cu")
		(net 406)
	)
	(segment
		(start 98.5 92.1)
		(end 98.5 91.275)
		(width 0.15)
		(layer "B.Cu")
		(net 406)
	)
	(segment
		(start 97.51 91.265)
		(end 97.5 91.255)
		(width 0.15)
		(layer "B.Cu")
		(net 406)
	)
	(segment
		(start 106.1 91.235)
		(end 104.985 91.235)
		(width 0.15)
		(layer "B.Cu")
		(net 406)
	)
	(segment
		(start 98.5 91.275)
		(end 98.49 91.265)
		(width 0.15)
		(layer "B.Cu")
		(net 406)
	)
	(segment
		(start 96.674 91.214)
		(end 106.774 91.214)
		(width 0.15)
		(layer "In5.Cu")
		(net 406)
	)
	(segment
		(start 100.775 111.175)
		(end 100.275 110.675)
		(width 0.1)
		(layer "F.Cu")
		(net 407)
	)
	(segment
		(start 102.85 99.652149)
		(end 102.85 101.45)
		(width 0.15)
		(layer "F.Cu")
		(net 407)
	)
	(via blind
		(at 100.275 110.675)
		(size 0.5)
		(drill 0.2)
		(layers "F.Cu" "In2.Cu")
		(net 407)
	)
	(via
		(at 102.85 101.45)
		(size 0.5)
		(drill 0.2)
		(layers "F.Cu" "B.Cu")
		(net 407)
	)
	(segment
		(start 102.6 102.415)
		(end 102.6 101.7)
		(width 0.15)
		(layer "B.Cu")
		(net 407)
	)
	(segment
		(start 102.6 101.7)
		(end 102.85 101.45)
		(width 0.15)
		(layer "B.Cu")
		(net 407)
	)
	(segment
		(start 102.85 101.45)
		(end 102.85 102.1)
		(width 0.15)
		(layer "In2.Cu")
		(net 407)
	)
	(segment
		(start 100.849999 104.100001)
		(end 100.849999 110.100001)
		(width 0.15)
		(layer "In2.Cu")
		(net 407)
	)
	(segment
		(start 102.85 102.1)
		(end 100.849999 104.100001)
		(width 0.15)
		(layer "In2.Cu")
		(net 407)
	)
	(segment
		(start 100.275 110.675)
		(end 100.849999 110.100001)
		(width 0.15)
		(layer "In2.Cu")
		(net 407)
	)
	(segment
		(start 102.35 99.652149)
		(end 102.35 100.8)
		(width 0.15)
		(layer "F.Cu")
		(net 408)
	)
	(segment
		(start 100.775 110.175)
		(end 100.275 109.675)
		(width 0.1)
		(layer "F.Cu")
		(net 408)
	)
	(via
		(at 102.35 100.8)
		(size 0.5)
		(drill 0.2)
		(layers "F.Cu" "B.Cu")
		(net 408)
	)
	(via blind
		(at 100.275 109.675)
		(size 0.5)
		(drill 0.2)
		(layers "F.Cu" "In2.Cu")
		(net 408)
	)
	(segment
		(start 101.65 101.5)
		(end 102.35 100.8)
		(width 0.15)
		(layer "B.Cu")
		(net 408)
	)
	(segment
		(start 101.65 102.415)
		(end 101.65 101.5)
		(width 0.15)
		(layer "B.Cu")
		(net 408)
	)
	(segment
		(start 101.493724 101.909991)
		(end 101.48625 101.942738)
		(width 0.15)
		(layer "In2.Cu")
		(net 408)
	)
	(segment
		(start 101.471676 101.973001)
		(end 101.450735 101.999264)
		(width 0.15)
		(layer "In2.Cu")
		(net 408)
	)
	(segment
		(start 101.450735 101.999264)
		(end 100.275 103.175)
		(width 0.15)
		(layer "In2.Cu")
		(net 408)
	)
	(segment
		(start 101.352749 101.524218)
		(end 101.338175 101.554481)
		(width 0.15)
		(layer "In2.Cu")
		(net 408)
	)
	(segment
		(start 101.818475 101.610516)
		(end 101.785728 101.61799)
		(width 0.15)
		(layer "In2.Cu")
		(net 408)
	)
	(segment
		(start 101.330701 101.587228)
		(end 101.330701 101.620817)
		(width 0.15)
		(layer "In2.Cu")
		(net 408)
	)
	(segment
		(start 101.785728 101.61799)
		(end 101.752139 101.61799)
		(width 0.15)
		(layer "In2.Cu")
		(net 408)
	)
	(segment
		(start 101.496553 101.454967)
		(end 101.462964 101.454967)
		(width 0.15)
		(layer "In2.Cu")
		(net 408)
	)
	(segment
		(start 101.471676 101.813392)
		(end 101.48625 101.843655)
		(width 0.15)
		(layer "In2.Cu")
		(net 408)
	)
	(segment
		(start 102.35 101.1)
		(end 101.875 101.575)
		(width 0.15)
		(layer "In2.Cu")
		(net 408)
	)
	(segment
		(start 101.399954 101.477015)
		(end 101.373692 101.497957)
		(width 0.15)
		(layer "In2.Cu")
		(net 408)
	)
	(segment
		(start 101.338175 101.554481)
		(end 101.330701 101.587228)
		(width 0.15)
		(layer "In2.Cu")
		(net 408)
	)
	(segment
		(start 101.493724 101.876402)
		(end 101.493724 101.909991)
		(width 0.15)
		(layer "In2.Cu")
		(net 408)
	)
	(segment
		(start 102.35 100.8)
		(end 102.35 101.1)
		(width 0.15)
		(layer "In2.Cu")
		(net 408)
	)
	(segment
		(start 101.662867 101.575)
		(end 101.585824 101.497957)
		(width 0.15)
		(layer "In2.Cu")
		(net 408)
	)
	(segment
		(start 101.338175 101.653564)
		(end 101.352749 101.683827)
		(width 0.15)
		(layer "In2.Cu")
		(net 408)
	)
	(segment
		(start 101.585824 101.497957)
		(end 101.559563 101.477015)
		(width 0.15)
		(layer "In2.Cu")
		(net 408)
	)
	(segment
		(start 101.719392 101.610516)
		(end 101.689129 101.595942)
		(width 0.15)
		(layer "In2.Cu")
		(net 408)
	)
	(segment
		(start 101.848738 101.595942)
		(end 101.818475 101.610516)
		(width 0.15)
		(layer "In2.Cu")
		(net 408)
	)
	(segment
		(start 101.352749 101.683827)
		(end 101.373692 101.710089)
		(width 0.15)
		(layer "In2.Cu")
		(net 408)
	)
	(segment
		(start 101.559563 101.477015)
		(end 101.5293 101.462441)
		(width 0.15)
		(layer "In2.Cu")
		(net 408)
	)
	(segment
		(start 101.689129 101.595942)
		(end 101.662867 101.575)
		(width 0.15)
		(layer "In2.Cu")
		(net 408)
	)
	(segment
		(start 101.462964 101.454967)
		(end 101.430217 101.462441)
		(width 0.15)
		(layer "In2.Cu")
		(net 408)
	)
	(segment
		(start 101.48625 101.843655)
		(end 101.493724 101.876402)
		(width 0.15)
		(layer "In2.Cu")
		(net 408)
	)
	(segment
		(start 101.450734 101.787131)
		(end 101.471676 101.813392)
		(width 0.15)
		(layer "In2.Cu")
		(net 408)
	)
	(segment
		(start 101.330701 101.620817)
		(end 101.338175 101.653564)
		(width 0.15)
		(layer "In2.Cu")
		(net 408)
	)
	(segment
		(start 101.430217 101.462441)
		(end 101.399954 101.477015)
		(width 0.15)
		(layer "In2.Cu")
		(net 408)
	)
	(segment
		(start 101.373692 101.710089)
		(end 101.450734 101.787131)
		(width 0.15)
		(layer "In2.Cu")
		(net 408)
	)
	(segment
		(start 101.5293 101.462441)
		(end 101.496553 101.454967)
		(width 0.15)
		(layer "In2.Cu")
		(net 408)
	)
	(segment
		(start 101.875 101.575)
		(end 101.848738 101.595942)
		(width 0.15)
		(layer "In2.Cu")
		(net 408)
	)
	(segment
		(start 101.752139 101.61799)
		(end 101.719392 101.610516)
		(width 0.15)
		(layer "In2.Cu")
		(net 408)
	)
	(segment
		(start 101.48625 101.942738)
		(end 101.471676 101.973001)
		(width 0.15)
		(layer "In2.Cu")
		(net 408)
	)
	(segment
		(start 100.275 103.175)
		(end 100.275 109.675)
		(width 0.15)
		(layer "In2.Cu")
		(net 408)
	)
	(segment
		(start 101.373692 101.497957)
		(end 101.352749 101.524218)
		(width 0.15)
		(layer "In2.Cu")
		(net 408)
	)
	(segment
		(start 99.775 110.175)
		(end 99.275 109.675)
		(width 0.1)
		(layer "F.Cu")
		(net 409)
	)
	(segment
		(start 100.85 99.652149)
		(end 100.85 101.45)
		(width 0.15)
		(layer "F.Cu")
		(net 409)
	)
	(via blind
		(at 99.275 109.675)
		(size 0.5)
		(drill 0.2)
		(layers "F.Cu" "In2.Cu")
		(net 409)
	)
	(via
		(at 100.85 101.45)
		(size 0.5)
		(drill 0.2)
		(layers "F.Cu" "B.Cu")
		(net 409)
	)
	(segment
		(start 100.7 101.6)
		(end 100.85 101.45)
		(width 0.15)
		(layer "B.Cu")
		(net 409)
	)
	(segment
		(start 100.7 102.415)
		(end 100.7 101.6)
		(width 0.15)
		(layer "B.Cu")
		(net 409)
	)
	(segment
		(start 100.016455 107.245054)
		(end 100.007413 107.219213)
		(width 0.15)
		(layer "In2.Cu")
		(net 409)
	)
	(segment
		(start 99.924466 107.755805)
		(end 99.89726 107.75274)
		(width 0.15)
		(layer "In2.Cu")
		(net 409)
	)
	(segment
		(start 99.530479 106.97226)
		(end 99.533545 106.945054)
		(width 0.15)
		(layer "In2.Cu")
		(net 409)
	)
	(segment
		(start 99.89726 107.75274)
		(end 99.775 107.75274)
		(width 0.15)
		(layer "In2.Cu")
		(net 409)
	)
	(segment
		(start 100.019521 107.27226)
		(end 100.016455 107.245054)
		(width 0.15)
		(layer "In2.Cu")
		(net 409)
	)
	(segment
		(start 99.679946 106.846934)
		(end 99.705787 106.837892)
		(width 0.15)
		(layer "In2.Cu")
		(net 409)
	)
	(segment
		(start 99.762893 106.780786)
		(end 99.771935 106.754945)
		(width 0.15)
		(layer "In2.Cu")
		(net 409)
	)
	(segment
		(start 99.542587 107.519213)
		(end 99.557153 107.496032)
		(width 0.15)
		(layer "In2.Cu")
		(net 409)
	)
	(segment
		(start 99.576512 107.123326)
		(end 99.557153 107.103967)
		(width 0.15)
		(layer "In2.Cu")
		(net 409)
	)
	(segment
		(start 99.530479 107.57226)
		(end 99.533545 107.545054)
		(width 0.15)
		(layer "In2.Cu")
		(net 409)
	)
	(segment
		(start 100.019521 107.875)
		(end 100.016455 107.847794)
		(width 0.15)
		(layer "In2.Cu")
		(net 409)
	)
	(segment
		(start 99.950307 107.162107)
		(end 99.924466 107.153065)
		(width 0.15)
		(layer "In2.Cu")
		(net 409)
	)
	(segment
		(start 99.973488 107.779413)
		(end 99.950307 107.764847)
		(width 0.15)
		(layer "In2.Cu")
		(net 409)
	)
	(segment
		(start 99.599693 107.137892)
		(end 99.576512 107.123326)
		(width 0.15)
		(layer "In2.Cu")
		(net 409)
	)
	(segment
		(start 100.019521 107.32774)
		(end 100.019521 107.27226)
		(width 0.15)
		(layer "In2.Cu")
		(net 409)
	)
	(segment
		(start 100.007413 107.983526)
		(end 100.016455 107.957685)
		(width 0.15)
		(layer "In2.Cu")
		(net 409)
	)
	(segment
		(start 99.625534 107.746934)
		(end 99.599693 107.737892)
		(width 0.15)
		(layer "In2.Cu")
		(net 409)
	)
	(segment
		(start 99.992847 107.196032)
		(end 99.973488 107.176673)
		(width 0.15)
		(layer "In2.Cu")
		(net 409)
	)
	(segment
		(start 99.599693 107.462107)
		(end 99.625534 107.453065)
		(width 0.15)
		(layer "In2.Cu")
		(net 409)
	)
	(segment
		(start 99.557153 107.703967)
		(end 99.542587 107.680786)
		(width 0.15)
		(layer "In2.Cu")
		(net 409)
	)
	(segment
		(start 99.533545 107.545054)
		(end 99.542587 107.519213)
		(width 0.15)
		(layer "In2.Cu")
		(net 409)
	)
	(segment
		(start 99.787107 108.121953)
		(end 99.801673 108.098772)
		(width 0.15)
		(layer "In2.Cu")
		(net 409)
	)
	(segment
		(start 99.748327 106.803967)
		(end 99.762893 106.780786)
		(width 0.15)
		(layer "In2.Cu")
		(net 409)
	)
	(segment
		(start 99.897261 107.45)
		(end 99.924466 107.446934)
		(width 0.15)
		(layer "In2.Cu")
		(net 409)
	)
	(segment
		(start 99.599693 107.737892)
		(end 99.576512 107.723326)
		(width 0.15)
		(layer "In2.Cu")
		(net 409)
	)
	(segment
		(start 99.973488 107.176673)
		(end 99.950307 107.162107)
		(width 0.15)
		(layer "In2.Cu")
		(net 409)
	)
	(segment
		(start 99.950307 108.040632)
		(end 99.973488 108.026066)
		(width 0.15)
		(layer "In2.Cu")
		(net 409)
	)
	(segment
		(start 100.007413 107.821953)
		(end 99.992847 107.798772)
		(width 0.15)
		(layer "In2.Cu")
		(net 409)
	)
	(segment
		(start 99.652739 107.15)
		(end 99.625534 107.146934)
		(width 0.15)
		(layer "In2.Cu")
		(net 409)
	)
	(segment
		(start 99.533545 107.054945)
		(end 99.530479 107.02774)
		(width 0.15)
		(layer "In2.Cu")
		(net 409)
	)
	(segment
		(start 100.007413 107.219213)
		(end 99.992847 107.196032)
		(width 0.15)
		(layer "In2.Cu")
		(net 409)
	)
	(segment
		(start 99.557153 107.103967)
		(end 99.542587 107.080786)
		(width 0.15)
		(layer "In2.Cu")
		(net 409)
	)
	(segment
		(start 100.825 101.45)
		(end 100.85 101.45)
		(width 0.15)
		(layer "In2.Cu")
		(net 409)
	)
	(segment
		(start 99.950307 107.437892)
		(end 99.973488 107.423326)
		(width 0.15)
		(layer "In2.Cu")
		(net 409)
	)
	(segment
		(start 100.007413 107.380786)
		(end 100.016455 107.354945)
		(width 0.15)
		(layer "In2.Cu")
		(net 409)
	)
	(segment
		(start 99.950307 107.764847)
		(end 99.924466 107.755805)
		(width 0.15)
		(layer "In2.Cu")
		(net 409)
	)
	(segment
		(start 99.728968 106.823326)
		(end 99.748327 106.803967)
		(width 0.15)
		(layer "In2.Cu")
		(net 409)
	)
	(segment
		(start 99.275 109.675)
		(end 99.775 109.175)
		(width 0.15)
		(layer "In2.Cu")
		(net 409)
	)
	(segment
		(start 99.705787 106.837892)
		(end 99.728968 106.823326)
		(width 0.15)
		(layer "In2.Cu")
		(net 409)
	)
	(segment
		(start 99.973488 108.026066)
		(end 99.992847 108.006707)
		(width 0.15)
		(layer "In2.Cu")
		(net 409)
	)
	(segment
		(start 99.576512 106.876673)
		(end 99.599693 106.862107)
		(width 0.15)
		(layer "In2.Cu")
		(net 409)
	)
	(segment
		(start 99.625534 107.146934)
		(end 99.599693 107.137892)
		(width 0.15)
		(layer "In2.Cu")
		(net 409)
	)
	(segment
		(start 99.897261 107.15)
		(end 99.652739 107.15)
		(width 0.15)
		(layer "In2.Cu")
		(net 409)
	)
	(segment
		(start 99.992847 108.006707)
		(end 100.007413 107.983526)
		(width 0.15)
		(layer "In2.Cu")
		(net 409)
	)
	(segment
		(start 100.016455 107.957685)
		(end 100.019521 107.93048)
		(width 0.15)
		(layer "In2.Cu")
		(net 409)
	)
	(segment
		(start 100.016455 107.847794)
		(end 100.007413 107.821953)
		(width 0.15)
		(layer "In2.Cu")
		(net 409)
	)
	(segment
		(start 99.625534 107.453065)
		(end 99.652739 107.45)
		(width 0.15)
		(layer "In2.Cu")
		(net 409)
	)
	(segment
		(start 99.775 107.75)
		(end 99.652739 107.75)
		(width 0.15)
		(layer "In2.Cu")
		(net 409)
	)
	(segment
		(start 99.870054 108.055805)
		(end 99.924466 108.049674)
		(width 0.15)
		(layer "In2.Cu")
		(net 409)
	)
	(segment
		(start 99.924466 108.049674)
		(end 99.950307 108.040632)
		(width 0.15)
		(layer "In2.Cu")
		(net 409)
	)
	(segment
		(start 99.652739 107.75)
		(end 99.625534 107.746934)
		(width 0.15)
		(layer "In2.Cu")
		(net 409)
	)
	(segment
		(start 100.019521 107.93048)
		(end 100.019521 107.875)
		(width 0.15)
		(layer "In2.Cu")
		(net 409)
	)
	(segment
		(start 100.016455 107.354945)
		(end 100.019521 107.32774)
		(width 0.15)
		(layer "In2.Cu")
		(net 409)
	)
	(segment
		(start 99.844213 108.064847)
		(end 99.870054 108.055805)
		(width 0.15)
		(layer "In2.Cu")
		(net 409)
	)
	(segment
		(start 99.530479 107.02774)
		(end 99.530479 106.97226)
		(width 0.15)
		(layer "In2.Cu")
		(net 409)
	)
	(segment
		(start 99.775 107.75274)
		(end 99.775 107.75)
		(width 0.15)
		(layer "In2.Cu")
		(net 409)
	)
	(segment
		(start 99.652739 107.45)
		(end 99.897261 107.45)
		(width 0.15)
		(layer "In2.Cu")
		(net 409)
	)
	(segment
		(start 99.992847 107.403967)
		(end 100.007413 107.380786)
		(width 0.15)
		(layer "In2.Cu")
		(net 409)
	)
	(segment
		(start 99.557153 106.896032)
		(end 99.576512 106.876673)
		(width 0.15)
		(layer "In2.Cu")
		(net 409)
	)
	(segment
		(start 99.924466 107.153065)
		(end 99.897261 107.15)
		(width 0.15)
		(layer "In2.Cu")
		(net 409)
	)
	(segment
		(start 99.533545 107.654945)
		(end 99.530479 107.62774)
		(width 0.15)
		(layer "In2.Cu")
		(net 409)
	)
	(segment
		(start 99.625534 106.853065)
		(end 99.679946 106.846934)
		(width 0.15)
		(layer "In2.Cu")
		(net 409)
	)
	(segment
		(start 99.775 102.5)
		(end 100.825 101.45)
		(width 0.15)
		(layer "In2.Cu")
		(net 409)
	)
	(segment
		(start 99.778065 108.147794)
		(end 99.787107 108.121953)
		(width 0.15)
		(layer "In2.Cu")
		(net 409)
	)
	(segment
		(start 99.775 106.72774)
		(end 99.775 102.5)
		(width 0.15)
		(layer "In2.Cu")
		(net 409)
	)
	(segment
		(start 99.775 109.175)
		(end 99.775 108.175)
		(width 0.15)
		(layer "In2.Cu")
		(net 409)
	)
	(segment
		(start 99.801673 108.098772)
		(end 99.821032 108.079413)
		(width 0.15)
		(layer "In2.Cu")
		(net 409)
	)
	(segment
		(start 99.775 108.175)
		(end 99.778065 108.147794)
		(width 0.15)
		(layer "In2.Cu")
		(net 409)
	)
	(segment
		(start 99.973488 107.423326)
		(end 99.992847 107.403967)
		(width 0.15)
		(layer "In2.Cu")
		(net 409)
	)
	(segment
		(start 99.576512 107.723326)
		(end 99.557153 107.703967)
		(width 0.15)
		(layer "In2.Cu")
		(net 409)
	)
	(segment
		(start 99.771935 106.754945)
		(end 99.775 106.72774)
		(width 0.15)
		(layer "In2.Cu")
		(net 409)
	)
	(segment
		(start 99.542587 107.680786)
		(end 99.533545 107.654945)
		(width 0.15)
		(layer "In2.Cu")
		(net 409)
	)
	(segment
		(start 99.530479 107.62774)
		(end 99.530479 107.57226)
		(width 0.15)
		(layer "In2.Cu")
		(net 409)
	)
	(segment
		(start 99.599693 106.862107)
		(end 99.625534 106.853065)
		(width 0.15)
		(layer "In2.Cu")
		(net 409)
	)
	(segment
		(start 99.992847 107.798772)
		(end 99.973488 107.779413)
		(width 0.15)
		(layer "In2.Cu")
		(net 409)
	)
	(segment
		(start 99.533545 106.945054)
		(end 99.542587 106.919213)
		(width 0.15)
		(layer "In2.Cu")
		(net 409)
	)
	(segment
		(start 99.557153 107.496032)
		(end 99.576512 107.476673)
		(width 0.15)
		(layer "In2.Cu")
		(net 409)
	)
	(segment
		(start 99.576512 107.476673)
		(end 99.599693 107.462107)
		(width 0.15)
		(layer "In2.Cu")
		(net 409)
	)
	(segment
		(start 99.542587 106.919213)
		(end 99.557153 106.896032)
		(width 0.15)
		(layer "In2.Cu")
		(net 409)
	)
	(segment
		(start 99.542587 107.080786)
		(end 99.533545 107.054945)
		(width 0.15)
		(layer "In2.Cu")
		(net 409)
	)
	(segment
		(start 99.821032 108.079413)
		(end 99.844213 108.064847)
		(width 0.15)
		(layer "In2.Cu")
		(net 409)
	)
	(segment
		(start 99.924466 107.446934)
		(end 99.950307 107.437892)
		(width 0.15)
		(layer "In2.Cu")
		(net 409)
	)
	(segment
		(start 100.35 99.652149)
		(end 100.35 100.8)
		(width 0.15)
		(layer "F.Cu")
		(net 410)
	)
	(segment
		(start 99.775 109.175)
		(end 99.275 108.675)
		(width 0.1)
		(layer "F.Cu")
		(net 410)
	)
	(via blind
		(at 99.275 108.675)
		(size 0.5)
		(drill 0.2)
		(layers "F.Cu" "In2.Cu")
		(net 410)
	)
	(via
		(at 100.35 100.8)
		(size 0.5)
		(drill 0.2)
		(layers "F.Cu" "B.Cu")
		(net 410)
	)
	(segment
		(start 99.75 101.4)
		(end 100.35 100.8)
		(width 0.15)
		(layer "B.Cu")
		(net 410)
	)
	(segment
		(start 99.75 102.415)
		(end 99.75 101.4)
		(width 0.15)
		(layer "B.Cu")
		(net 410)
	)
	(segment
		(start 99.229167 103.470171)
		(end 99.206087 103.484674)
		(width 0.15)
		(layer "In2.Cu")
		(net 410)
	)
	(segment
		(start 99.100453 105.312054)
		(end 99.077373 105.326557)
		(width 0.15)
		(layer "In2.Cu")
		(net 410)
	)
	(segment
		(start 99.043595 104.768912)
		(end 99.034593 104.794641)
		(width 0.15)
		(layer "In2.Cu")
		(net 410)
	)
	(segment
		(start 99.031541 105.421729)
		(end 99.031541 105.478271)
		(width 0.15)
		(layer "In2.Cu")
		(net 410)
	)
	(segment
		(start 99.518459 105.778271)
		(end 99.515407 105.805358)
		(width 0.15)
		(layer "In2.Cu")
		(net 410)
	)
	(segment
		(start 99.39673 105.6)
		(end 99.423818 105.603052)
		(width 0.15)
		(layer "In2.Cu")
		(net 410)
	)
	(segment
		(start 99.423818 103.803052)
		(end 99.449547 103.812054)
		(width 0.15)
		(layer "In2.Cu")
		(net 410)
	)
	(segment
		(start 99.39673 104.1)
		(end 99.15327 104.1)
		(width 0.15)
		(layer "In2.Cu")
		(net 410)
	)
	(segment
		(start 99.100453 103.784674)
		(end 99.126182 103.793676)
		(width 0.15)
		(layer "In2.Cu")
		(net 410)
	)
	(segment
		(start 99.058098 103.542561)
		(end 99.043595 103.565641)
		(width 0.15)
		(layer "In2.Cu")
		(net 410)
	)
	(segment
		(start 99.275 103.375)
		(end 99.271947 103.402087)
		(width 0.15)
		(layer "In2.Cu")
		(net 410)
	)
	(segment
		(start 99.518459 105.721729)
		(end 99.518459 105.778271)
		(width 0.15)
		(layer "In2.Cu")
		(net 410)
	)
	(segment
		(start 99.126182 103.793676)
		(end 99.153271 103.796729)
		(width 0.15)
		(layer "In2.Cu")
		(net 410)
	)
	(segment
		(start 99.034593 105.994641)
		(end 99.031541 106.021729)
		(width 0.15)
		(layer "In2.Cu")
		(net 410)
	)
	(segment
		(start 99.287055 106.568912)
		(end 99.278053 106.594641)
		(width 0.15)
		(layer "In2.Cu")
		(net 410)
	)
	(segment
		(start 99.034593 105.505358)
		(end 99.043595 105.531087)
		(width 0.15)
		(layer "In2.Cu")
		(net 410)
	)
	(segment
		(start 99.077373 105.926557)
		(end 99.058098 105.945832)
		(width 0.15)
		(layer "In2.Cu")
		(net 410)
	)
	(segment
		(start 99.449547 104.087945)
		(end 99.423818 104.096947)
		(width 0.15)
		(layer "In2.Cu")
		(net 410)
	)
	(segment
		(start 99.034593 104.305358)
		(end 99.043595 104.331087)
		(width 0.15)
		(layer "In2.Cu")
		(net 410)
	)
	(segment
		(start 99.423818 104.696947)
		(end 99.39673 104.7)
		(width 0.15)
		(layer "In2.Cu")
		(net 410)
	)
	(segment
		(start 99.15327 104.1)
		(end 99.126182 104.103052)
		(width 0.15)
		(layer "In2.Cu")
		(net 410)
	)
	(segment
		(start 99.034593 106.105358)
		(end 99.043595 106.131087)
		(width 0.15)
		(layer "In2.Cu")
		(net 410)
	)
	(segment
		(start 99.058098 104.954167)
		(end 99.077373 104.973442)
		(width 0.15)
		(layer "In2.Cu")
		(net 410)
	)
	(segment
		(start 99.449547 105.612054)
		(end 99.472627 105.626557)
		(width 0.15)
		(layer "In2.Cu")
		(net 410)
	)
	(segment
		(start 99.058098 105.554167)
		(end 99.077373 105.573442)
		(width 0.15)
		(layer "In2.Cu")
		(net 410)
	)
	(segment
		(start 99.126182 104.703052)
		(end 99.100453 104.712054)
		(width 0.15)
		(layer "In2.Cu")
		(net 410)
	)
	(segment
		(start 99.423818 105.896947)
		(end 99.39673 105.9)
		(width 0.15)
		(layer "In2.Cu")
		(net 410)
	)
	(segment
		(start 99.034593 104.905358)
		(end 99.043595 104.931087)
		(width 0.15)
		(layer "In2.Cu")
		(net 410)
	)
	(segment
		(start 99.15327 105.9)
		(end 99.126182 105.903052)
		(width 0.15)
		(layer "In2.Cu")
		(net 410)
	)
	(segment
		(start 99.058098 104.145832)
		(end 99.043595 104.168912)
		(width 0.15)
		(layer "In2.Cu")
		(net 410)
	)
	(segment
		(start 99.491902 104.654167)
		(end 99.472627 104.673442)
		(width 0.15)
		(layer "In2.Cu")
		(net 410)
	)
	(segment
		(start 99.518459 104.521729)
		(end 99.518459 104.578271)
		(width 0.15)
		(layer "In2.Cu")
		(net 410)
	)
	(segment
		(start 99.077373 104.126557)
		(end 99.058098 104.145832)
		(width 0.15)
		(layer "In2.Cu")
		(net 410)
	)
	(segment
		(start 99.126182 106.196947)
		(end 99.15327 106.2)
		(width 0.15)
		(layer "In2.Cu")
		(net 410)
	)
	(segment
		(start 99.100453 104.987945)
		(end 99.126182 104.996947)
		(width 0.15)
		(layer "In2.Cu")
		(net 410)
	)
	(segment
		(start 99.472627 105.026557)
		(end 99.491902 105.045832)
		(width 0.15)
		(layer "In2.Cu")
		(net 410)
	)
	(segment
		(start 99.043595 106.131087)
		(end 99.058098 106.154167)
		(width 0.15)
		(layer "In2.Cu")
		(net 410)
	)
	(segment
		(start 99.506405 105.668912)
		(end 99.515407 105.694641)
		(width 0.15)
		(layer "In2.Cu")
		(net 410)
	)
	(segment
		(start 99.506405 105.068912)
		(end 99.515407 105.094641)
		(width 0.15)
		(layer "In2.Cu")
		(net 410)
	)
	(segment
		(start 99.515407 104.605358)
		(end 99.506405 104.631087)
		(width 0.15)
		(layer "In2.Cu")
		(net 410)
	)
	(segment
		(start 99.271947 103.402087)
		(end 99.262945 103.427816)
		(width 0.15)
		(layer "In2.Cu")
		(net 410)
	)
	(segment
		(start 99.39673 103.8)
		(end 99.423818 103.803052)
		(width 0.15)
		(layer "In2.Cu")
		(net 410)
	)
	(segment
		(start 99.077373 104.973442)
		(end 99.100453 104.987945)
		(width 0.15)
		(layer "In2.Cu")
		(net 410)
	)
	(segment
		(start 99.031541 103.675)
		(end 99.034593 103.702087)
		(width 0.15)
		(layer "In2.Cu")
		(net 410)
	)
	(segment
		(start 99.39673 105.9)
		(end 99.15327 105.9)
		(width 0.15)
		(layer "In2.Cu")
		(net 410)
	)
	(segment
		(start 99.515407 103.894641)
		(end 99.518459 103.921729)
		(width 0.15)
		(layer "In2.Cu")
		(net 410)
	)
	(segment
		(start 99.515407 106.294641)
		(end 99.518459 106.321729)
		(width 0.15)
		(layer "In2.Cu")
		(net 410)
	)
	(segment
		(start 99.100453 105.587945)
		(end 99.126182 105.596947)
		(width 0.15)
		(layer "In2.Cu")
		(net 410)
	)
	(segment
		(start 99.515407 105.805358)
		(end 99.506405 105.831087)
		(width 0.15)
		(layer "In2.Cu")
		(net 410)
	)
	(segment
		(start 99.39673 105.3)
		(end 99.15327 105.3)
		(width 0.15)
		(layer "In2.Cu")
		(net 410)
	)
	(segment
		(start 99.15327 105.6)
		(end 99.39673 105.6)
		(width 0.15)
		(layer "In2.Cu")
		(net 410)
	)
	(segment
		(start 99.491902 105.645832)
		(end 99.506405 105.668912)
		(width 0.15)
		(layer "In2.Cu")
		(net 410)
	)
	(segment
		(start 99.472627 104.073442)
		(end 99.449547 104.087945)
		(width 0.15)
		(layer "In2.Cu")
		(net 410)
	)
	(segment
		(start 99.491902 103.845832)
		(end 99.506405 103.868912)
		(width 0.15)
		(layer "In2.Cu")
		(net 410)
	)
	(segment
		(start 99.077373 103.770171)
		(end 99.100453 103.784674)
		(width 0.15)
		(layer "In2.Cu")
		(net 410)
	)
	(segment
		(start 99.031541 104.278271)
		(end 99.034593 104.305358)
		(width 0.15)
		(layer "In2.Cu")
		(net 410)
	)
	(segment
		(start 99.472627 106.226557)
		(end 99.491902 106.245832)
		(width 0.15)
		(layer "In2.Cu")
		(net 410)
	)
	(segment
		(start 99.320833 106.526557)
		(end 99.301558 106.545832)
		(width 0.15)
		(layer "In2.Cu")
		(net 410)
	)
	(segment
		(start 99.034593 103.702087)
		(end 99.043595 103.727816)
		(width 0.15)
		(layer "In2.Cu")
		(net 410)
	)
	(segment
		(start 99.518459 104.578271)
		(end 99.515407 104.605358)
		(width 0.15)
		(layer "In2.Cu")
		(net 410)
	)
	(segment
		(start 99.491902 104.445832)
		(end 99.506405 104.468912)
		(width 0.15)
		(layer "In2.Cu")
		(net 410)
	)
	(segment
		(start 100.35 101.1)
		(end 99.275 102.175)
		(width 0.15)
		(layer "In2.Cu")
		(net 410)
	)
	(segment
		(start 99.491902 106.454167)
		(end 99.472627 106.473442)
		(width 0.15)
		(layer "In2.Cu")
		(net 410)
	)
	(segment
		(start 99.518459 105.121729)
		(end 99.518459 105.178271)
		(width 0.15)
		(layer "In2.Cu")
		(net 410)
	)
	(segment
		(start 99.077373 103.523286)
		(end 99.058098 103.542561)
		(width 0.15)
		(layer "In2.Cu")
		(net 410)
	)
	(segment
		(start 99.100453 104.712054)
		(end 99.077373 104.726557)
		(width 0.15)
		(layer "In2.Cu")
		(net 410)
	)
	(segment
		(start 99.472627 105.626557)
		(end 99.491902 105.645832)
		(width 0.15)
		(layer "In2.Cu")
		(net 410)
	)
	(segment
		(start 99.262945 103.427816)
		(end 99.248442 103.450896)
		(width 0.15)
		(layer "In2.Cu")
		(net 410)
	)
	(segment
		(start 99.031541 104.878271)
		(end 99.034593 104.905358)
		(width 0.15)
		(layer "In2.Cu")
		(net 410)
	)
	(segment
		(start 99.100453 103.508783)
		(end 99.077373 103.523286)
		(width 0.15)
		(layer "In2.Cu")
		(net 410)
	)
	(segment
		(start 99.506405 105.231087)
		(end 99.491902 105.254167)
		(width 0.15)
		(layer "In2.Cu")
		(net 410)
	)
	(segment
		(start 99.043595 104.931087)
		(end 99.058098 104.954167)
		(width 0.15)
		(layer "In2.Cu")
		(net 410)
	)
	(segment
		(start 99.043595 104.168912)
		(end 99.034593 104.194641)
		(width 0.15)
		(layer "In2.Cu")
		(net 410)
	)
	(segment
		(start 99.472627 104.426557)
		(end 99.491902 104.445832)
		(width 0.15)
		(layer "In2.Cu")
		(net 410)
	)
	(segment
		(start 99.275 103.8)
		(end 99.39673 103.8)
		(width 0.15)
		(layer "In2.Cu")
		(net 410)
	)
	(segment
		(start 99.506405 104.468912)
		(end 99.515407 104.494641)
		(width 0.15)
		(layer "In2.Cu")
		(net 410)
	)
	(segment
		(start 99.423818 104.403052)
		(end 99.449547 104.412054)
		(width 0.15)
		(layer "In2.Cu")
		(net 410)
	)
	(segment
		(start 99.423818 105.603052)
		(end 99.449547 105.612054)
		(width 0.15)
		(layer "In2.Cu")
		(net 410)
	)
	(segment
		(start 99.275 106.621729)
		(end 99.275 108.675)
		(width 0.15)
		(layer "In2.Cu")
		(net 410)
	)
	(segment
		(start 99.126182 105.303052)
		(end 99.100453 105.312054)
		(width 0.15)
		(layer "In2.Cu")
		(net 410)
	)
	(segment
		(start 99.100453 106.187945)
		(end 99.126182 106.196947)
		(width 0.15)
		(layer "In2.Cu")
		(net 410)
	)
	(segment
		(start 99.515407 104.005358)
		(end 99.506405 104.031087)
		(width 0.15)
		(layer "In2.Cu")
		(net 410)
	)
	(segment
		(start 99.15327 104.7)
		(end 99.126182 104.703052)
		(width 0.15)
		(layer "In2.Cu")
		(net 410)
	)
	(segment
		(start 99.423818 105.296947)
		(end 99.39673 105.3)
		(width 0.15)
		(layer "In2.Cu")
		(net 410)
	)
	(segment
		(start 99.126182 104.996947)
		(end 99.15327 105)
		(width 0.15)
		(layer "In2.Cu")
		(net 410)
	)
	(segment
		(start 99.423818 106.496947)
		(end 99.369642 106.503052)
		(width 0.15)
		(layer "In2.Cu")
		(net 410)
	)
	(segment
		(start 99.031541 104.221729)
		(end 99.031541 104.278271)
		(width 0.15)
		(layer "In2.Cu")
		(net 410)
	)
	(segment
		(start 99.472627 103.826557)
		(end 99.491902 103.845832)
		(width 0.15)
		(layer "In2.Cu")
		(net 410)
	)
	(segment
		(start 99.058098 106.154167)
		(end 99.077373 106.173442)
		(width 0.15)
		(layer "In2.Cu")
		(net 410)
	)
	(segment
		(start 99.506405 104.031087)
		(end 99.491902 104.054167)
		(width 0.15)
		(layer "In2.Cu")
		(net 410)
	)
	(segment
		(start 99.301558 106.545832)
		(end 99.287055 106.568912)
		(width 0.15)
		(layer "In2.Cu")
		(net 410)
	)
	(segment
		(start 99.518459 103.978271)
		(end 99.515407 104.005358)
		(width 0.15)
		(layer "In2.Cu")
		(net 410)
	)
	(segment
		(start 99.100453 104.387945)
		(end 99.126182 104.396947)
		(width 0.15)
		(layer "In2.Cu")
		(net 410)
	)
	(segment
		(start 99.031541 105.478271)
		(end 99.034593 105.505358)
		(width 0.15)
		(layer "In2.Cu")
		(net 410)
	)
	(segment
		(start 99.034593 103.59137)
		(end 99.031541 103.618458)
		(width 0.15)
		(layer "In2.Cu")
		(net 410)
	)
	(segment
		(start 99.077373 105.326557)
		(end 99.058098 105.345832)
		(width 0.15)
		(layer "In2.Cu")
		(net 410)
	)
	(segment
		(start 99.206087 103.484674)
		(end 99.180358 103.493676)
		(width 0.15)
		(layer "In2.Cu")
		(net 410)
	)
	(segment
		(start 99.518459 106.378271)
		(end 99.515407 106.405358)
		(width 0.15)
		(layer "In2.Cu")
		(net 410)
	)
	(segment
		(start 99.343913 106.512054)
		(end 99.320833 106.526557)
		(width 0.15)
		(layer "In2.Cu")
		(net 410)
	)
	(segment
		(start 99.491902 106.245832)
		(end 99.506405 106.268912)
		(width 0.15)
		(layer "In2.Cu")
		(net 410)
	)
	(segment
		(start 99.449547 105.887945)
		(end 99.423818 105.896947)
		(width 0.15)
		(layer "In2.Cu")
		(net 410)
	)
	(segment
		(start 99.043595 103.565641)
		(end 99.034593 103.59137)
		(width 0.15)
		(layer "In2.Cu")
		(net 410)
	)
	(segment
		(start 99.031541 106.021729)
		(end 99.031541 106.078271)
		(width 0.15)
		(layer "In2.Cu")
		(net 410)
	)
	(segment
		(start 99.472627 106.473442)
		(end 99.449547 106.487945)
		(width 0.15)
		(layer "In2.Cu")
		(net 410)
	)
	(segment
		(start 99.515407 106.405358)
		(end 99.506405 106.431087)
		(width 0.15)
		(layer "In2.Cu")
		(net 410)
	)
	(segment
		(start 99.491902 104.054167)
		(end 99.472627 104.073442)
		(width 0.15)
		(layer "In2.Cu")
		(net 410)
	)
	(segment
		(start 99.031541 103.618458)
		(end 99.031541 103.675)
		(width 0.15)
		(layer "In2.Cu")
		(net 410)
	)
	(segment
		(start 99.449547 106.212054)
		(end 99.472627 106.226557)
		(width 0.15)
		(layer "In2.Cu")
		(net 410)
	)
	(segment
		(start 99.449547 105.012054)
		(end 99.472627 105.026557)
		(width 0.15)
		(layer "In2.Cu")
		(net 410)
	)
	(segment
		(start 99.126182 104.103052)
		(end 99.100453 104.112054)
		(width 0.15)
		(layer "In2.Cu")
		(net 410)
	)
	(segment
		(start 99.15327 105.3)
		(end 99.126182 105.303052)
		(width 0.15)
		(layer "In2.Cu")
		(net 410)
	)
	(segment
		(start 99.506405 105.831087)
		(end 99.491902 105.854167)
		(width 0.15)
		(layer "In2.Cu")
		(net 410)
	)
	(segment
		(start 99.043595 105.968912)
		(end 99.034593 105.994641)
		(width 0.15)
		(layer "In2.Cu")
		(net 410)
	)
	(segment
		(start 99.126182 103.499781)
		(end 99.100453 103.508783)
		(width 0.15)
		(layer "In2.Cu")
		(net 410)
	)
	(segment
		(start 99.275 103.796729)
		(end 99.275 103.8)
		(width 0.15)
		(layer "In2.Cu")
		(net 410)
	)
	(segment
		(start 99.449547 103.812054)
		(end 99.472627 103.826557)
		(width 0.15)
		(layer "In2.Cu")
		(net 410)
	)
	(segment
		(start 99.518459 105.178271)
		(end 99.515407 105.205358)
		(width 0.15)
		(layer "In2.Cu")
		(net 410)
	)
	(segment
		(start 99.043595 105.531087)
		(end 99.058098 105.554167)
		(width 0.15)
		(layer "In2.Cu")
		(net 410)
	)
	(segment
		(start 99.472627 105.873442)
		(end 99.449547 105.887945)
		(width 0.15)
		(layer "In2.Cu")
		(net 410)
	)
	(segment
		(start 99.031541 106.078271)
		(end 99.034593 106.105358)
		(width 0.15)
		(layer "In2.Cu")
		(net 410)
	)
	(segment
		(start 99.058098 105.345832)
		(end 99.043595 105.368912)
		(width 0.15)
		(layer "In2.Cu")
		(net 410)
	)
	(segment
		(start 99.248442 103.450896)
		(end 99.229167 103.470171)
		(width 0.15)
		(layer "In2.Cu")
		(net 410)
	)
	(segment
		(start 99.491902 105.254167)
		(end 99.472627 105.273442)
		(width 0.15)
		(layer "In2.Cu")
		(net 410)
	)
	(segment
		(start 100.35 100.8)
		(end 100.35 101.1)
		(width 0.15)
		(layer "In2.Cu")
		(net 410)
	)
	(segment
		(start 99.472627 105.273442)
		(end 99.449547 105.287945)
		(width 0.15)
		(layer "In2.Cu")
		(net 410)
	)
	(segment
		(start 99.043595 103.727816)
		(end 99.058098 103.750896)
		(width 0.15)
		(layer "In2.Cu")
		(net 410)
	)
	(segment
		(start 99.034593 105.394641)
		(end 99.031541 105.421729)
		(width 0.15)
		(layer "In2.Cu")
		(net 410)
	)
	(segment
		(start 99.506405 103.868912)
		(end 99.515407 103.894641)
		(width 0.15)
		(layer "In2.Cu")
		(net 410)
	)
	(segment
		(start 99.515407 105.205358)
		(end 99.506405 105.231087)
		(width 0.15)
		(layer "In2.Cu")
		(net 410)
	)
	(segment
		(start 99.153271 103.796729)
		(end 99.275 103.796729)
		(width 0.15)
		(layer "In2.Cu")
		(net 410)
	)
	(segment
		(start 99.39673 106.2)
		(end 99.423818 106.203052)
		(width 0.15)
		(layer "In2.Cu")
		(net 410)
	)
	(segment
		(start 99.449547 106.487945)
		(end 99.423818 106.496947)
		(width 0.15)
		(layer "In2.Cu")
		(net 410)
	)
	(segment
		(start 99.449547 105.287945)
		(end 99.423818 105.296947)
		(width 0.15)
		(layer "In2.Cu")
		(net 410)
	)
	(segment
		(start 99.058098 105.945832)
		(end 99.043595 105.968912)
		(width 0.15)
		(layer "In2.Cu")
		(net 410)
	)
	(segment
		(start 99.034593 104.194641)
		(end 99.031541 104.221729)
		(width 0.15)
		(layer "In2.Cu")
		(net 410)
	)
	(segment
		(start 99.491902 105.045832)
		(end 99.506405 105.068912)
		(width 0.15)
		(layer "In2.Cu")
		(net 410)
	)
	(segment
		(start 99.126182 105.903052)
		(end 99.100453 105.912054)
		(width 0.15)
		(layer "In2.Cu")
		(net 410)
	)
	(segment
		(start 99.515407 105.094641)
		(end 99.518459 105.121729)
		(width 0.15)
		(layer "In2.Cu")
		(net 410)
	)
	(segment
		(start 99.077373 104.373442)
		(end 99.100453 104.387945)
		(width 0.15)
		(layer "In2.Cu")
		(net 410)
	)
	(segment
		(start 99.077373 104.726557)
		(end 99.058098 104.745832)
		(width 0.15)
		(layer "In2.Cu")
		(net 410)
	)
	(segment
		(start 99.15327 106.2)
		(end 99.39673 106.2)
		(width 0.15)
		(layer "In2.Cu")
		(net 410)
	)
	(segment
		(start 99.15327 105)
		(end 99.39673 105)
		(width 0.15)
		(layer "In2.Cu")
		(net 410)
	)
	(segment
		(start 99.100453 104.112054)
		(end 99.077373 104.126557)
		(width 0.15)
		(layer "In2.Cu")
		(net 410)
	)
	(segment
		(start 99.39673 104.4)
		(end 99.423818 104.403052)
		(width 0.15)
		(layer "In2.Cu")
		(net 410)
	)
	(segment
		(start 99.449547 104.412054)
		(end 99.472627 104.426557)
		(width 0.15)
		(layer "In2.Cu")
		(net 410)
	)
	(segment
		(start 99.180358 103.493676)
		(end 99.126182 103.499781)
		(width 0.15)
		(layer "In2.Cu")
		(net 410)
	)
	(segment
		(start 99.518459 103.921729)
		(end 99.518459 103.978271)
		(width 0.15)
		(layer "In2.Cu")
		(net 410)
	)
	(segment
		(start 99.39673 104.7)
		(end 99.15327 104.7)
		(width 0.15)
		(layer "In2.Cu")
		(net 410)
	)
	(segment
		(start 99.423818 106.203052)
		(end 99.449547 106.212054)
		(width 0.15)
		(layer "In2.Cu")
		(net 410)
	)
	(segment
		(start 99.058098 104.354167)
		(end 99.077373 104.373442)
		(width 0.15)
		(layer "In2.Cu")
		(net 410)
	)
	(segment
		(start 99.506405 106.268912)
		(end 99.515407 106.294641)
		(width 0.15)
		(layer "In2.Cu")
		(net 410)
	)
	(segment
		(start 99.077373 105.573442)
		(end 99.100453 105.587945)
		(width 0.15)
		(layer "In2.Cu")
		(net 410)
	)
	(segment
		(start 99.031541 104.821729)
		(end 99.031541 104.878271)
		(width 0.15)
		(layer "In2.Cu")
		(net 410)
	)
	(segment
		(start 99.518459 106.321729)
		(end 99.518459 106.378271)
		(width 0.15)
		(layer "In2.Cu")
		(net 410)
	)
	(segment
		(start 99.15327 104.4)
		(end 99.39673 104.4)
		(width 0.15)
		(layer "In2.Cu")
		(net 410)
	)
	(segment
		(start 99.278053 106.594641)
		(end 99.275 106.621729)
		(width 0.15)
		(layer "In2.Cu")
		(net 410)
	)
	(segment
		(start 99.449547 104.687945)
		(end 99.423818 104.696947)
		(width 0.15)
		(layer "In2.Cu")
		(net 410)
	)
	(segment
		(start 99.491902 105.854167)
		(end 99.472627 105.873442)
		(width 0.15)
		(layer "In2.Cu")
		(net 410)
	)
	(segment
		(start 99.506405 104.631087)
		(end 99.491902 104.654167)
		(width 0.15)
		(layer "In2.Cu")
		(net 410)
	)
	(segment
		(start 99.043595 104.331087)
		(end 99.058098 104.354167)
		(width 0.15)
		(layer "In2.Cu")
		(net 410)
	)
	(segment
		(start 99.034593 104.794641)
		(end 99.031541 104.821729)
		(width 0.15)
		(layer "In2.Cu")
		(net 410)
	)
	(segment
		(start 99.515407 104.494641)
		(end 99.518459 104.521729)
		(width 0.15)
		(layer "In2.Cu")
		(net 410)
	)
	(segment
		(start 99.126182 105.596947)
		(end 99.15327 105.6)
		(width 0.15)
		(layer "In2.Cu")
		(net 410)
	)
	(segment
		(start 99.126182 104.396947)
		(end 99.15327 104.4)
		(width 0.15)
		(layer "In2.Cu")
		(net 410)
	)
	(segment
		(start 99.058098 103.750896)
		(end 99.077373 103.770171)
		(width 0.15)
		(layer "In2.Cu")
		(net 410)
	)
	(segment
		(start 99.058098 104.745832)
		(end 99.043595 104.768912)
		(width 0.15)
		(layer "In2.Cu")
		(net 410)
	)
	(segment
		(start 99.515407 105.694641)
		(end 99.518459 105.721729)
		(width 0.15)
		(layer "In2.Cu")
		(net 410)
	)
	(segment
		(start 99.506405 106.431087)
		(end 99.491902 106.454167)
		(width 0.15)
		(layer "In2.Cu")
		(net 410)
	)
	(segment
		(start 99.369642 106.503052)
		(end 99.343913 106.512054)
		(width 0.15)
		(layer "In2.Cu")
		(net 410)
	)
	(segment
		(start 99.043595 105.368912)
		(end 99.034593 105.394641)
		(width 0.15)
		(layer "In2.Cu")
		(net 410)
	)
	(segment
		(start 99.275 102.175)
		(end 99.275 103.375)
		(width 0.15)
		(layer "In2.Cu")
		(net 410)
	)
	(segment
		(start 99.472627 104.673442)
		(end 99.449547 104.687945)
		(width 0.15)
		(layer "In2.Cu")
		(net 410)
	)
	(segment
		(start 99.423818 105.003052)
		(end 99.449547 105.012054)
		(width 0.15)
		(layer "In2.Cu")
		(net 410)
	)
	(segment
		(start 99.100453 105.912054)
		(end 99.077373 105.926557)
		(width 0.15)
		(layer "In2.Cu")
		(net 410)
	)
	(segment
		(start 99.077373 106.173442)
		(end 99.100453 106.187945)
		(width 0.15)
		(layer "In2.Cu")
		(net 410)
	)
	(segment
		(start 99.39673 105)
		(end 99.423818 105.003052)
		(width 0.15)
		(layer "In2.Cu")
		(net 410)
	)
	(segment
		(start 99.423818 104.096947)
		(end 99.39673 104.1)
		(width 0.15)
		(layer "In2.Cu")
		(net 410)
	)
	(segment
		(start 103.35 99.652149)
		(end 103.35 100.8)
		(width 0.15)
		(layer "F.Cu")
		(net 411)
	)
	(segment
		(start 101.775 109.175)
		(end 101.275 108.675)
		(width 0.1)
		(layer "F.Cu")
		(net 411)
	)
	(via
		(at 103.35 100.8)
		(size 0.5)
		(drill 0.2)
		(layers "F.Cu" "B.Cu")
		(net 411)
	)
	(via blind
		(at 101.275 108.675)
		(size 0.5)
		(drill 0.2)
		(layers "F.Cu" "In2.Cu")
		(net 411)
	)
	(segment
		(start 103.55 101)
		(end 103.35 100.8)
		(width 0.15)
		(layer "B.Cu")
		(net 411)
	)
	(segment
		(start 103.55 102.415)
		(end 103.55 101)
		(width 0.15)
		(layer "B.Cu")
		(net 411)
	)
	(segment
		(start 103.35 102.5)
		(end 103.35 100.8)
		(width 0.15)
		(layer "In2.Cu")
		(net 411)
	)
	(segment
		(start 101.275 108.675)
		(end 101.275 104.575)
		(width 0.15)
		(layer "In2.Cu")
		(net 411)
	)
	(segment
		(start 101.275 104.575)
		(end 103.35 102.5)
		(width 0.15)
		(layer "In2.Cu")
		(net 411)
	)
	(segment
		(start 104.35 99.702149)
		(end 104.35 100.85)
		(width 0.15)
		(layer "F.Cu")
		(net 412)
	)
	(segment
		(start 99.675 112.175)
		(end 99.3 111.8)
		(width 0.1)
		(layer "F.Cu")
		(net 412)
	)
	(segment
		(start 99.775 112.175)
		(end 99.675 112.175)
		(width 0.1)
		(layer "F.Cu")
		(net 412)
	)
	(via
		(at 104.35 100.85)
		(size 0.5)
		(drill 0.2)
		(layers "F.Cu" "B.Cu")
		(net 412)
	)
	(via blind
		(at 99.3 111.8)
		(size 0.5)
		(drill 0.2)
		(layers "F.Cu" "In2.Cu")
		(net 412)
	)
	(segment
		(start 104.35 102.265)
		(end 104.35 100.85)
		(width 0.15)
		(layer "B.Cu")
		(net 412)
	)
	(segment
		(start 104.5 102.415)
		(end 104.35 102.265)
		(width 0.15)
		(layer "B.Cu")
		(net 412)
	)
	(segment
		(start 99.3 111.8)
		(end 100.45 111.8)
		(width 0.15)
		(layer "In2.Cu")
		(net 412)
	)
	(segment
		(start 101.775 110.475)
		(end 101.775 104.975)
		(width 0.15)
		(layer "In2.Cu")
		(net 412)
	)
	(segment
		(start 101.775 104.975)
		(end 104.35 102.4)
		(width 0.15)
		(layer "In2.Cu")
		(net 412)
	)
	(segment
		(start 104.35 102.4)
		(end 104.35 100.85)
		(width 0.15)
		(layer "In2.Cu")
		(net 412)
	)
	(segment
		(start 100.45 111.8)
		(end 101.775 110.475)
		(width 0.15)
		(layer "In2.Cu")
		(net 412)
	)
	(segment
		(start 105.527149 96.975)
		(end 106.775 96.975)
		(width 0.15)
		(layer "F.Cu")
		(net 413)
	)
	(segment
		(start 97.775 112.175)
		(end 97.75 112.175)
		(width 0.1)
		(layer "F.Cu")
		(net 413)
	)
	(segment
		(start 97.75 112.175)
		(end 97.3 111.725)
		(width 0.1)
		(layer "F.Cu")
		(net 413)
	)
	(segment
		(start 106.775 96.975)
		(end 107.05 97.25)
		(width 0.15)
		(layer "F.Cu")
		(net 413)
	)
	(segment
		(start 107.05 97.25)
		(end 107.05 100.05)
		(width 0.15)
		(layer "F.Cu")
		(net 413)
	)
	(segment
		(start 107.05 100.05)
		(end 106.9 100.2)
		(width 0.15)
		(layer "F.Cu")
		(net 413)
	)
	(via
		(at 106.9 100.2)
		(size 0.5)
		(drill 0.2)
		(layers "F.Cu" "B.Cu")
		(net 413)
	)
	(via blind
		(at 97.3 111.725)
		(size 0.5)
		(drill 0.2)
		(layers "F.Cu" "In2.Cu")
		(net 413)
	)
	(segment
		(start 106.9 101.35)
		(end 106.9 100.2)
		(width 0.15)
		(layer "B.Cu")
		(net 413)
	)
	(segment
		(start 107.35 101.8)
		(end 106.9 101.35)
		(width 0.15)
		(layer "B.Cu")
		(net 413)
	)
	(segment
		(start 107.35 102.415)
		(end 107.35 101.8)
		(width 0.15)
		(layer "B.Cu")
		(net 413)
	)
	(segment
		(start 97.3 111.725)
		(end 97.800001 112.225001)
		(width 0.15)
		(layer "In2.Cu")
		(net 413)
	)
	(segment
		(start 106.9 102.85)
		(end 105.275 104.475)
		(width 0.15)
		(layer "In2.Cu")
		(net 413)
	)
	(segment
		(start 103.885882 108.276618)
		(end 105.275 106.8875)
		(width 0.15)
		(layer "In2.Cu")
		(net 413)
	)
	(segment
		(start 106.9 100.2)
		(end 106.9 102.85)
		(width 0.15)
		(layer "In2.Cu")
		(net 413)
	)
	(segment
		(start 103.885882 109.45162)
		(end 103.885882 108.276618)
		(width 0.15)
		(layer "In2.Cu")
		(net 413)
	)
	(segment
		(start 105.275 106.8875)
		(end 105.275 104.475)
		(width 0.15)
		(layer "In2.Cu")
		(net 413)
	)
	(segment
		(start 97.800001 112.225001)
		(end 101.624999 112.225001)
		(width 0.15)
		(layer "In2.Cu")
		(net 413)
	)
	(segment
		(start 101.624999 112.225001)
		(end 101.75 112.2125)
		(width 0.15)
		(layer "In2.Cu")
		(net 413)
	)
	(segment
		(start 101.75 112.2125)
		(end 102.700001 111.262499)
		(width 0.15)
		(layer "In2.Cu")
		(net 413)
	)
	(segment
		(start 102.700001 110.637501)
		(end 103.885882 109.45162)
		(width 0.15)
		(layer "In2.Cu")
		(net 413)
	)
	(segment
		(start 102.700001 111.262499)
		(end 102.700001 110.637501)
		(width 0.15)
		(layer "In2.Cu")
		(net 413)
	)
	(segment
		(start 102.8 113.15)
		(end 103.25 112.7)
		(width 0.1)
		(layer "F.Cu")
		(net 414)
	)
	(segment
		(start 105.527149 96.475)
		(end 107.075 96.475)
		(width 0.15)
		(layer "F.Cu")
		(net 414)
	)
	(segment
		(start 107.075 96.475)
		(end 107.349968 96.749968)
		(width 0.15)
		(layer "F.Cu")
		(net 414)
	)
	(segment
		(start 107.349968 96.749968)
		(end 107.349968 100.85)
		(width 0.15)
		(layer "F.Cu")
		(net 414)
	)
	(via blind
		(at 103.25 112.7)
		(size 0.5)
		(drill 0.2)
		(layers "F.Cu" "In2.Cu")
		(net 414)
	)
	(via
		(at 107.349968 100.85)
		(size 0.5)
		(drill 0.2)
		(layers "F.Cu" "B.Cu")
		(net 414)
	)
	(segment
		(start 108.3 102.415)
		(end 108.3 101.800032)
		(width 0.15)
		(layer "B.Cu")
		(net 414)
	)
	(segment
		(start 108.3 101.800032)
		(end 107.349968 100.85)
		(width 0.15)
		(layer "B.Cu")
		(net 414)
	)
	(segment
		(start 103.25 112.7)
		(end 103.25 111.7125)
		(width 0.15)
		(layer "In2.Cu")
		(net 414)
	)
	(segment
		(start 103.53125 111.43125)
		(end 104.76875 111.43125)
		(width 0.15)
		(layer "In2.Cu")
		(net 414)
	)
	(segment
		(start 103.25 111.7125)
		(end 103.53125 111.43125)
		(width 0.15)
		(layer "In2.Cu")
		(net 414)
	)
	(segment
		(start 107.349968 103.200032)
		(end 107.349968 100.85)
		(width 0.15)
		(layer "In2.Cu")
		(net 414)
	)
	(segment
		(start 105.775 104.775)
		(end 107.349968 103.200032)
		(width 0.15)
		(layer "In2.Cu")
		(net 414)
	)
	(segment
		(start 105.775 110.425)
		(end 105.775 104.775)
		(width 0.15)
		(layer "In2.Cu")
		(net 414)
	)
	(segment
		(start 104.76875 111.43125)
		(end 105.775 110.425)
		(width 0.15)
		(layer "In2.Cu")
		(net 414)
	)
	(segment
		(start 94.859999 94.714999)
		(end 93.939998 93.794998)
		(width 0.15)
		(layer "F.Cu")
		(net 415)
	)
	(segment
		(start 95.07 95.475)
		(end 94.859999 95.264999)
		(width 0.15)
		(layer "F.Cu")
		(net 415)
	)
	(segment
		(start 96.24 95.475)
		(end 96.225 95.49)
		(width 0.15)
		(layer "F.Cu")
		(net 415)
	)
	(segment
		(start 98.672851 95.475)
		(end 96.24 95.475)
		(width 0.15)
		(layer "F.Cu")
		(net 415)
	)
	(segment
		(start 93.939998 93.794998)
		(end 93.939998 92.54)
		(width 0.15)
		(layer "F.Cu")
		(net 415)
	)
	(segment
		(start 96.285 95.475)
		(end 95.07 95.475)
		(width 0.15)
		(layer "F.Cu")
		(net 415)
	)
	(segment
		(start 94.859999 95.264999)
		(end 94.859999 94.714999)
		(width 0.15)
		(layer "F.Cu")
		(net 415)
	)
	(via
		(at 93.939998 92.54)
		(size 0.5)
		(drill 0.2)
		(layers "F.Cu" "B.Cu")
		(net 415)
	)
	(segment
		(start 93.94 91.54)
		(end 93.94 92.539998)
		(width 0.15)
		(layer "B.Cu")
		(net 415)
	)
	(segment
		(start 93.94 92.539998)
		(end 93.939998 92.54)
		(width 0.15)
		(layer "B.Cu")
		(net 415)
	)
	(segment
		(start 95.25 93.005)
		(end 95.25 92.405)
		(width 0.15)
		(layer "F.Cu")
		(net 416)
	)
	(segment
		(start 94.75 93.505)
		(end 95.25 93.005)
		(width 0.15)
		(layer "F.Cu")
		(net 416)
	)
	(segment
		(start 98.672851 94.475)
		(end 96.295 94.475)
		(width 0.15)
		(layer "F.Cu")
		(net 416)
	)
	(segment
		(start 95.11 94.545)
		(end 94.75 94.185)
		(width 0.15)
		(layer "F.Cu")
		(net 416)
	)
	(segment
		(start 96.25 94.545)
		(end 95.11 94.545)
		(width 0.15)
		(layer "F.Cu")
		(net 416)
	)
	(segment
		(start 94.75 94.185)
		(end 94.75 93.505)
		(width 0.15)
		(layer "F.Cu")
		(net 416)
	)
	(segment
		(start 96.295 94.475)
		(end 96.225 94.545)
		(width 0.15)
		(layer "F.Cu")
		(net 416)
	)
	(via
		(at 95.25 92.405)
		(size 0.5)
		(drill 0.2)
		(layers "F.Cu" "B.Cu")
		(net 416)
	)
	(segment
		(start 95.25 92.405)
		(end 95.25 91.54)
		(width 0.15)
		(layer "B.Cu")
		(net 416)
	)
	(segment
		(start 106.075 98.475)
		(end 106.35 98.75)
		(width 0.15)
		(layer "F.Cu")
		(net 420)
	)
	(segment
		(start 102.775 111.175)
		(end 102.275 110.675)
		(width 0.1)
		(layer "F.Cu")
		(net 420)
	)
	(segment
		(start 106.35 98.75)
		(end 106.35 100.85)
		(width 0.15)
		(layer "F.Cu")
		(net 420)
	)
	(segment
		(start 105.527149 98.475)
		(end 106.075 98.475)
		(width 0.15)
		(layer "F.Cu")
		(net 420)
	)
	(via blind
		(at 102.275 110.675)
		(size 0.5)
		(drill 0.2)
		(layers "F.Cu" "In2.Cu")
		(net 420)
	)
	(via
		(at 106.35 100.85)
		(size 0.5)
		(drill 0.2)
		(layers "F.Cu" "B.Cu")
		(net 420)
	)
	(segment
		(start 106.35 100.85)
		(end 106.35 102.6)
		(width 0.15)
		(layer "In2.Cu")
		(net 420)
	)
	(segment
		(start 103.475 105.475)
		(end 106.35 102.6)
		(width 0.15)
		(layer "In2.Cu")
		(net 420)
	)
	(segment
		(start 103.475 109.175)
		(end 103.475 105.475)
		(width 0.15)
		(layer "In2.Cu")
		(net 420)
	)
	(segment
		(start 102.275 110.375)
		(end 103.475 109.175)
		(width 0.15)
		(layer "In2.Cu")
		(net 420)
	)
	(segment
		(start 102.275 110.675)
		(end 102.275 110.375)
		(width 0.15)
		(layer "In2.Cu")
		(net 420)
	)
	(segment
		(start 98.277149 100.377149)
		(end 98.672851 100.377149)
		(width 0.15)
		(layer "F.Cu")
		(net 421)
	)
	(segment
		(start 97.675 99.275)
		(end 97.675 99.775)
		(width 0.15)
		(layer "F.Cu")
		(net 421)
	)
	(segment
		(start 98.275 111.675)
		(end 98.275 110.675)
		(width 0.15)
		(layer "F.Cu")
		(net 421)
	)
	(segment
		(start 98.775 112.175)
		(end 98.275 111.675)
		(width 0.15)
		(layer "F.Cu")
		(net 421)
	)
	(segment
		(start 97.675 99.775)
		(end 98.277149 100.377149)
		(width 0.15)
		(layer "F.Cu")
		(net 421)
	)
	(segment
		(start 97.975 98.975)
		(end 97.675 99.275)
		(width 0.15)
		(layer "F.Cu")
		(net 421)
	)
	(segment
		(start 98.672851 98.975)
		(end 97.975 98.975)
		(width 0.15)
		(layer "F.Cu")
		(net 421)
	)
	(via blind
		(at 98.275 110.675)
		(size 0.5)
		(drill 0.2)
		(layers "F.Cu" "In2.Cu")
		(net 421)
	)
	(via
		(at 98.672851 100.377149)
		(size 0.5)
		(drill 0.2)
		(layers "F.Cu" "B.Cu")
		(net 421)
	)
	(segment
		(start 98.501356 104.53589)
		(end 98.492879 104.560115)
		(width 0.15)
		(layer "In2.Cu")
		(net 421)
	)
	(segment
		(start 97.728496 104.081476)
		(end 97.710625 104.109917)
		(width 0.15)
		(layer "In2.Cu")
		(net 421)
	)
	(segment
		(start 97.710625 104.109917)
		(end 97.699531 104.141621)
		(width 0.15)
		(layer "In2.Cu")
		(net 421)
	)
	(segment
		(start 98.492879 104.389884)
		(end 98.501356 104.414109)
		(width 0.15)
		(layer "In2.Cu")
		(net 421)
	)
	(segment
		(start 97.845771 104.325)
		(end 98.389615 104.325)
		(width 0.15)
		(layer "In2.Cu")
		(net 421)
	)
	(segment
		(start 98.190082 104.010145)
		(end 98.158378 104.021239)
		(width 0.15)
		(layer "In2.Cu")
		(net 421)
	)
	(segment
		(start 98.504229 104.439614)
		(end 98.504229 104.510386)
		(width 0.15)
		(layer "In2.Cu")
		(net 421)
	)
	(segment
		(start 98.389615 104.625)
		(end 97.845771 104.625)
		(width 0.15)
		(layer "In2.Cu")
		(net 421)
	)
	(segment
		(start 98.389615 104.325)
		(end 98.41512 104.327873)
		(width 0.15)
		(layer "In2.Cu")
		(net 421)
	)
	(segment
		(start 97.812392 104.62876)
		(end 97.780688 104.639854)
		(width 0.15)
		(layer "In2.Cu")
		(net 421)
	)
	(segment
		(start 98.275 100.775)
		(end 98.275 103.875)
		(width 0.15)
		(layer "In2.Cu")
		(net 421)
	)
	(segment
		(start 97.710625 104.709917)
		(end 97.699531 104.741621)
		(width 0.15)
		(layer "In2.Cu")
		(net 421)
	)
	(segment
		(start 97.845771 104.025)
		(end 97.812392 104.02876)
		(width 0.15)
		(layer "In2.Cu")
		(net 421)
	)
	(segment
		(start 97.812392 104.921239)
		(end 97.845771 104.925)
		(width 0.15)
		(layer "In2.Cu")
		(net 421)
	)
	(segment
		(start 97.812392 104.02876)
		(end 97.780688 104.039854)
		(width 0.15)
		(layer "In2.Cu")
		(net 421)
	)
	(segment
		(start 97.752247 104.657725)
		(end 97.728496 104.681476)
		(width 0.15)
		(layer "In2.Cu")
		(net 421)
	)
	(segment
		(start 98.849999 109.349999)
		(end 98.849999 110.100001)
		(width 0.15)
		(layer "In2.Cu")
		(net 421)
	)
	(segment
		(start 98.41512 104.622126)
		(end 98.389615 104.625)
		(width 0.15)
		(layer "In2.Cu")
		(net 421)
	)
	(segment
		(start 97.710625 104.840082)
		(end 97.728496 104.868523)
		(width 0.15)
		(layer "In2.Cu")
		(net 421)
	)
	(segment
		(start 97.699531 104.208378)
		(end 97.710625 104.240082)
		(width 0.15)
		(layer "In2.Cu")
		(net 421)
	)
	(segment
		(start 97.780688 104.310145)
		(end 97.812392 104.321239)
		(width 0.15)
		(layer "In2.Cu")
		(net 421)
	)
	(segment
		(start 98.218523 103.992274)
		(end 98.190082 104.010145)
		(width 0.15)
		(layer "In2.Cu")
		(net 421)
	)
	(segment
		(start 98.260145 105.009917)
		(end 98.271239 105.041621)
		(width 0.15)
		(layer "In2.Cu")
		(net 421)
	)
	(segment
		(start 97.752247 104.057725)
		(end 97.728496 104.081476)
		(width 0.15)
		(layer "In2.Cu")
		(net 421)
	)
	(segment
		(start 97.780688 104.639854)
		(end 97.752247 104.657725)
		(width 0.15)
		(layer "In2.Cu")
		(net 421)
	)
	(segment
		(start 98.461076 104.599994)
		(end 98.439345 104.613649)
		(width 0.15)
		(layer "In2.Cu")
		(net 421)
	)
	(segment
		(start 98.439345 104.613649)
		(end 98.41512 104.622126)
		(width 0.15)
		(layer "In2.Cu")
		(net 421)
	)
	(segment
		(start 98.439345 104.33635)
		(end 98.461076 104.350005)
		(width 0.15)
		(layer "In2.Cu")
		(net 421)
	)
	(segment
		(start 98.242274 104.981476)
		(end 98.260145 105.009917)
		(width 0.15)
		(layer "In2.Cu")
		(net 421)
	)
	(segment
		(start 98.158378 104.92876)
		(end 98.190082 104.939854)
		(width 0.15)
		(layer "In2.Cu")
		(net 421)
	)
	(segment
		(start 97.780688 104.039854)
		(end 97.752247 104.057725)
		(width 0.15)
		(layer "In2.Cu")
		(net 421)
	)
	(segment
		(start 98.41512 104.327873)
		(end 98.439345 104.33635)
		(width 0.15)
		(layer "In2.Cu")
		(net 421)
	)
	(segment
		(start 98.125 104.025)
		(end 97.845771 104.025)
		(width 0.15)
		(layer "In2.Cu")
		(net 421)
	)
	(segment
		(start 97.699531 104.141621)
		(end 97.695771 104.175)
		(width 0.15)
		(layer "In2.Cu")
		(net 421)
	)
	(segment
		(start 97.728496 104.868523)
		(end 97.752247 104.892274)
		(width 0.15)
		(layer "In2.Cu")
		(net 421)
	)
	(segment
		(start 98.271239 103.908378)
		(end 98.260145 103.940082)
		(width 0.15)
		(layer "In2.Cu")
		(net 421)
	)
	(segment
		(start 98.190082 104.939854)
		(end 98.218523 104.957725)
		(width 0.15)
		(layer "In2.Cu")
		(net 421)
	)
	(segment
		(start 98.242274 103.968523)
		(end 98.218523 103.992274)
		(width 0.15)
		(layer "In2.Cu")
		(net 421)
	)
	(segment
		(start 98.501356 104.414109)
		(end 98.504229 104.439614)
		(width 0.15)
		(layer "In2.Cu")
		(net 421)
	)
	(segment
		(start 97.845771 104.925)
		(end 98.125 104.925)
		(width 0.15)
		(layer "In2.Cu")
		(net 421)
	)
	(segment
		(start 98.158378 104.021239)
		(end 98.125 104.025)
		(width 0.15)
		(layer "In2.Cu")
		(net 421)
	)
	(segment
		(start 98.218523 104.957725)
		(end 98.242274 104.981476)
		(width 0.15)
		(layer "In2.Cu")
		(net 421)
	)
	(segment
		(start 98.275 108.775)
		(end 98.849999 109.349999)
		(width 0.15)
		(layer "In2.Cu")
		(net 421)
	)
	(segment
		(start 97.752247 104.292274)
		(end 97.780688 104.310145)
		(width 0.15)
		(layer "In2.Cu")
		(net 421)
	)
	(segment
		(start 97.699531 104.808378)
		(end 97.710625 104.840082)
		(width 0.15)
		(layer "In2.Cu")
		(net 421)
	)
	(segment
		(start 98.504229 104.510386)
		(end 98.501356 104.53589)
		(width 0.15)
		(layer "In2.Cu")
		(net 421)
	)
	(segment
		(start 98.672851 100.377149)
		(end 98.275 100.775)
		(width 0.15)
		(layer "In2.Cu")
		(net 421)
	)
	(segment
		(start 97.695771 104.175)
		(end 97.699531 104.208378)
		(width 0.15)
		(layer "In2.Cu")
		(net 421)
	)
	(segment
		(start 98.479224 104.368153)
		(end 98.492879 104.389884)
		(width 0.15)
		(layer "In2.Cu")
		(net 421)
	)
	(segment
		(start 98.461076 104.350005)
		(end 98.479224 104.368153)
		(width 0.15)
		(layer "In2.Cu")
		(net 421)
	)
	(segment
		(start 98.275 103.875)
		(end 98.271239 103.908378)
		(width 0.15)
		(layer "In2.Cu")
		(net 421)
	)
	(segment
		(start 98.492879 104.560115)
		(end 98.479224 104.581846)
		(width 0.15)
		(layer "In2.Cu")
		(net 421)
	)
	(segment
		(start 98.260145 103.940082)
		(end 98.242274 103.968523)
		(width 0.15)
		(layer "In2.Cu")
		(net 421)
	)
	(segment
		(start 97.699531 104.741621)
		(end 97.695771 104.775)
		(width 0.15)
		(layer "In2.Cu")
		(net 421)
	)
	(segment
		(start 97.695771 104.775)
		(end 97.699531 104.808378)
		(width 0.15)
		(layer "In2.Cu")
		(net 421)
	)
	(segment
		(start 98.271239 105.041621)
		(end 98.275 105.075)
		(width 0.15)
		(layer "In2.Cu")
		(net 421)
	)
	(segment
		(start 97.752247 104.892274)
		(end 97.780688 104.910145)
		(width 0.15)
		(layer "In2.Cu")
		(net 421)
	)
	(segment
		(start 97.780688 104.910145)
		(end 97.812392 104.921239)
		(width 0.15)
		(layer "In2.Cu")
		(net 421)
	)
	(segment
		(start 98.125 104.925)
		(end 98.158378 104.92876)
		(width 0.15)
		(layer "In2.Cu")
		(net 421)
	)
	(segment
		(start 98.479224 104.581846)
		(end 98.461076 104.599994)
		(width 0.15)
		(layer "In2.Cu")
		(net 421)
	)
	(segment
		(start 97.710625 104.240082)
		(end 97.728496 104.268523)
		(width 0.15)
		(layer "In2.Cu")
		(net 421)
	)
	(segment
		(start 97.812392 104.321239)
		(end 97.845771 104.325)
		(width 0.15)
		(layer "In2.Cu")
		(net 421)
	)
	(segment
		(start 97.728496 104.268523)
		(end 97.752247 104.292274)
		(width 0.15)
		(layer "In2.Cu")
		(net 421)
	)
	(segment
		(start 98.849999 110.100001)
		(end 98.275 110.675)
		(width 0.15)
		(layer "In2.Cu")
		(net 421)
	)
	(segment
		(start 97.845771 104.625)
		(end 97.812392 104.62876)
		(width 0.15)
		(layer "In2.Cu")
		(net 421)
	)
	(segment
		(start 97.728496 104.681476)
		(end 97.710625 104.709917)
		(width 0.15)
		(layer "In2.Cu")
		(net 421)
	)
	(segment
		(start 98.275 105.075)
		(end 98.275 108.765)
		(width 0.15)
		(layer "In2.Cu")
		(net 421)
	)
	(segment
		(start 98.775 110.175)
		(end 98.275 109.675)
		(width 0.1)
		(layer "F.Cu")
		(net 422)
	)
	(segment
		(start 98.672851 97.975)
		(end 97.671998 97.975)
		(width 0.15)
		(layer "F.Cu")
		(net 422)
	)
	(segment
		(start 97.1 99.8)
		(end 97.675 100.375)
		(width 0.15)
		(layer "F.Cu")
		(net 422)
	)
	(segment
		(start 97.1 98.546998)
		(end 97.1 99.8)
		(width 0.15)
		(layer "F.Cu")
		(net 422)
	)
	(segment
		(start 97.671998 97.975)
		(end 97.1 98.546998)
		(width 0.15)
		(layer "F.Cu")
		(net 422)
	)
	(via
		(at 97.65 100.4)
		(size 0.5)
		(drill 0.2)
		(layers "F.Cu" "B.Cu")
		(net 422)
	)
	(via blind
		(at 98.275 109.675)
		(size 0.5)
		(drill 0.2)
		(layers "F.Cu" "In2.Cu")
		(net 422)
	)
	(segment
		(start 97.153135 103.372183)
		(end 97.150001 103.399999)
		(width 0.15)
		(layer "In2.Cu")
		(net 422)
	)
	(segment
		(start 97.275001 102.374999)
		(end 97.850001 102.374999)
		(width 0.15)
		(layer "In2.Cu")
		(net 422)
	)
	(segment
		(start 97.387622 102.004234)
		(end 97.372729 102.027935)
		(width 0.15)
		(layer "In2.Cu")
		(net 422)
	)
	(segment
		(start 97.985147 102.459916)
		(end 97.996241 102.49162)
		(width 0.15)
		(layer "In2.Cu")
		(net 422)
	)
	(segment
		(start 97.400001 103.699999)
		(end 97.400001 108.000001)
		(width 0.15)
		(layer "In2.Cu")
		(net 422)
	)
	(segment
		(start 97.247185 103.571864)
		(end 97.302816 103.578133)
		(width 0.15)
		(layer "In2.Cu")
		(net 422)
	)
	(segment
		(start 97.150001 102.849999)
		(end 97.153135 102.877814)
		(width 0.15)
		(layer "In2.Cu")
		(net 422)
	)
	(segment
		(start 97.220765 102.687377)
		(end 97.197064 102.70227)
		(width 0.15)
		(layer "In2.Cu")
		(net 422)
	)
	(segment
		(start 97.996241 103.09162)
		(end 98.000001 103.124999)
		(width 0.15)
		(layer "In2.Cu")
		(net 422)
	)
	(segment
		(start 97.352937 103.60227)
		(end 97.372729 103.622062)
		(width 0.15)
		(layer "In2.Cu")
		(net 422)
	)
	(segment
		(start 97.967276 102.618522)
		(end 97.943525 102.642273)
		(width 0.15)
		(layer "In2.Cu")
		(net 422)
	)
	(segment
		(start 97.247185 102.678133)
		(end 97.220765 102.687377)
		(width 0.15)
		(layer "In2.Cu")
		(net 422)
	)
	(segment
		(start 97.162379 103.504234)
		(end 97.177272 103.527935)
		(width 0.15)
		(layer "In2.Cu")
		(net 422)
	)
	(segment
		(start 97.775 109.175)
		(end 98.275 109.675)
		(width 0.15)
		(layer "In2.Cu")
		(net 422)
	)
	(segment
		(start 97.275001 102.674999)
		(end 97.247185 102.678133)
		(width 0.15)
		(layer "In2.Cu")
		(net 422)
	)
	(segment
		(start 97.150001 103.449999)
		(end 97.153135 103.477814)
		(width 0.15)
		(layer "In2.Cu")
		(net 422)
	)
	(segment
		(start 97.220765 102.96262)
		(end 97.247185 102.971864)
		(width 0.15)
		(layer "In2.Cu")
		(net 422)
	)
	(segment
		(start 97.850001 102.974999)
		(end 97.88338 102.978759)
		(width 0.15)
		(layer "In2.Cu")
		(net 422)
	)
	(segment
		(start 97.967276 103.218522)
		(end 97.943525 103.242273)
		(width 0.15)
		(layer "In2.Cu")
		(net 422)
	)
	(segment
		(start 97.177272 103.322062)
		(end 97.162379 103.345763)
		(width 0.15)
		(layer "In2.Cu")
		(net 422)
	)
	(segment
		(start 97.302816 103.578133)
		(end 97.329236 103.587377)
		(width 0.15)
		(layer "In2.Cu")
		(net 422)
	)
	(segment
		(start 97.943525 102.407724)
		(end 97.967276 102.431475)
		(width 0.15)
		(layer "In2.Cu")
		(net 422)
	)
	(segment
		(start 97.197064 102.70227)
		(end 97.177272 102.722062)
		(width 0.15)
		(layer "In2.Cu")
		(net 422)
	)
	(segment
		(start 97.197064 102.347727)
		(end 97.220765 102.36262)
		(width 0.15)
		(layer "In2.Cu")
		(net 422)
	)
	(segment
		(start 97.372729 102.027935)
		(end 97.352937 102.047727)
		(width 0.15)
		(layer "In2.Cu")
		(net 422)
	)
	(segment
		(start 97.162379 102.145763)
		(end 97.153135 102.172183)
		(width 0.15)
		(layer "In2.Cu")
		(net 422)
	)
	(segment
		(start 97.88338 102.671238)
		(end 97.850001 102.674999)
		(width 0.15)
		(layer "In2.Cu")
		(net 422)
	)
	(segment
		(start 97.915084 102.389853)
		(end 97.943525 102.407724)
		(width 0.15)
		(layer "In2.Cu")
		(net 422)
	)
	(segment
		(start 97.915084 103.260144)
		(end 97.88338 103.271238)
		(width 0.15)
		(layer "In2.Cu")
		(net 422)
	)
	(segment
		(start 97.177272 102.327935)
		(end 97.197064 102.347727)
		(width 0.15)
		(layer "In2.Cu")
		(net 422)
	)
	(segment
		(start 97.220765 102.36262)
		(end 97.247185 102.371864)
		(width 0.15)
		(layer "In2.Cu")
		(net 422)
	)
	(segment
		(start 97.197064 103.30227)
		(end 97.177272 103.322062)
		(width 0.15)
		(layer "In2.Cu")
		(net 422)
	)
	(segment
		(start 97.153135 102.877814)
		(end 97.162379 102.904234)
		(width 0.15)
		(layer "In2.Cu")
		(net 422)
	)
	(segment
		(start 97.153135 103.477814)
		(end 97.162379 103.504234)
		(width 0.15)
		(layer "In2.Cu")
		(net 422)
	)
	(segment
		(start 97.162379 103.345763)
		(end 97.153135 103.372183)
		(width 0.15)
		(layer "In2.Cu")
		(net 422)
	)
	(segment
		(start 97.996241 102.49162)
		(end 98.000001 102.524999)
		(width 0.15)
		(layer "In2.Cu")
		(net 422)
	)
	(segment
		(start 97.329236 103.587377)
		(end 97.352937 103.60227)
		(width 0.15)
		(layer "In2.Cu")
		(net 422)
	)
	(segment
		(start 97.400001 101.949999)
		(end 97.396866 101.977814)
		(width 0.15)
		(layer "In2.Cu")
		(net 422)
	)
	(segment
		(start 97.150001 103.399999)
		(end 97.150001 103.449999)
		(width 0.15)
		(layer "In2.Cu")
		(net 422)
	)
	(segment
		(start 97.177272 102.927935)
		(end 97.197064 102.947727)
		(width 0.15)
		(layer "In2.Cu")
		(net 422)
	)
	(segment
		(start 97.302816 102.071864)
		(end 97.247185 102.078133)
		(width 0.15)
		(layer "In2.Cu")
		(net 422)
	)
	(segment
		(start 97.396866 101.977814)
		(end 97.387622 102.004234)
		(width 0.15)
		(layer "In2.Cu")
		(net 422)
	)
	(segment
		(start 97.150001 102.199999)
		(end 97.150001 102.249999)
		(width 0.15)
		(layer "In2.Cu")
		(net 422)
	)
	(segment
		(start 97.850001 102.374999)
		(end 97.88338 102.378759)
		(width 0.15)
		(layer "In2.Cu")
		(net 422)
	)
	(segment
		(start 97.400001 108.000001)
		(end 97.775 108.375)
		(width 0.15)
		(layer "In2.Cu")
		(net 422)
	)
	(segment
		(start 97.387622 103.645763)
		(end 97.396866 103.672183)
		(width 0.15)
		(layer "In2.Cu")
		(net 422)
	)
	(segment
		(start 98.000001 103.124999)
		(end 97.996241 103.158377)
		(width 0.15)
		(layer "In2.Cu")
		(net 422)
	)
	(segment
		(start 97.153135 102.172183)
		(end 97.150001 102.199999)
		(width 0.15)
		(layer "In2.Cu")
		(net 422)
	)
	(segment
		(start 97.88338 102.378759)
		(end 97.915084 102.389853)
		(width 0.15)
		(layer "In2.Cu")
		(net 422)
	)
	(segment
		(start 98.000001 102.524999)
		(end 97.996241 102.558377)
		(width 0.15)
		(layer "In2.Cu")
		(net 422)
	)
	(segment
		(start 97.177272 102.722062)
		(end 97.162379 102.745763)
		(width 0.15)
		(layer "In2.Cu")
		(net 422)
	)
	(segment
		(start 97.177272 103.527935)
		(end 97.197064 103.547727)
		(width 0.15)
		(layer "In2.Cu")
		(net 422)
	)
	(segment
		(start 97.915084 102.660144)
		(end 97.88338 102.671238)
		(width 0.15)
		(layer "In2.Cu")
		(net 422)
	)
	(segment
		(start 97.197064 103.547727)
		(end 97.220765 103.56262)
		(width 0.15)
		(layer "In2.Cu")
		(net 422)
	)
	(segment
		(start 97.372729 103.622062)
		(end 97.387622 103.645763)
		(width 0.15)
		(layer "In2.Cu")
		(net 422)
	)
	(segment
		(start 97.220765 102.087377)
		(end 97.197064 102.10227)
		(width 0.15)
		(layer "In2.Cu")
		(net 422)
	)
	(segment
		(start 97.162379 102.745763)
		(end 97.153135 102.772183)
		(width 0.15)
		(layer "In2.Cu")
		(net 422)
	)
	(segment
		(start 97.153135 102.277814)
		(end 97.162379 102.304234)
		(width 0.15)
		(layer "In2.Cu")
		(net 422)
	)
	(segment
		(start 97.275001 102.974999)
		(end 97.850001 102.974999)
		(width 0.15)
		(layer "In2.Cu")
		(net 422)
	)
	(segment
		(start 97.220765 103.56262)
		(end 97.247185 103.571864)
		(width 0.15)
		(layer "In2.Cu")
		(net 422)
	)
	(segment
		(start 97.967276 103.031475)
		(end 97.985147 103.059916)
		(width 0.15)
		(layer "In2.Cu")
		(net 422)
	)
	(segment
		(start 97.396866 103.672183)
		(end 97.400001 103.699999)
		(width 0.15)
		(layer "In2.Cu")
		(net 422)
	)
	(segment
		(start 97.150001 102.799999)
		(end 97.150001 102.849999)
		(width 0.15)
		(layer "In2.Cu")
		(net 422)
	)
	(segment
		(start 97.775 108.375)
		(end 97.775 109.175)
		(width 0.15)
		(layer "In2.Cu")
		(net 422)
	)
	(segment
		(start 97.985147 103.190081)
		(end 97.967276 103.218522)
		(width 0.15)
		(layer "In2.Cu")
		(net 422)
	)
	(segment
		(start 97.150001 102.249999)
		(end 97.153135 102.277814)
		(width 0.15)
		(layer "In2.Cu")
		(net 422)
	)
	(segment
		(start 97.88338 102.978759)
		(end 97.915084 102.989853)
		(width 0.15)
		(layer "In2.Cu")
		(net 422)
	)
	(segment
		(start 97.220765 103.287377)
		(end 97.197064 103.30227)
		(width 0.15)
		(layer "In2.Cu")
		(net 422)
	)
	(segment
		(start 97.177272 102.122062)
		(end 97.162379 102.145763)
		(width 0.15)
		(layer "In2.Cu")
		(net 422)
	)
	(segment
		(start 97.247185 102.971864)
		(end 97.275001 102.974999)
		(width 0.15)
		(layer "In2.Cu")
		(net 422)
	)
	(segment
		(start 97.88338 103.271238)
		(end 97.850001 103.274999)
		(width 0.15)
		(layer "In2.Cu")
		(net 422)
	)
	(segment
		(start 97.162379 102.904234)
		(end 97.177272 102.927935)
		(width 0.15)
		(layer "In2.Cu")
		(net 422)
	)
	(segment
		(start 97.65 100.4)
		(end 97.400001 100.649999)
		(width 0.15)
		(layer "In2.Cu")
		(net 422)
	)
	(segment
		(start 97.943525 102.642273)
		(end 97.915084 102.660144)
		(width 0.15)
		(layer "In2.Cu")
		(net 422)
	)
	(segment
		(start 97.967276 102.431475)
		(end 97.985147 102.459916)
		(width 0.15)
		(layer "In2.Cu")
		(net 422)
	)
	(segment
		(start 97.943525 103.242273)
		(end 97.915084 103.260144)
		(width 0.15)
		(layer "In2.Cu")
		(net 422)
	)
	(segment
		(start 97.153135 102.772183)
		(end 97.150001 102.799999)
		(width 0.15)
		(layer "In2.Cu")
		(net 422)
	)
	(segment
		(start 97.247185 102.078133)
		(end 97.220765 102.087377)
		(width 0.15)
		(layer "In2.Cu")
		(net 422)
	)
	(segment
		(start 97.985147 103.059916)
		(end 97.996241 103.09162)
		(width 0.15)
		(layer "In2.Cu")
		(net 422)
	)
	(segment
		(start 97.247185 102.371864)
		(end 97.275001 102.374999)
		(width 0.15)
		(layer "In2.Cu")
		(net 422)
	)
	(segment
		(start 97.850001 103.274999)
		(end 97.275001 103.274999)
		(width 0.15)
		(layer "In2.Cu")
		(net 422)
	)
	(segment
		(start 97.400001 100.649999)
		(end 97.400001 101.949999)
		(width 0.15)
		(layer "In2.Cu")
		(net 422)
	)
	(segment
		(start 97.850001 102.674999)
		(end 97.275001 102.674999)
		(width 0.15)
		(layer "In2.Cu")
		(net 422)
	)
	(segment
		(start 97.352937 102.047727)
		(end 97.329236 102.06262)
		(width 0.15)
		(layer "In2.Cu")
		(net 422)
	)
	(segment
		(start 97.996241 102.558377)
		(end 97.985147 102.590081)
		(width 0.15)
		(layer "In2.Cu")
		(net 422)
	)
	(segment
		(start 97.985147 102.590081)
		(end 97.967276 102.618522)
		(width 0.15)
		(layer "In2.Cu")
		(net 422)
	)
	(segment
		(start 97.275001 103.274999)
		(end 97.247185 103.278133)
		(width 0.15)
		(layer "In2.Cu")
		(net 422)
	)
	(segment
		(start 97.247185 103.278133)
		(end 97.220765 103.287377)
		(width 0.15)
		(layer "In2.Cu")
		(net 422)
	)
	(segment
		(start 97.915084 102.989853)
		(end 97.943525 103.007724)
		(width 0.15)
		(layer "In2.Cu")
		(net 422)
	)
	(segment
		(start 97.943525 103.007724)
		(end 97.967276 103.031475)
		(width 0.15)
		(layer "In2.Cu")
		(net 422)
	)
	(segment
		(start 97.996241 103.158377)
		(end 97.985147 103.190081)
		(width 0.15)
		(layer "In2.Cu")
		(net 422)
	)
	(segment
		(start 97.329236 102.06262)
		(end 97.302816 102.071864)
		(width 0.15)
		(layer "In2.Cu")
		(net 422)
	)
	(segment
		(start 97.162379 102.304234)
		(end 97.177272 102.327935)
		(width 0.15)
		(layer "In2.Cu")
		(net 422)
	)
	(segment
		(start 97.197064 102.947727)
		(end 97.220765 102.96262)
		(width 0.15)
		(layer "In2.Cu")
		(net 422)
	)
	(segment
		(start 97.197064 102.10227)
		(end 97.177272 102.122062)
		(width 0.15)
		(layer "In2.Cu")
		(net 422)
	)
	(segment
		(start 97.475 97.475)
		(end 96.65 98.3)
		(width 0.15)
		(layer "F.Cu")
		(net 423)
	)
	(segment
		(start 96.65 98.3)
		(end 96.65 100.15)
		(width 0.15)
		(layer "F.Cu")
		(net 423)
	)
	(segment
		(start 98.672851 97.475)
		(end 97.475 97.475)
		(width 0.15)
		(layer "F.Cu")
		(net 423)
	)
	(segment
		(start 97.775 109.175)
		(end 97.275 108.675)
		(width 0.1)
		(layer "F.Cu")
		(net 423)
	)
	(segment
		(start 96.65 100.15)
		(end 96.875 100.375)
		(width 0.15)
		(layer "F.Cu")
		(net 423)
	)
	(via
		(at 96.875 100.375)
		(size 0.5)
		(drill 0.2)
		(layers "F.Cu" "B.Cu")
		(net 423)
	)
	(via blind
		(at 97.275 108.675)
		(size 0.5)
		(drill 0.2)
		(layers "F.Cu" "In2.Cu")
		(net 423)
	)
	(segment
		(start 96.875 108.275)
		(end 96.875 100.375)
		(width 0.15)
		(layer "In2.Cu")
		(net 423)
	)
	(segment
		(start 97.275 108.675)
		(end 96.875 108.275)
		(width 0.15)
		(layer "In2.Cu")
		(net 423)
	)
	(segment
		(start 96.3 98.225)
		(end 96.3 100.8)
		(width 0.15)
		(layer "F.Cu")
		(net 424)
	)
	(segment
		(start 97.775 111.175)
		(end 97.275 110.675)
		(width 0.1)
		(layer "F.Cu")
		(net 424)
	)
	(segment
		(start 98.672851 96.975)
		(end 97.425 96.975)
		(width 0.15)
		(layer "F.Cu")
		(net 424)
	)
	(segment
		(start 97.425 96.975)
		(end 96.3 98.1)
		(width 0.15)
		(layer "F.Cu")
		(net 424)
	)
	(segment
		(start 96.3 100.8)
		(end 96.375 100.875)
		(width 0.15)
		(layer "F.Cu")
		(net 424)
	)
	(via
		(at 96.375 100.875)
		(size 0.5)
		(drill 0.2)
		(layers "F.Cu" "B.Cu")
		(net 424)
	)
	(via blind
		(at 97.275 110.675)
		(size 0.5)
		(drill 0.2)
		(layers "F.Cu" "In2.Cu")
		(net 424)
	)
	(segment
		(start 96.775 110.175)
		(end 96.775 108.725)
		(width 0.15)
		(layer "In2.Cu")
		(net 424)
	)
	(segment
		(start 96.375 108.325)
		(end 96.375 100.875)
		(width 0.15)
		(layer "In2.Cu")
		(net 424)
	)
	(segment
		(start 96.775 108.725)
		(end 96.375 108.325)
		(width 0.15)
		(layer "In2.Cu")
		(net 424)
	)
	(segment
		(start 97.275 110.675)
		(end 96.775 110.175)
		(width 0.15)
		(layer "In2.Cu")
		(net 424)
	)
	(segment
		(start 98.672851 96.475)
		(end 97.252164 96.475)
		(width 0.15)
		(layer "F.Cu")
		(net 425)
	)
	(segment
		(start 95.95 100.267813)
		(end 95.811972 100.405841)
		(width 0.15)
		(layer "F.Cu")
		(net 425)
	)
	(segment
		(start 97.252164 96.475)
		(end 95.95 97.777164)
		(width 0.15)
		(layer "F.Cu")
		(net 425)
	)
	(segment
		(start 95.95 97.777164)
		(end 95.95 100.267813)
		(width 0.15)
		(layer "F.Cu")
		(net 425)
	)
	(segment
		(start 96.775 111.175)
		(end 96.275 110.675)
		(width 0.1)
		(layer "F.Cu")
		(net 425)
	)
	(via blind
		(at 96.275 110.675)
		(size 0.5)
		(drill 0.2)
		(layers "F.Cu" "In2.Cu")
		(net 425)
	)
	(via
		(at 95.811972 100.405841)
		(size 0.5)
		(drill 0.2)
		(layers "F.Cu" "B.Cu")
		(net 425)
	)
	(segment
		(start 96.275 110.675)
		(end 96.275 109.075)
		(width 0.15)
		(layer "In2.Cu")
		(net 425)
	)
	(segment
		(start 95.811972 108.611972)
		(end 95.811972 100.405841)
		(width 0.15)
		(layer "In2.Cu")
		(net 425)
	)
	(segment
		(start 96.275 109.075)
		(end 95.811972 108.611972)
		(width 0.15)
		(layer "In2.Cu")
		(net 425)
	)
	(segment
		(start 98.775 109.175)
		(end 98.775 107.417181)
		(width 0.15)
		(layer "F.Cu")
		(net 427)
	)
	(segment
		(start 99.35 99.652149)
		(end 99.35 100.75)
		(width 0.15)
		(layer "F.Cu")
		(net 427)
	)
	(segment
		(start 98.775 107.417181)
		(end 98.797492 107.394689)
		(width 0.15)
		(layer "F.Cu")
		(net 427)
	)
	(via blind
		(at 98.797492 107.394689)
		(size 0.5)
		(drill 0.2)
		(layers "F.Cu" "In2.Cu")
		(net 427)
	)
	(via
		(at 99.35 100.75)
		(size 0.5)
		(drill 0.2)
		(layers "F.Cu" "B.Cu")
		(net 427)
	)
	(segment
		(start 98.775 107.372197)
		(end 98.775 101.325)
		(width 0.15)
		(layer "In2.Cu")
		(net 427)
	)
	(segment
		(start 98.775 101.325)
		(end 99.35 100.75)
		(width 0.15)
		(layer "In2.Cu")
		(net 427)
	)
	(segment
		(start 98.797492 107.394689)
		(end 98.775 107.372197)
		(width 0.15)
		(layer "In2.Cu")
		(net 427)
	)
	(segment
		(start 100.667572 90.357272)
		(end 100.654467 90.336416)
		(width 0.11)
		(layer "F.Cu")
		(net 428)
	)
	(segment
		(start 99.30933 90.933257)
		(end 99.301534 90.864068)
		(width 0.11)
		(layer "F.Cu")
		(net 428)
	)
	(segment
		(start 99.99 89.984068)
		(end 99.99 84.29)
		(width 0.11)
		(layer "F.Cu")
		(net 428)
	)
	(segment
		(start 99.477558 91.144208)
		(end 99.418603 91.107164)
		(width 0.11)
		(layer "F.Cu")
		(net 428)
	)
	(segment
		(start 99.543277 90.522795)
		(end 99.612466 90.515)
		(width 0.11)
		(layer "F.Cu")
		(net 428)
	)
	(segment
		(start 100.616193 90.504106)
		(end 100.637049 90.491001)
		(width 0.11)
		(layer "F.Cu")
		(net 428)
	)
	(segment
		(start 100.616193 90.305893)
		(end 100.592943 90.297757)
		(width 0.11)
		(layer "F.Cu")
		(net 428)
	)
	(segment
		(start 100.568466 90.515)
		(end 100.592943 90.512242)
		(width 0.11)
		(layer "F.Cu")
		(net 428)
	)
	(segment
		(start 100.231742 90.287204)
		(end 100.166023 90.264208)
		(width 0.11)
		(layer "F.Cu")
		(net 428)
	)
	(segment
		(start 100.678466 90.405)
		(end 100.675708 90.380522)
		(width 0.11)
		(layer "F.Cu")
		(net 428)
	)
	(segment
		(start 100.566193 91.185893)
		(end 100.542943 91.177757)
		(width 0.11)
		(layer "F.Cu")
		(net 428)
	)
	(segment
		(start 100.637049 90.491001)
		(end 100.654467 90.473583)
		(width 0.11)
		(layer "F.Cu")
		(net 428)
	)
	(segment
		(start 100.617572 91.332727)
		(end 100.625708 91.309477)
		(width 0.11)
		(layer "F.Cu")
		(net 428)
	)
	(segment
		(start 100.637049 90.318998)
		(end 100.616193 90.305893)
		(width 0.11)
		(layer "F.Cu")
		(net 428)
	)
	(segment
		(start 100.164599 82.444999)
		(end 101.712999 82.444999)
		(width 0.11)
		(layer "F.Cu")
		(net 428)
	)
	(segment
		(start 100.587049 91.371001)
		(end 100.604467 91.353583)
		(width 0.11)
		(layer "F.Cu")
		(net 428)
	)
	(segment
		(start 100.675708 90.380522)
		(end 100.667572 90.357272)
		(width 0.11)
		(layer "F.Cu")
		(net 428)
	)
	(segment
		(start 99.477558 90.545791)
		(end 99.543277 90.522795)
		(width 0.11)
		(layer "F.Cu")
		(net 428)
	)
	(segment
		(start 100.604467 91.216416)
		(end 100.587049 91.198998)
		(width 0.11)
		(layer "F.Cu")
		(net 428)
	)
	(segment
		(start 100.592943 90.297757)
		(end 100.568466 90.295)
		(width 0.11)
		(layer "F.Cu")
		(net 428)
	)
	(segment
		(start 100.300931 90.295)
		(end 100.231742 90.287204)
		(width 0.11)
		(layer "F.Cu")
		(net 428)
	)
	(segment
		(start 99.99 91.705931)
		(end 99.997795 91.636742)
		(width 0.11)
		(layer "F.Cu")
		(net 428)
	)
	(segment
		(start 100.518466 91.175)
		(end 99.612466 91.175)
		(width 0.11)
		(layer "F.Cu")
		(net 428)
	)
	(segment
		(start 99.99 84.29)
		(end 99.615 83.915)
		(width 0.11)
		(layer "F.Cu")
		(net 428)
	)
	(segment
		(start 99.301534 90.864068)
		(end 99.301534 90.825931)
		(width 0.11)
		(layer "F.Cu")
		(net 428)
	)
	(segment
		(start 100.628466 91.285)
		(end 100.625708 91.260522)
		(width 0.11)
		(layer "F.Cu")
		(net 428)
	)
	(segment
		(start 100.566193 91.384106)
		(end 100.587049 91.371001)
		(width 0.11)
		(layer "F.Cu")
		(net 428)
	)
	(segment
		(start 100.518466 91.395)
		(end 100.542943 91.392242)
		(width 0.11)
		(layer "F.Cu")
		(net 428)
	)
	(segment
		(start 99.301534 90.825931)
		(end 99.30933 90.756742)
		(width 0.11)
		(layer "F.Cu")
		(net 428)
	)
	(segment
		(start 101.712999 82.444999)
		(end 102.643 83.375)
		(width 0.11)
		(layer "F.Cu")
		(net 428)
	)
	(segment
		(start 99.36937 90.632068)
		(end 99.418603 90.582835)
		(width 0.11)
		(layer "F.Cu")
		(net 428)
	)
	(segment
		(start 100.675708 90.429477)
		(end 100.678466 90.405)
		(width 0.11)
		(layer "F.Cu")
		(net 428)
	)
	(segment
		(start 99.332326 90.691023)
		(end 99.36937 90.632068)
		(width 0.11)
		(layer "F.Cu")
		(net 428)
	)
	(segment
		(start 99.615 82.994598)
		(end 100.164599 82.444999)
		(width 0.11)
		(layer "F.Cu")
		(net 428)
	)
	(segment
		(start 99.997795 90.053257)
		(end 99.99 89.984068)
		(width 0.11)
		(layer "F.Cu")
		(net 428)
	)
	(segment
		(start 100.166023 90.264208)
		(end 100.107068 90.227164)
		(width 0.11)
		(layer "F.Cu")
		(net 428)
	)
	(segment
		(start 100.617572 91.237272)
		(end 100.604467 91.216416)
		(width 0.11)
		(layer "F.Cu")
		(net 428)
	)
	(segment
		(start 100.568466 90.295)
		(end 100.300931 90.295)
		(width 0.11)
		(layer "F.Cu")
		(net 428)
	)
	(segment
		(start 99.30933 90.756742)
		(end 99.332326 90.691023)
		(width 0.11)
		(layer "F.Cu")
		(net 428)
	)
	(segment
		(start 99.612466 91.175)
		(end 99.543277 91.167204)
		(width 0.11)
		(layer "F.Cu")
		(net 428)
	)
	(segment
		(start 100.587049 91.198998)
		(end 100.566193 91.185893)
		(width 0.11)
		(layer "F.Cu")
		(net 428)
	)
	(segment
		(start 100.107068 91.462835)
		(end 100.166023 91.425791)
		(width 0.11)
		(layer "F.Cu")
		(net 428)
	)
	(segment
		(start 99.997795 91.636742)
		(end 100.020791 91.571023)
		(width 0.11)
		(layer "F.Cu")
		(net 428)
	)
	(segment
		(start 99.36937 91.057931)
		(end 99.332326 90.998976)
		(width 0.11)
		(layer "F.Cu")
		(net 428)
	)
	(segment
		(start 99.418603 90.582835)
		(end 99.477558 90.545791)
		(width 0.11)
		(layer "F.Cu")
		(net 428)
	)
	(segment
		(start 99.615 83.915)
		(end 99.615 82.994598)
		(width 0.11)
		(layer "F.Cu")
		(net 428)
	)
	(segment
		(start 100.592943 90.512242)
		(end 100.616193 90.504106)
		(width 0.11)
		(layer "F.Cu")
		(net 428)
	)
	(segment
		(start 100.020791 90.118976)
		(end 99.997795 90.053257)
		(width 0.11)
		(layer "F.Cu")
		(net 428)
	)
	(segment
		(start 99.99 92.657851)
		(end 99.99 91.705931)
		(width 0.11)
		(layer "F.Cu")
		(net 428)
	)
	(segment
		(start 100.625708 91.309477)
		(end 100.628466 91.285)
		(width 0.11)
		(layer "F.Cu")
		(net 428)
	)
	(segment
		(start 100.057835 90.177931)
		(end 100.020791 90.118976)
		(width 0.11)
		(layer "F.Cu")
		(net 428)
	)
	(segment
		(start 100.231742 91.402795)
		(end 100.300931 91.395)
		(width 0.11)
		(layer "F.Cu")
		(net 428)
	)
	(segment
		(start 99.332326 90.998976)
		(end 99.30933 90.933257)
		(width 0.11)
		(layer "F.Cu")
		(net 428)
	)
	(segment
		(start 99.418603 91.107164)
		(end 99.36937 91.057931)
		(width 0.11)
		(layer "F.Cu")
		(net 428)
	)
	(segment
		(start 100.654467 90.336416)
		(end 100.637049 90.318998)
		(width 0.11)
		(layer "F.Cu")
		(net 428)
	)
	(segment
		(start 100.542943 91.177757)
		(end 100.518466 91.175)
		(width 0.11)
		(layer "F.Cu")
		(net 428)
	)
	(segment
		(start 99.85 92.797851)
		(end 99.99 92.657851)
		(width 0.11)
		(layer "F.Cu")
		(net 428)
	)
	(segment
		(start 100.667572 90.452727)
		(end 100.675708 90.429477)
		(width 0.11)
		(layer "F.Cu")
		(net 428)
	)
	(segment
		(start 99.543277 91.167204)
		(end 99.477558 91.144208)
		(width 0.11)
		(layer "F.Cu")
		(net 428)
	)
	(segment
		(start 100.542943 91.392242)
		(end 100.566193 91.384106)
		(width 0.11)
		(layer "F.Cu")
		(net 428)
	)
	(segment
		(start 100.654467 90.473583)
		(end 100.667572 90.452727)
		(width 0.11)
		(layer "F.Cu")
		(net 428)
	)
	(segment
		(start 100.625708 91.260522)
		(end 100.617572 91.237272)
		(width 0.11)
		(layer "F.Cu")
		(net 428)
	)
	(segment
		(start 100.604467 91.353583)
		(end 100.617572 91.332727)
		(width 0.11)
		(layer "F.Cu")
		(net 428)
	)
	(segment
		(start 100.057835 91.512068)
		(end 100.107068 91.462835)
		(width 0.11)
		(layer "F.Cu")
		(net 428)
	)
	(segment
		(start 100.020791 91.571023)
		(end 100.057835 91.512068)
		(width 0.11)
		(layer "F.Cu")
		(net 428)
	)
	(segment
		(start 99.612466 90.515)
		(end 100.568466 90.515)
		(width 0.11)
		(layer "F.Cu")
		(net 428)
	)
	(segment
		(start 100.300931 91.395)
		(end 100.518466 91.395)
		(width 0.11)
		(layer "F.Cu")
		(net 428)
	)
	(segment
		(start 100.107068 90.227164)
		(end 100.057835 90.177931)
		(width 0.11)
		(layer "F.Cu")
		(net 428)
	)
	(segment
		(start 100.166023 91.425791)
		(end 100.231742 91.402795)
		(width 0.11)
		(layer "F.Cu")
		(net 428)
	)
	(segment
		(start 100.58905 86.204854)
		(end 100.557346 86.19376)
		(width 0.11)
		(layer "F.Cu")
		(net 429)
	)
	(segment
		(start 100.272272 91.625893)
		(end 100.295522 91.617757)
		(width 0.11)
		(layer "F.Cu")
		(net 429)
	)
	(segment
		(start 100.213761 87.206621)
		(end 100.224855 87.174917)
		(width 0.11)
		(layer "F.Cu")
		(net 429)
	)
	(segment
		(start 100.672442 91.584208)
		(end 100.731397 91.547164)
		(width 0.11)
		(layer "F.Cu")
		(net 429)
	)
	(segment
		(start 100.523967 85.29)
		(end 100.557346 85.286239)
		(width 0.11)
		(layer "F.Cu")
		(net 429)
	)
	(segment
		(start 100.656723 90.082795)
		(end 100.587534 90.075)
		(width 0.11)
		(layer "F.Cu")
		(net 429)
	)
	(segment
		(start 99.583807 90.745893)
		(end 99.607057 90.737757)
		(width 0.11)
		(layer "F.Cu")
		(net 429)
	)
	(segment
		(start 100.224855 87.174917)
		(end 100.242726 87.146476)
		(width 0.11)
		(layer "F.Cu")
		(net 429)
	)
	(segment
		(start 100.641242 86.846476)
		(end 100.617491 86.822725)
		(width 0.11)
		(layer "F.Cu")
		(net 429)
	)
	(segment
		(start 100.673967 86.34)
		(end 100.670207 86.306621)
		(width 0.11)
		(layer "F.Cu")
		(net 429)
	)
	(segment
		(start 100.242726 86.733523)
		(end 100.224855 86.705082)
		(width 0.11)
		(layer "F.Cu")
		(net 429)
	)
	(segment
		(start 100.523967 84.69)
		(end 100.557346 84.686239)
		(width 0.11)
		(layer "F.Cu")
		(net 429)
	)
	(segment
		(start 100.557346 85.286239)
		(end 100.58905 85.275145)
		(width 0.11)
		(layer "F.Cu")
		(net 429)
	)
	(segment
		(start 100.326622 87.386239)
		(end 100.294918 87.375145)
		(width 0.11)
		(layer "F.Cu")
		(net 429)
	)
	(segment
		(start 100.213761 84.873378)
		(end 100.21 84.84)
		(width 0.11)
		(layer "F.Cu")
		(net 429)
	)
	(segment
		(start 100.36 85.89)
		(end 100.523967 85.89)
		(width 0.11)
		(layer "F.Cu")
		(net 429)
	)
	(segment
		(start 100.659113 85.074917)
		(end 100.641242 85.046476)
		(width 0.11)
		(layer "F.Cu")
		(net 429)
	)
	(segment
		(start 100.587534 90.735)
		(end 100.656723 90.727204)
		(width 0.11)
		(layer "F.Cu")
		(net 429)
	)
	(segment
		(start 100.294918 87.704854)
		(end 100.326622 87.69376)
		(width 0.11)
		(layer "F.Cu")
		(net 429)
	)
	(segment
		(start 100.617491 85.257274)
		(end 100.641242 85.233523)
		(width 0.11)
		(layer "F.Cu")
		(net 429)
	)
	(segment
		(start 100.36 84.99)
		(end 100.326622 84.986239)
		(width 0.11)
		(layer "F.Cu")
		(net 429)
	)
	(segment
		(start 100.659113 85.205082)
		(end 100.670207 85.173378)
		(width 0.11)
		(layer "F.Cu")
		(net 429)
	)
	(segment
		(start 100.294918 84.375145)
		(end 100.266477 84.357274)
		(width 0.11)
		(layer "F.Cu")
		(net 429)
	)
	(segment
		(start 100.557346 85.59376)
		(end 100.523967 85.59)
		(width 0.11)
		(layer "F.Cu")
		(net 429)
	)
	(segment
		(start 100.670207 86.373378)
		(end 100.673967 86.34)
		(width 0.11)
		(layer "F.Cu")
		(net 429)
	)
	(segment
		(start 100.58905 86.804854)
		(end 100.557346 86.79376)
		(width 0.11)
		(layer "F.Cu")
		(net 429)
	)
	(segment
		(start 100.659113 86.274917)
		(end 100.641242 86.246476)
		(width 0.11)
		(layer "F.Cu")
		(net 429)
	)
	(segment
		(start 100.58905 87.404854)
		(end 100.557346 87.39376)
		(width 0.11)
		(layer "F.Cu")
		(net 429)
	)
	(segment
		(start 100.233998 90.033583)
		(end 100.220893 90.012727)
		(width 0.11)
		(layer "F.Cu")
		(net 429)
	)
	(segment
		(start 100.242726 84.746476)
		(end 100.266477 84.722725)
		(width 0.11)
		(layer "F.Cu")
		(net 429)
	)
	(segment
		(start 100.722442 90.105791)
		(end 100.656723 90.082795)
		(width 0.11)
		(layer "F.Cu")
		(net 429)
	)
	(segment
		(start 100.781397 90.667164)
		(end 100.83063 90.617931)
		(width 0.11)
		(layer "F.Cu")
		(net 429)
	)
	(segment
		(start 100.523967 87.39)
		(end 100.36 87.39)
		(width 0.11)
		(layer "F.Cu")
		(net 429)
	)
	(segment
		(start 100.617491 87.057274)
		(end 100.641242 87.033523)
		(width 0.11)
		(layer "F.Cu")
		(net 429)
	)
	(segment
		(start 100.617491 85.857274)
		(end 100.641242 85.833523)
		(width 0.11)
		(layer "F.Cu")
		(net 429)
	)
	(segment
		(start 100.670207 87.573378)
		(end 100.673967 87.54)
		(width 0.11)
		(layer "F.Cu")
		(net 429)
	)
	(segment
		(start 100.731397 91.022835)
		(end 100.672442 90.985791)
		(width 0.11)
		(layer "F.Cu")
		(net 429)
	)
	(segment
		(start 100.326622 84.386239)
		(end 100.294918 84.375145)
		(width 0.11)
		(layer "F.Cu")
		(net 429)
	)
	(segment
		(start 100.266477 86.757274)
		(end 100.242726 86.733523)
		(width 0.11)
		(layer "F.Cu")
		(net 429)
	)
	(segment
		(start 100.294918 85.575145)
		(end 100.266477 85.557274)
		(width 0.11)
		(layer "F.Cu")
		(net 429)
	)
	(segment
		(start 100.617491 86.222725)
		(end 100.58905 86.204854)
		(width 0.11)
		(layer "F.Cu")
		(net 429)
	)
	(segment
		(start 100.641242 85.233523)
		(end 100.659113 85.205082)
		(width 0.11)
		(layer "F.Cu")
		(net 429)
	)
	(segment
		(start 100.523967 84.99)
		(end 100.36 84.99)
		(width 0.11)
		(layer "F.Cu")
		(net 429)
	)
	(segment
		(start 100.78063 91.497931)
		(end 100.817674 91.438976)
		(width 0.11)
		(layer "F.Cu")
		(net 429)
	)
	(segment
		(start 100.36 86.49)
		(end 100.523967 86.49)
		(width 0.11)
		(layer "F.Cu")
		(net 429)
	)
	(segment
		(start 100.617491 87.422725)
		(end 100.58905 87.404854)
		(width 0.11)
		(layer "F.Cu")
		(net 429)
	)
	(segment
		(start 99.545533 90.913583)
		(end 99.532428 90.892727)
		(width 0.11)
		(layer "F.Cu")
		(net 429)
	)
	(segment
		(start 100.294918 84.975145)
		(end 100.266477 84.957274)
		(width 0.11)
		(layer "F.Cu")
		(net 429)
	)
	(segment
		(start 100.36 87.69)
		(end 100.523967 87.69)
		(width 0.11)
		(layer "F.Cu")
		(net 429)
	)
	(segment
		(start 100.659113 84.605082)
		(end 100.670207 84.573378)
		(width 0.11)
		(layer "F.Cu")
		(net 429)
	)
	(segment
		(start 100.58905 85.875145)
		(end 100.617491 85.857274)
		(width 0.11)
		(layer "F.Cu")
		(net 429)
	)
	(segment
		(start 100.781397 90.142835)
		(end 100.722442 90.105791)
		(width 0.11)
		(layer "F.Cu")
		(net 429)
	)
	(segment
		(start 100.213761 84.273378)
		(end 100.21 84.24)
		(width 0.11)
		(layer "F.Cu")
		(net 429)
	)
	(segment
		(start 100.670207 84.506621)
		(end 100.659113 84.474917)
		(width 0.11)
		(layer "F.Cu")
		(net 429)
	)
	(segment
		(start 100.557346 84.686239)
		(end 100.58905 84.675145)
		(width 0.11)
		(layer "F.Cu")
		(net 429)
	)
	(segment
		(start 100.224855 85.374917)
		(end 100.242726 85.346476)
		(width 0.11)
		(layer "F.Cu")
		(net 429)
	)
	(segment
		(start 100.898466 90.424068)
		(end 100.898466 90.385931)
		(width 0.11)
		(layer "F.Cu")
		(net 429)
	)
	(segment
		(start 100.21 92.657851)
		(end 100.21 91.725)
		(width 0.11)
		(layer "F.Cu")
		(net 429)
	)
	(segment
		(start 100.294918 87.375145)
		(end 100.266477 87.357274)
		(width 0.11)
		(layer "F.Cu")
		(net 429)
	)
	(segment
		(start 100.58905 85.275145)
		(end 100.617491 85.257274)
		(width 0.11)
		(layer "F.Cu")
		(net 429)
	)
	(segment
		(start 100.670207 85.173378)
		(end 100.673967 85.14)
		(width 0.11)
		(layer "F.Cu")
		(net 429)
	)
	(segment
		(start 100.36 86.79)
		(end 100.326622 86.786239)
		(width 0.11)
		(layer "F.Cu")
		(net 429)
	)
	(segment
		(start 100.32 90.075)
		(end 100.295522 90.072242)
		(width 0.11)
		(layer "F.Cu")
		(net 429)
	)
	(segment
		(start 100.606723 90.962795)
		(end 100.537534 90.955)
		(width 0.11)
		(layer "F.Cu")
		(net 429)
	)
	(segment
		(start 100.641242 87.446476)
		(end 100.617491 87.422725)
		(width 0.11)
		(layer "F.Cu")
		(net 429)
	)
	(segment
		(start 100.294918 86.175145)
		(end 100.266477 86.157274)
		(width 0.11)
		(layer "F.Cu")
		(net 429)
	)
	(segment
		(start 100.213761 85.406621)
		(end 100.224855 85.374917)
		(width 0.11)
		(layer "F.Cu")
		(net 429)
	)
	(segment
		(start 100.32 91.615)
		(end 100.537534 91.615)
		(width 0.11)
		(layer "F.Cu")
		(net 429)
	)
	(segment
		(start 100.659113 86.874917)
		(end 100.641242 86.846476)
		(width 0.11)
		(layer "F.Cu")
		(net 429)
	)
	(segment
		(start 100.266477 84.957274)
		(end 100.242726 84.933523)
		(width 0.11)
		(layer "F.Cu")
		(net 429)
	)
	(segment
		(start 100.21 85.44)
		(end 100.213761 85.406621)
		(width 0.11)
		(layer "F.Cu")
		(net 429)
	)
	(segment
		(start 100.220893 91.677272)
		(end 100.233998 91.656416)
		(width 0.11)
		(layer "F.Cu")
		(net 429)
	)
	(segment
		(start 100.58905 87.675145)
		(end 100.617491 87.657274)
		(width 0.11)
		(layer "F.Cu")
		(net 429)
	)
	(segment
		(start 100.656723 90.727204)
		(end 100.722442 90.704208)
		(width 0.11)
		(layer "F.Cu")
		(net 429)
	)
	(segment
		(start 100.294918 85.904854)
		(end 100.326622 85.89376)
		(width 0.11)
		(layer "F.Cu")
		(net 429)
	)
	(segment
		(start 100.617491 84.422725)
		(end 100.58905 84.404854)
		(width 0.11)
		(layer "F.Cu")
		(net 429)
	)
	(segment
		(start 100.326622 87.09376)
		(end 100.36 87.09)
		(width 0.11)
		(layer "F.Cu")
		(net 429)
	)
	(segment
		(start 100.898466 90.385931)
		(end 100.89067 90.316742)
		(width 0.11)
		(layer "F.Cu")
		(net 429)
	)
	(segment
		(start 100.224855 85.974917)
		(end 100.242726 85.946476)
		(width 0.11)
		(layer "F.Cu")
		(net 429)
	)
	(segment
		(start 100.224855 86.574917)
		(end 100.242726 86.546476)
		(width 0.11)
		(layer "F.Cu")
		(net 429)
	)
	(segment
		(start 100.617491 85.622725)
		(end 100.58905 85.604854)
		(width 0.11)
		(layer "F.Cu")
		(net 429)
	)
	(segment
		(start 99.631534 90.955)
		(end 99.607057 90.952242)
		(width 0.11)
		(layer "F.Cu")
		(net 429)
	)
	(segment
		(start 99.524292 90.820522)
		(end 99.532428 90.797272)
		(width 0.11)
		(layer "F.Cu")
		(net 429)
	)
	(segment
		(start 100.21 84.24)
		(end 100.21 83.776)
		(width 0.11)
		(layer "F.Cu")
		(net 429)
	)
	(segment
		(start 100.326622 85.89376)
		(end 100.36 85.89)
		(width 0.11)
		(layer "F.Cu")
		(net 429)
	)
	(segment
		(start 100.670207 86.306621)
		(end 100.659113 86.274917)
		(width 0.11)
		(layer "F.Cu")
		(net 429)
	)
	(segment
		(start 100.58905 84.404854)
		(end 100.557346 84.39376)
		(width 0.11)
		(layer "F.Cu")
		(net 429)
	)
	(segment
		(start 100.523967 84.39)
		(end 100.36 84.39)
		(width 0.11)
		(layer "F.Cu")
		(net 429)
	)
	(segment
		(start 100.21 87.84)
		(end 100.213761 87.806621)
		(width 0.11)
		(layer "F.Cu")
		(net 429)
	)
	(segment
		(start 100.213761 87.273378)
		(end 100.21 87.24)
		(width 0.11)
		(layer "F.Cu")
		(net 429)
	)
	(segment
		(start 100.242726 85.346476)
		(end 100.266477 85.322725)
		(width 0.11)
		(layer "F.Cu")
		(net 429)
	)
	(segment
		(start 100.326622 86.186239)
		(end 100.294918 86.175145)
		(width 0.11)
		(layer "F.Cu")
		(net 429)
	)
	(segment
		(start 100.242726 85.533523)
		(end 100.224855 85.505082)
		(width 0.11)
		(layer "F.Cu")
		(net 429)
	)
	(segment
		(start 100.670207 84.573378)
		(end 100.673967 84.54)
		(width 0.11)
		(layer "F.Cu")
		(net 429)
	)
	(segment
		(start 100.670207 85.706621)
		(end 100.659113 85.674917)
		(width 0.11)
		(layer "F.Cu")
		(net 429)
	)
	(segment
		(start 100.58905 85.004854)
		(end 100.557346 84.99376)
		(width 0.11)
		(layer "F.Cu")
		(net 429)
	)
	(segment
		(start 100.523967 87.09)
		(end 100.557346 87.086239)
		(width 0.11)
		(layer "F.Cu")
		(net 429)
	)
	(segment
		(start 100.36 86.19)
		(end 100.326622 86.186239)
		(width 0.11)
		(layer "F.Cu")
		(net 429)
	)
	(segment
		(start 100.326622 85.586239)
		(end 100.294918 85.575145)
		(width 0.11)
		(layer "F.Cu")
		(net 429)
	)
	(segment
		(start 100.673967 87.54)
		(end 100.670207 87.506621)
		(width 0.11)
		(layer "F.Cu")
		(net 429)
	)
	(segment
		(start 100.36 87.09)
		(end 100.523967 87.09)
		(width 0.11)
		(layer "F.Cu")
		(net 429)
	)
	(segment
		(start 100.617491 87.657274)
		(end 100.641242 87.633523)
		(width 0.11)
		(layer "F.Cu")
		(net 429)
	)
	(segment
		(start 100.213761 86.606621)
		(end 100.224855 86.574917)
		(width 0.11)
		(layer "F.Cu")
		(net 429)
	)
	(segment
		(start 100.224855 87.774917)
		(end 100.242726 87.746476)
		(width 0.11)
		(layer "F.Cu")
		(net 429)
	)
	(segment
		(start 100.21 86.04)
		(end 100.213761 86.006621)
		(width 0.11)
		(layer "F.Cu")
		(net 429)
	)
	(segment
		(start 100.58905 87.075145)
		(end 100.617491 87.057274)
		(width 0.11)
		(layer "F.Cu")
		(net 429)
	)
	(segment
		(start 100.673967 85.74)
		(end 100.670207 85.706621)
		(width 0.11)
		(layer "F.Cu")
		(net 429)
	)
	(segment
		(start 100.722442 90.704208)
		(end 100.781397 90.667164)
		(width 0.11)
		(layer "F.Cu")
		(net 429)
	)
	(segment
		(start 100.224855 86.705082)
		(end 100.213761 86.673378)
		(width 0.11)
		(layer "F.Cu")
		(net 429)
	)
	(segment
		(start 100.242726 86.133523)
		(end 100.224855 86.105082)
		(width 0.11)
		(layer "F.Cu")
		(net 429)
	)
	(segment
		(start 100.537534 91.615)
		(end 100.606723 91.607204)
		(width 0.11)
		(layer "F.Cu")
		(net 429)
	)
	(segment
		(start 100.213761 86.673378)
		(end 100.21 86.64)
		(width 0.11)
		(layer "F.Cu")
		(net 429)
	)
	(segment
		(start 100.659113 84.474917)
		(end 100.641242 84.446476)
		(width 0.11)
		(layer "F.Cu")
		(net 429)
	)
	(segment
		(start 99.545533 90.776416)
		(end 99.562951 90.758998)
		(width 0.11)
		(layer "F.Cu")
		(net 429)
	)
	(segment
		(start 100.266477 86.157274)
		(end 100.242726 86.133523)
		(width 0.11)
		(layer "F.Cu")
		(net 429)
	)
	(segment
		(start 100.242726 86.546476)
		(end 100.266477 86.522725)
		(width 0.11)
		(layer "F.Cu")
		(net 429)
	)
	(segment
		(start 100.326622 87.69376)
		(end 100.36 87.69)
		(width 0.11)
		(layer "F.Cu")
		(net 429)
	)
	(segment
		(start 100.848466 91.265931)
		(end 100.84067 91.196742)
		(width 0.11)
		(layer "F.Cu")
		(net 429)
	)
	(segment
		(start 100.224855 84.905082)
		(end 100.213761 84.873378)
		(width 0.11)
		(layer "F.Cu")
		(net 429)
	)
	(segment
		(start 100.673967 85.14)
		(end 100.670207 85.106621)
		(width 0.11)
		(layer "F.Cu")
		(net 429)
	)
	(segment
		(start 100.659113 86.405082)
		(end 100.670207 86.373378)
		(width 0.11)
		(layer "F.Cu")
		(net 429)
	)
	(segment
		(start 100.557346 86.19376)
		(end 100.523967 86.19)
		(width 0.11)
		(layer "F.Cu")
		(net 429)
	)
	(segment
		(start 100.641242 85.833523)
		(end 100.659113 85.805082)
		(width 0.11)
		(layer "F.Cu")
		(net 429)
	)
	(segment
		(start 100.89067 90.316742)
		(end 100.867674 90.251023)
		(width 0.11)
		(layer "F.Cu")
		(net 429)
	)
	(segment
		(start 100.659113 87.005082)
		(end 100.670207 86.973378)
		(width 0.11)
		(layer "F.Cu")
		(net 429)
	)
	(segment
		(start 100.294918 86.504854)
		(end 100.326622 86.49376)
		(width 0.11)
		(layer "F.Cu")
		(net 429)
	)
	(segment
		(start 100.326622 84.986239)
		(end 100.294918 84.975145)
		(width 0.11)
		(layer "F.Cu")
		(net 429)
	)
	(segment
		(start 100.641242 84.446476)
		(end 100.617491 84.422725)
		(width 0.11)
		(layer "F.Cu")
		(net 429)
	)
	(segment
		(start 100.659113 85.674917)
		(end 100.641242 85.646476)
		(width 0.11)
		(layer "F.Cu")
		(net 429)
	)
	(segment
		(start 99.524292 90.869477)
		(end 99.521534 90.845)
		(width 0.11)
		(layer "F.Cu")
		(net 429)
	)
	(segment
		(start 100.266477 86.522725)
		(end 100.294918 86.504854)
		(width 0.11)
		(layer "F.Cu")
		(net 429)
	)
	(segment
		(start 100.224855 84.774917)
		(end 100.242726 84.746476)
		(width 0.11)
		(layer "F.Cu")
		(net 429)
	)
	(segment
		(start 100.523967 85.59)
		(end 100.36 85.59)
		(width 0.11)
		(layer "F.Cu")
		(net 429)
	)
	(segment
		(start 100.587534 90.075)
		(end 100.32 90.075)
		(width 0.11)
		(layer "F.Cu")
		(net 429)
	)
	(segment
		(start 100.641242 87.033523)
		(end 100.659113 87.005082)
		(width 0.11)
		(layer "F.Cu")
		(net 429)
	)
	(segment
		(start 100.21 84.84)
		(end 100.213761 84.806621)
		(width 0.11)
		(layer "F.Cu")
		(net 429)
	)
	(segment
		(start 100.326622 86.49376)
		(end 100.36 86.49)
		(width 0.11)
		(layer "F.Cu")
		(net 429)
	)
	(segment
		(start 100.21 83.776)
		(end 100.611 83.375)
		(width 0.11)
		(layer "F.Cu")
		(net 429)
	)
	(segment
		(start 100.670207 87.506621)
		(end 100.659113 87.474917)
		(width 0.11)
		(layer "F.Cu")
		(net 429)
	)
	(segment
		(start 100.213761 85.473378)
		(end 100.21 85.44)
		(width 0.11)
		(layer "F.Cu")
		(net 429)
	)
	(segment
		(start 100.83063 90.192068)
		(end 100.781397 90.142835)
		(width 0.11)
		(layer "F.Cu")
		(net 429)
	)
	(segment
		(start 100.242726 84.933523)
		(end 100.224855 84.905082)
		(width 0.11)
		(layer "F.Cu")
		(net 429)
	)
	(segment
		(start 100.557346 87.086239)
		(end 100.58905 87.075145)
		(width 0.11)
		(layer "F.Cu")
		(net 429)
	)
	(segment
		(start 100.557346 86.486239)
		(end 100.58905 86.475145)
		(width 0.11)
		(layer "F.Cu")
		(net 429)
	)
	(segment
		(start 99.583807 90.944106)
		(end 99.562951 90.931001)
		(width 0.11)
		(layer "F.Cu")
		(net 429)
	)
	(segment
		(start 100.673967 84.54)
		(end 100.670207 84.506621)
		(width 0.11)
		(layer "F.Cu")
		(net 429)
	)
	(segment
		(start 100.673967 86.94)
		(end 100.670207 86.906621)
		(width 0.11)
		(layer "F.Cu")
		(net 429)
	)
	(segment
		(start 100.224855 85.505082)
		(end 100.213761 85.473378)
		(width 0.11)
		(layer "F.Cu")
		(net 429)
	)
	(segment
		(start 100.670207 85.106621)
		(end 100.659113 85.074917)
		(width 0.11)
		(layer "F.Cu")
		(net 429)
	)
	(segment
		(start 100.294918 84.704854)
		(end 100.326622 84.69376)
		(width 0.11)
		(layer "F.Cu")
		(net 429)
	)
	(segment
		(start 100.659113 87.474917)
		(end 100.641242 87.446476)
		(width 0.11)
		(layer "F.Cu")
		(net 429)
	)
	(segment
		(start 100.242726 87.146476)
		(end 100.266477 87.122725)
		(width 0.11)
		(layer "F.Cu")
		(net 429)
	)
	(segment
		(start 100.224855 87.305082)
		(end 100.213761 87.273378)
		(width 0.11)
		(layer "F.Cu")
		(net 429)
	)
	(segment
		(start 100.220893 90.012727)
		(end 100.212757 89.989477)
		(width 0.11)
		(layer "F.Cu")
		(net 429)
	)
	(segment
		(start 100.867674 90.558976)
		(end 100.89067 90.493257)
		(width 0.11)
		(layer "F.Cu")
		(net 429)
	)
	(segment
		(start 100.266477 85.322725)
		(end 100.294918 85.304854)
		(width 0.11)
		(layer "F.Cu")
		(net 429)
	)
	(segment
		(start 100.817674 91.131023)
		(end 100.78063 91.072068)
		(width 0.11)
		(layer "F.Cu")
		(net 429)
	)
	(segment
		(start 100.641242 86.433523)
		(end 100.659113 86.405082)
		(width 0.11)
		(layer "F.Cu")
		(net 429)
	)
	(segment
		(start 100.272272 90.064106)
		(end 100.251416 90.051001)
		(width 0.11)
		(layer "F.Cu")
		(net 429)
	)
	(segment
		(start 100.224855 84.305082)
		(end 100.213761 84.273378)
		(width 0.11)
		(layer "F.Cu")
		(net 429)
	)
	(segment
		(start 100.295522 90.072242)
		(end 100.272272 90.064106)
		(width 0.11)
		(layer "F.Cu")
		(net 429)
	)
	(segment
		(start 100.731397 91.547164)
		(end 100.78063 91.497931)
		(width 0.11)
		(layer "F.Cu")
		(net 429)
	)
	(segment
		(start 100.557346 85.886239)
		(end 100.58905 85.875145)
		(width 0.11)
		(layer "F.Cu")
		(net 429)
	)
	(segment
		(start 100.557346 87.686239)
		(end 100.58905 87.675145)
		(width 0.11)
		(layer "F.Cu")
		(net 429)
	)
	(segment
		(start 100.670207 86.906621)
		(end 100.659113 86.874917)
		(width 0.11)
		(layer "F.Cu")
		(net 429)
	)
	(segment
		(start 100.83063 90.617931)
		(end 100.867674 90.558976)
		(width 0.11)
		(layer "F.Cu")
		(net 429)
	)
	(segment
		(start 100.251416 91.638998)
		(end 100.272272 91.625893)
		(width 0.11)
		(layer "F.Cu")
		(net 429)
	)
	(segment
		(start 100.537534 90.955)
		(end 99.631534 90.955)
		(width 0.11)
		(layer "F.Cu")
		(net 429)
	)
	(segment
		(start 100.266477 87.357274)
		(end 100.242726 87.333523)
		(width 0.11)
		(layer "F.Cu")
		(net 429)
	)
	(segment
		(start 100.213761 84.806621)
		(end 100.224855 84.774917)
		(width 0.11)
		(layer "F.Cu")
		(net 429)
	)
	(segment
		(start 100.326622 84.69376)
		(end 100.36 84.69)
		(width 0.11)
		(layer "F.Cu")
		(net 429)
	)
	(segment
		(start 99.532428 90.892727)
		(end 99.524292 90.869477)
		(width 0.11)
		(layer "F.Cu")
		(net 429)
	)
	(segment
		(start 100.641242 85.646476)
		(end 100.617491 85.622725)
		(width 0.11)
		(layer "F.Cu")
		(net 429)
	)
	(segment
		(start 100.672442 90.985791)
		(end 100.606723 90.962795)
		(width 0.11)
		(layer "F.Cu")
		(net 429)
	)
	(segment
		(start 100.617491 86.457274)
		(end 100.641242 86.433523)
		(width 0.11)
		(layer "F.Cu")
		(net 429)
	)
	(segment
		(start 100.58905 86.475145)
		(end 100.617491 86.457274)
		(width 0.11)
		(layer "F.Cu")
		(net 429)
	)
	(segment
		(start 100.36 84.69)
		(end 100.523967 84.69)
		(width 0.11)
		(layer "F.Cu")
		(net 429)
	)
	(segment
		(start 99.562951 90.931001)
		(end 99.545533 90.913583)
		(width 0.11)
		(layer "F.Cu")
		(net 429)
	)
	(segment
		(start 99.607057 90.952242)
		(end 99.583807 90.944106)
		(width 0.11)
		(layer "F.Cu")
		(net 429)
	)
	(segment
		(start 100.867674 90.251023)
		(end 100.83063 90.192068)
		(width 0.11)
		(layer "F.Cu")
		(net 429)
	)
	(segment
		(start 100.212757 89.989477)
		(end 100.21 89.965)
		(width 0.11)
		(layer "F.Cu")
		(net 429)
	)
	(segment
		(start 100.523967 85.89)
		(end 100.557346 85.886239)
		(width 0.11)
		(layer "F.Cu")
		(net 429)
	)
	(segment
		(start 100.557346 84.39376)
		(end 100.523967 84.39)
		(width 0.11)
		(layer "F.Cu")
		(net 429)
	)
	(segment
		(start 99.607057 90.737757)
		(end 99.631534 90.735)
		(width 0.11)
		(layer "F.Cu")
		(net 429)
	)
	(segment
		(start 100.557346 87.39376)
		(end 100.523967 87.39)
		(width 0.11)
		(layer "F.Cu")
		(net 429)
	)
	(segment
		(start 100.212757 91.700522)
		(end 100.220893 91.677272)
		(width 0.11)
		(layer "F.Cu")
		(net 429)
	)
	(segment
		(start 100.233998 91.656416)
		(end 100.251416 91.638998)
		(width 0.11)
		(layer "F.Cu")
		(net 429)
	)
	(segment
		(start 100.294918 86.775145)
		(end 100.266477 86.757274)
		(width 0.11)
		(layer "F.Cu")
		(net 429)
	)
	(segment
		(start 100.58905 85.604854)
		(end 100.557346 85.59376)
		(width 0.11)
		(layer "F.Cu")
		(net 429)
	)
	(segment
		(start 100.641242 85.046476)
		(end 100.617491 85.022725)
		(width 0.11)
		(layer "F.Cu")
		(net 429)
	)
	(segment
		(start 100.326622 85.29376)
		(end 100.36 85.29)
		(width 0.11)
		(layer "F.Cu")
		(net 429)
	)
	(segment
		(start 100.242726 85.946476)
		(end 100.266477 85.922725)
		(width 0.11)
		(layer "F.Cu")
		(net 429)
	)
	(segment
		(start 100.641242 87.633523)
		(end 100.659113 87.605082)
		(width 0.11)
		(layer "F.Cu")
		(net 429)
	)
	(segment
		(start 99.532428 90.797272)
		(end 99.545533 90.776416)
		(width 0.11)
		(layer "F.Cu")
		(net 429)
	)
	(segment
		(start 100.242726 87.333523)
		(end 100.224855 87.305082)
		(width 0.11)
		(layer "F.Cu")
		(net 429)
	)
	(segment
		(start 100.35 92.797851)
		(end 100.21 92.657851)
		(width 0.11)
		(layer "F.Cu")
		(net 429)
	)
	(segment
		(start 100.606723 91.607204)
		(end 100.672442 91.584208)
		(width 0.11)
		(layer "F.Cu")
		(net 429)
	)
	(segment
		(start 100.670207 85.773378)
		(end 100.673967 85.74)
		(width 0.11)
		(layer "F.Cu")
		(net 429)
	)
	(segment
		(start 100.36 87.39)
		(end 100.326622 87.386239)
		(width 0.11)
		(layer "F.Cu")
		(net 429)
	)
	(segment
		(start 100.58905 84.675145)
		(end 100.617491 84.657274)
		(width 0.11)
		(layer "F.Cu")
		(net 429)
	)
	(segment
		(start 100.21 87.24)
		(end 100.213761 87.206621)
		(width 0.11)
		(layer "F.Cu")
		(net 429)
	)
	(segment
		(start 99.631534 90.735)
		(end 100.587534 90.735)
		(width 0.11)
		(layer "F.Cu")
		(net 429)
	)
	(segment
		(start 100.659113 85.805082)
		(end 100.670207 85.773378)
		(width 0.11)
		(layer "F.Cu")
		(net 429)
	)
	(segment
		(start 100.617491 85.022725)
		(end 100.58905 85.004854)
		(width 0.11)
		(layer "F.Cu")
		(net 429)
	)
	(segment
		(start 100.266477 84.722725)
		(end 100.294918 84.704854)
		(width 0.11)
		(layer "F.Cu")
		(net 429)
	)
	(segment
		(start 100.266477 87.722725)
		(end 100.294918 87.704854)
		(width 0.11)
		(layer "F.Cu")
		(net 429)
	)
	(segment
		(start 100.294918 85.304854)
		(end 100.326622 85.29376)
		(width 0.11)
		(layer "F.Cu")
		(net 429)
	)
	(segment
		(start 100.36 84.39)
		(end 100.326622 84.386239)
		(width 0.11)
		(layer "F.Cu")
		(net 429)
	)
	(segment
		(start 100.557346 86.79376)
		(end 100.523967 86.79)
		(width 0.11)
		(layer "F.Cu")
		(net 429)
	)
	(segment
		(start 100.21 91.725)
		(end 100.212757 91.700522)
		(width 0.11)
		(layer "F.Cu")
		(net 429)
	)
	(segment
		(start 100.242726 87.746476)
		(end 100.266477 87.722725)
		(width 0.11)
		(layer "F.Cu")
		(net 429)
	)
	(segment
		(start 100.213761 86.006621)
		(end 100.224855 85.974917)
		(width 0.11)
		(layer "F.Cu")
		(net 429)
	)
	(segment
		(start 100.523967 86.49)
		(end 100.557346 86.486239)
		(width 0.11)
		(layer "F.Cu")
		(net 429)
	)
	(segment
		(start 100.294918 87.104854)
		(end 100.326622 87.09376)
		(width 0.11)
		(layer "F.Cu")
		(net 429)
	)
	(segment
		(start 100.266477 85.922725)
		(end 100.294918 85.904854)
		(width 0.11)
		(layer "F.Cu")
		(net 429)
	)
	(segment
		(start 100.523967 86.19)
		(end 100.36 86.19)
		(width 0.11)
		(layer "F.Cu")
		(net 429)
	)
	(segment
		(start 100.641242 86.246476)
		(end 100.617491 86.222725)
		(width 0.11)
		(layer "F.Cu")
		(net 429)
	)
	(segment
		(start 100.36 85.59)
		(end 100.326622 85.586239)
		(width 0.11)
		(layer "F.Cu")
		(net 429)
	)
	(segment
		(start 100.295522 91.617757)
		(end 100.32 91.615)
		(width 0.11)
		(layer "F.Cu")
		(net 429)
	)
	(segment
		(start 100.557346 84.99376)
		(end 100.523967 84.99)
		(width 0.11)
		(layer "F.Cu")
		(net 429)
	)
	(segment
		(start 100.84067 91.196742)
		(end 100.817674 91.131023)
		(width 0.11)
		(layer "F.Cu")
		(net 429)
	)
	(segment
		(start 100.523967 86.79)
		(end 100.36 86.79)
		(width 0.11)
		(layer "F.Cu")
		(net 429)
	)
	(segment
		(start 99.562951 90.758998)
		(end 99.583807 90.745893)
		(width 0.11)
		(layer "F.Cu")
		(net 429)
	)
	(segment
		(start 100.89067 90.493257)
		(end 100.898466 90.424068)
		(width 0.11)
		(layer "F.Cu")
		(net 429)
	)
	(segment
		(start 100.641242 84.633523)
		(end 100.659113 84.605082)
		(width 0.11)
		(layer "F.Cu")
		(net 429)
	)
	(segment
		(start 100.21 86.64)
		(end 100.213761 86.606621)
		(width 0.11)
		(layer "F.Cu")
		(net 429)
	)
	(segment
		(start 100.617491 86.822725)
		(end 100.58905 86.804854)
		(width 0.11)
		(layer "F.Cu")
		(net 429)
	)
	(segment
		(start 100.21 89.965)
		(end 100.21 87.84)
		(width 0.11)
		(layer "F.Cu")
		(net 429)
	)
	(segment
		(start 100.617491 84.657274)
		(end 100.641242 84.633523)
		(width 0.11)
		(layer "F.Cu")
		(net 429)
	)
	(segment
		(start 100.242726 84.333523)
		(end 100.224855 84.305082)
		(width 0.11)
		(layer "F.Cu")
		(net 429)
	)
	(segment
		(start 100.36 85.29)
		(end 100.523967 85.29)
		(width 0.11)
		(layer "F.Cu")
		(net 429)
	)
	(segment
		(start 100.523967 87.69)
		(end 100.557346 87.686239)
		(width 0.11)
		(layer "F.Cu")
		(net 429)
	)
	(segment
		(start 100.213761 87.806621)
		(end 100.224855 87.774917)
		(width 0.11)
		(layer "F.Cu")
		(net 429)
	)
	(segment
		(start 100.266477 84.357274)
		(end 100.242726 84.333523)
		(width 0.11)
		(layer "F.Cu")
		(net 429)
	)
	(segment
		(start 100.670207 86.973378)
		(end 100.673967 86.94)
		(width 0.11)
		(layer "F.Cu")
		(net 429)
	)
	(segment
		(start 100.84067 91.373257)
		(end 100.848466 91.304068)
		(width 0.11)
		(layer "F.Cu")
		(net 429)
	)
	(segment
		(start 100.78063 91.072068)
		(end 100.731397 91.022835)
		(width 0.11)
		(layer "F.Cu")
		(net 429)
	)
	(segment
		(start 100.251416 90.051001)
		(end 100.233998 90.033583)
		(width 0.11)
		(layer "F.Cu")
		(net 429)
	)
	(segment
		(start 100.848466 91.304068)
		(end 100.848466 91.265931)
		(width 0.11)
		(layer "F.Cu")
		(net 429)
	)
	(segment
		(start 100.817674 91.438976)
		(end 100.84067 91.373257)
		(width 0.11)
		(layer "F.Cu")
		(net 429)
	)
	(segment
		(start 100.326622 86.786239)
		(end 100.294918 86.775145)
		(width 0.11)
		(layer "F.Cu")
		(net 429)
	)
	(segment
		(start 100.659113 87.605082)
		(end 100.670207 87.573378)
		(width 0.11)
		(layer "F.Cu")
		(net 429)
	)
	(segment
		(start 100.266477 87.122725)
		(end 100.294918 87.104854)
		(width 0.11)
		(layer "F.Cu")
		(net 429)
	)
	(segment
		(start 100.213761 86.073378)
		(end 100.21 86.04)
		(width 0.11)
		(layer "F.Cu")
		(net 429)
	)
	(segment
		(start 100.224855 86.105082)
		(end 100.213761 86.073378)
		(width 0.11)
		(layer "F.Cu")
		(net 429)
	)
	(segment
		(start 100.266477 85.557274)
		(end 100.242726 85.533523)
		(width 0.11)
		(layer "F.Cu")
		(net 429)
	)
	(segment
		(start 99.521534 90.845)
		(end 99.524292 90.820522)
		(width 0.11)
		(layer "F.Cu")
		(net 429)
	)
	(segment
		(start 101.1054 88.520791)
		(end 101.171119 88.497795)
		(width 0.11)
		(layer "F.Cu")
		(net 430)
	)
	(segment
		(start 102.009207 89.346001)
		(end 102.026625 89.328583)
		(width 0.11)
		(layer "F.Cu")
		(net 430)
	)
	(segment
		(start 101.35 92.797851)
		(end 101.49 92.657851)
		(width 0.11)
		(layer "F.Cu")
		(net 430)
	)
	(segment
		(start 101.49 86.484436)
		(end 103.915 84.059436)
		(width 0.11)
		(layer "F.Cu")
		(net 430)
	)
	(segment
		(start 102.533 81.938564)
		(end 102.533 81.741)
		(width 0.11)
		(layer "F.Cu")
		(net 430)
	)
	(segment
		(start 100.929376 88.800931)
		(end 100.937172 88.731742)
		(width 0.11)
		(layer "F.Cu")
		(net 430)
	)
	(segment
		(start 101.49 89.680931)
		(end 101.497795 89.611742)
		(width 0.11)
		(layer "F.Cu")
		(net 430)
	)
	(segment
		(start 101.240308 89.15)
		(end 101.171119 89.142204)
		(width 0.11)
		(layer "F.Cu")
		(net 430)
	)
	(segment
		(start 103.915 84.059436)
		(end 103.915 82.720564)
		(width 0.11)
		(layer "F.Cu")
		(net 430)
	)
	(segment
		(start 102.009207 88.466001)
		(end 102.026625 88.448583)
		(width 0.11)
		(layer "F.Cu")
		(net 430)
	)
	(segment
		(start 102.929436 82.335)
		(end 102.533 81.938564)
		(width 0.11)
		(layer "F.Cu")
		(net 430)
	)
	(segment
		(start 102.050624 88.38)
		(end 102.047866 88.355522)
		(width 0.11)
		(layer "F.Cu")
		(net 430)
	)
	(segment
		(start 101.965101 89.152757)
		(end 101.940624 89.15)
		(width 0.11)
		(layer "F.Cu")
		(net 430)
	)
	(segment
		(start 100.929376 88.839068)
		(end 100.929376 88.800931)
		(width 0.11)
		(layer "F.Cu")
		(net 430)
	)
	(segment
		(start 101.171119 89.142204)
		(end 101.1054 89.119208)
		(width 0.11)
		(layer "F.Cu")
		(net 430)
	)
	(segment
		(start 101.965101 89.367242)
		(end 101.988351 89.359106)
		(width 0.11)
		(layer "F.Cu")
		(net 430)
	)
	(segment
		(start 101.965101 88.487242)
		(end 101.988351 88.479106)
		(width 0.11)
		(layer "F.Cu")
		(net 430)
	)
	(segment
		(start 102.050624 89.26)
		(end 102.047866 89.235522)
		(width 0.11)
		(layer "F.Cu")
		(net 430)
	)
	(segment
		(start 101.988351 89.359106)
		(end 102.009207 89.346001)
		(width 0.11)
		(layer "F.Cu")
		(net 430)
	)
	(segment
		(start 102.026625 89.328583)
		(end 102.03973 89.307727)
		(width 0.11)
		(layer "F.Cu")
		(net 430)
	)
	(segment
		(start 101.940624 89.15)
		(end 101.240308 89.15)
		(width 0.11)
		(layer "F.Cu")
		(net 430)
	)
	(segment
		(start 101.988351 88.280893)
		(end 101.965101 88.272757)
		(width 0.11)
		(layer "F.Cu")
		(net 430)
	)
	(segment
		(start 101.607068 89.437835)
		(end 101.666023 89.400791)
		(width 0.11)
		(layer "F.Cu")
		(net 430)
	)
	(segment
		(start 102.009207 88.293998)
		(end 101.988351 88.280893)
		(width 0.11)
		(layer "F.Cu")
		(net 430)
	)
	(segment
		(start 102.03973 88.332272)
		(end 102.026625 88.311416)
		(width 0.11)
		(layer "F.Cu")
		(net 430)
	)
	(segment
		(start 101.607068 88.202164)
		(end 101.557835 88.152931)
		(width 0.11)
		(layer "F.Cu")
		(net 430)
	)
	(segment
		(start 100.960168 88.666023)
		(end 100.997212 88.607068)
		(width 0.11)
		(layer "F.Cu")
		(net 430)
	)
	(segment
		(start 101.988351 88.479106)
		(end 102.009207 88.466001)
		(width 0.11)
		(layer "F.Cu")
		(net 430)
	)
	(segment
		(start 102.047866 89.284477)
		(end 102.050624 89.26)
		(width 0.11)
		(layer "F.Cu")
		(net 430)
	)
	(segment
		(start 102.03973 89.307727)
		(end 102.047866 89.284477)
		(width 0.11)
		(layer "F.Cu")
		(net 430)
	)
	(segment
		(start 101.497795 88.028257)
		(end 101.49 87.959068)
		(width 0.11)
		(layer "F.Cu")
		(net 430)
	)
	(segment
		(start 103.529436 82.335)
		(end 102.929436 82.335)
		(width 0.11)
		(layer "F.Cu")
		(net 430)
	)
	(segment
		(start 101.940624 89.37)
		(end 101.965101 89.367242)
		(width 0.11)
		(layer "F.Cu")
		(net 430)
	)
	(segment
		(start 101.988351 89.160893)
		(end 101.965101 89.152757)
		(width 0.11)
		(layer "F.Cu")
		(net 430)
	)
	(segment
		(start 101.240308 88.49)
		(end 101.940624 88.49)
		(width 0.11)
		(layer "F.Cu")
		(net 430)
	)
	(segment
		(start 102.03973 88.427727)
		(end 102.047866 88.404477)
		(width 0.11)
		(layer "F.Cu")
		(net 430)
	)
	(segment
		(start 100.997212 88.607068)
		(end 101.046445 88.557835)
		(width 0.11)
		(layer "F.Cu")
		(net 430)
	)
	(segment
		(start 101.520791 89.546023)
		(end 101.557835 89.487068)
		(width 0.11)
		(layer "F.Cu")
		(net 430)
	)
	(segment
		(start 101.940624 88.27)
		(end 101.800931 88.27)
		(width 0.11)
		(layer "F.Cu")
		(net 430)
	)
	(segment
		(start 101.666023 88.239208)
		(end 101.607068 88.202164)
		(width 0.11)
		(layer "F.Cu")
		(net 430)
	)
	(segment
		(start 100.937172 88.908257)
		(end 100.929376 88.839068)
		(width 0.11)
		(layer "F.Cu")
		(net 430)
	)
	(segment
		(start 102.047866 89.235522)
		(end 102.03973 89.212272)
		(width 0.11)
		(layer "F.Cu")
		(net 430)
	)
	(segment
		(start 101.800931 88.27)
		(end 101.731742 88.262204)
		(width 0.11)
		(layer "F.Cu")
		(net 430)
	)
	(segment
		(start 102.047866 88.355522)
		(end 102.03973 88.332272)
		(width 0.11)
		(layer "F.Cu")
		(net 430)
	)
	(segment
		(start 101.965101 88.272757)
		(end 101.940624 88.27)
		(width 0.11)
		(layer "F.Cu")
		(net 430)
	)
	(segment
		(start 102.047866 88.404477)
		(end 102.050624 88.38)
		(width 0.11)
		(layer "F.Cu")
		(net 430)
	)
	(segment
		(start 102.009207 89.173998)
		(end 101.988351 89.160893)
		(width 0.11)
		(layer "F.Cu")
		(net 430)
	)
	(segment
		(start 101.731742 89.377795)
		(end 101.800931 89.37)
		(width 0.11)
		(layer "F.Cu")
		(net 430)
	)
	(segment
		(start 101.497795 89.611742)
		(end 101.520791 89.546023)
		(width 0.11)
		(layer "F.Cu")
		(net 430)
	)
	(segment
		(start 102.026625 89.191416)
		(end 102.009207 89.173998)
		(width 0.11)
		(layer "F.Cu")
		(net 430)
	)
	(segment
		(start 101.557835 88.152931)
		(end 101.520791 88.093976)
		(width 0.11)
		(layer "F.Cu")
		(net 430)
	)
	(segment
		(start 101.49 92.657851)
		(end 101.49 89.680931)
		(width 0.11)
		(layer "F.Cu")
		(net 430)
	)
	(segment
		(start 102.026625 88.448583)
		(end 102.03973 88.427727)
		(width 0.11)
		(layer "F.Cu")
		(net 430)
	)
	(segment
		(start 101.666023 89.400791)
		(end 101.731742 89.377795)
		(width 0.11)
		(layer "F.Cu")
		(net 430)
	)
	(segment
		(start 101.520791 88.093976)
		(end 101.497795 88.028257)
		(width 0.11)
		(layer "F.Cu")
		(net 430)
	)
	(segment
		(start 100.997212 89.032931)
		(end 100.960168 88.973976)
		(width 0.11)
		(layer "F.Cu")
		(net 430)
	)
	(segment
		(start 101.800931 89.37)
		(end 101.940624 89.37)
		(width 0.11)
		(layer "F.Cu")
		(net 430)
	)
	(segment
		(start 101.940624 88.49)
		(end 101.965101 88.487242)
		(width 0.11)
		(layer "F.Cu")
		(net 430)
	)
	(segment
		(start 102.03973 89.212272)
		(end 102.026625 89.191416)
		(width 0.11)
		(layer "F.Cu")
		(net 430)
	)
	(segment
		(start 101.046445 89.082164)
		(end 100.997212 89.032931)
		(width 0.11)
		(layer "F.Cu")
		(net 430)
	)
	(segment
		(start 102.533 81.741)
		(end 101.627 80.835)
		(width 0.11)
		(layer "F.Cu")
		(net 430)
	)
	(segment
		(start 102.026625 88.311416)
		(end 102.009207 88.293998)
		(width 0.11)
		(layer "F.Cu")
		(net 430)
	)
	(segment
		(start 100.960168 88.973976)
		(end 100.937172 88.908257)
		(width 0.11)
		(layer "F.Cu")
		(net 430)
	)
	(segment
		(start 100.937172 88.731742)
		(end 100.960168 88.666023)
		(width 0.11)
		(layer "F.Cu")
		(net 430)
	)
	(segment
		(start 103.915 82.720564)
		(end 103.529436 82.335)
		(width 0.11)
		(layer "F.Cu")
		(net 430)
	)
	(segment
		(start 101.171119 88.497795)
		(end 101.240308 88.49)
		(width 0.11)
		(layer "F.Cu")
		(net 430)
	)
	(segment
		(start 101.731742 88.262204)
		(end 101.666023 88.239208)
		(width 0.11)
		(layer "F.Cu")
		(net 430)
	)
	(segment
		(start 101.557835 89.487068)
		(end 101.607068 89.437835)
		(width 0.11)
		(layer "F.Cu")
		(net 430)
	)
	(segment
		(start 101.1054 89.119208)
		(end 101.046445 89.082164)
		(width 0.11)
		(layer "F.Cu")
		(net 430)
	)
	(segment
		(start 101.046445 88.557835)
		(end 101.1054 88.520791)
		(width 0.11)
		(layer "F.Cu")
		(net 430)
	)
	(segment
		(start 101.49 87.959068)
		(end 101.49 86.484436)
		(width 0.11)
		(layer "F.Cu")
		(net 430)
	)
	(segment
		(start 102.270624 89.279068)
		(end 102.270624 89.240931)
		(width 0.11)
		(layer "F.Cu")
		(net 431)
	)
	(segment
		(start 101.733998 88.008583)
		(end 101.720893 87.987727)
		(width 0.11)
		(layer "F.Cu")
		(net 431)
	)
	(segment
		(start 101.959692 88.71)
		(end 102.028881 88.702204)
		(width 0.11)
		(layer "F.Cu")
		(net 431)
	)
	(segment
		(start 101.71 87.94)
		(end 101.71 86.575564)
		(width 0.11)
		(layer "F.Cu")
		(net 431)
	)
	(segment
		(start 101.173375 88.888583)
		(end 101.16027 88.867727)
		(width 0.11)
		(layer "F.Cu")
		(net 431)
	)
	(segment
		(start 101.772272 88.039106)
		(end 101.751416 88.026001)
		(width 0.11)
		(layer "F.Cu")
		(net 431)
	)
	(segment
		(start 101.16027 88.772272)
		(end 101.173375 88.751416)
		(width 0.11)
		(layer "F.Cu")
		(net 431)
	)
	(segment
		(start 101.85 92.797851)
		(end 101.71 92.657851)
		(width 0.11)
		(layer "F.Cu")
		(net 431)
	)
	(segment
		(start 102.239832 88.533976)
		(end 102.262828 88.468257)
		(width 0.11)
		(layer "F.Cu")
		(net 431)
	)
	(segment
		(start 101.751416 89.613998)
		(end 101.772272 89.600893)
		(width 0.11)
		(layer "F.Cu")
		(net 431)
	)
	(segment
		(start 102.270624 88.399068)
		(end 102.270624 88.360931)
		(width 0.11)
		(layer "F.Cu")
		(net 431)
	)
	(segment
		(start 102.153555 88.642164)
		(end 102.202788 88.592931)
		(width 0.11)
		(layer "F.Cu")
		(net 431)
	)
	(segment
		(start 102.202788 88.592931)
		(end 102.239832 88.533976)
		(width 0.11)
		(layer "F.Cu")
		(net 431)
	)
	(segment
		(start 101.720893 89.652272)
		(end 101.733998 89.631416)
		(width 0.11)
		(layer "F.Cu")
		(net 431)
	)
	(segment
		(start 101.152134 88.795522)
		(end 101.16027 88.772272)
		(width 0.11)
		(layer "F.Cu")
		(net 431)
	)
	(segment
		(start 101.173375 88.751416)
		(end 101.190793 88.733998)
		(width 0.11)
		(layer "F.Cu")
		(net 431)
	)
	(segment
		(start 101.16027 88.867727)
		(end 101.152134 88.844477)
		(width 0.11)
		(layer "F.Cu")
		(net 431)
	)
	(segment
		(start 101.149376 88.82)
		(end 101.152134 88.795522)
		(width 0.11)
		(layer "F.Cu")
		(net 431)
	)
	(segment
		(start 102.0946 88.960791)
		(end 102.028881 88.937795)
		(width 0.11)
		(layer "F.Cu")
		(net 431)
	)
	(segment
		(start 102.262828 89.171742)
		(end 102.239832 89.106023)
		(width 0.11)
		(layer "F.Cu")
		(net 431)
	)
	(segment
		(start 101.190793 88.733998)
		(end 101.211649 88.720893)
		(width 0.11)
		(layer "F.Cu")
		(net 431)
	)
	(segment
		(start 101.795522 89.592757)
		(end 101.82 89.59)
		(width 0.11)
		(layer "F.Cu")
		(net 431)
	)
	(segment
		(start 101.71 89.7)
		(end 101.712757 89.675522)
		(width 0.11)
		(layer "F.Cu")
		(net 431)
	)
	(segment
		(start 101.772272 89.600893)
		(end 101.795522 89.592757)
		(width 0.11)
		(layer "F.Cu")
		(net 431)
	)
	(segment
		(start 101.82 88.05)
		(end 101.795522 88.047242)
		(width 0.11)
		(layer "F.Cu")
		(net 431)
	)
	(segment
		(start 101.959692 89.59)
		(end 102.028881 89.582204)
		(width 0.11)
		(layer "F.Cu")
		(net 431)
	)
	(segment
		(start 103.020564 82.115)
		(end 102.753 81.847436)
		(width 0.11)
		(layer "F.Cu")
		(net 431)
	)
	(segment
		(start 102.239832 88.226023)
		(end 102.202788 88.167068)
		(width 0.11)
		(layer "F.Cu")
		(net 431)
	)
	(segment
		(start 102.202788 89.472931)
		(end 102.239832 89.413976)
		(width 0.11)
		(layer "F.Cu")
		(net 431)
	)
	(segment
		(start 101.71 92.657851)
		(end 101.71 89.7)
		(width 0.11)
		(layer "F.Cu")
		(net 431)
	)
	(segment
		(start 102.270624 89.240931)
		(end 102.262828 89.171742)
		(width 0.11)
		(layer "F.Cu")
		(net 431)
	)
	(segment
		(start 101.712757 87.964477)
		(end 101.71 87.94)
		(width 0.11)
		(layer "F.Cu")
		(net 431)
	)
	(segment
		(start 101.211649 88.919106)
		(end 101.190793 88.906001)
		(width 0.11)
		(layer "F.Cu")
		(net 431)
	)
	(segment
		(start 101.259376 88.71)
		(end 101.959692 88.71)
		(width 0.11)
		(layer "F.Cu")
		(net 431)
	)
	(segment
		(start 101.733998 89.631416)
		(end 101.751416 89.613998)
		(width 0.11)
		(layer "F.Cu")
		(net 431)
	)
	(segment
		(start 102.0946 89.559208)
		(end 102.153555 89.522164)
		(width 0.11)
		(layer "F.Cu")
		(net 431)
	)
	(segment
		(start 102.153555 88.117835)
		(end 102.0946 88.080791)
		(width 0.11)
		(layer "F.Cu")
		(net 431)
	)
	(segment
		(start 104.135 84.150564)
		(end 104.135 82.629436)
		(width 0.11)
		(layer "F.Cu")
		(net 431)
	)
	(segment
		(start 101.720893 87.987727)
		(end 101.712757 87.964477)
		(width 0.11)
		(layer "F.Cu")
		(net 431)
	)
	(segment
		(start 102.270624 88.360931)
		(end 102.262828 88.291742)
		(width 0.11)
		(layer "F.Cu")
		(net 431)
	)
	(segment
		(start 101.211649 88.720893)
		(end 101.234899 88.712757)
		(width 0.11)
		(layer "F.Cu")
		(net 431)
	)
	(segment
		(start 101.959692 88.93)
		(end 101.259376 88.93)
		(width 0.11)
		(layer "F.Cu")
		(net 431)
	)
	(segment
		(start 101.190793 88.906001)
		(end 101.173375 88.888583)
		(width 0.11)
		(layer "F.Cu")
		(net 431)
	)
	(segment
		(start 102.028881 88.937795)
		(end 101.959692 88.93)
		(width 0.11)
		(layer "F.Cu")
		(net 431)
	)
	(segment
		(start 101.259376 88.93)
		(end 101.234899 88.927242)
		(width 0.11)
		(layer "F.Cu")
		(net 431)
	)
	(segment
		(start 101.234899 88.927242)
		(end 101.211649 88.919106)
		(width 0.11)
		(layer "F.Cu")
		(net 431)
	)
	(segment
		(start 101.152134 88.844477)
		(end 101.149376 88.82)
		(width 0.11)
		(layer "F.Cu")
		(net 431)
	)
	(segment
		(start 102.202788 89.047068)
		(end 102.153555 88.997835)
		(width 0.11)
		(layer "F.Cu")
		(net 431)
	)
	(segment
		(start 102.0946 88.080791)
		(end 102.028881 88.057795)
		(width 0.11)
		(layer "F.Cu")
		(net 431)
	)
	(segment
		(start 103.620564 82.115)
		(end 103.020564 82.115)
		(width 0.11)
		(layer "F.Cu")
		(net 431)
	)
	(segment
		(start 102.153555 89.522164)
		(end 102.202788 89.472931)
		(width 0.11)
		(layer "F.Cu")
		(net 431)
	)
	(segment
		(start 101.712757 89.675522)
		(end 101.720893 89.652272)
		(width 0.11)
		(layer "F.Cu")
		(net 431)
	)
	(segment
		(start 102.239832 89.413976)
		(end 102.262828 89.348257)
		(width 0.11)
		(layer "F.Cu")
		(net 431)
	)
	(segment
		(start 101.234899 88.712757)
		(end 101.259376 88.71)
		(width 0.11)
		(layer "F.Cu")
		(net 431)
	)
	(segment
		(start 102.028881 88.702204)
		(end 102.0946 88.679208)
		(width 0.11)
		(layer "F.Cu")
		(net 431)
	)
	(segment
		(start 102.239832 89.106023)
		(end 102.202788 89.047068)
		(width 0.11)
		(layer "F.Cu")
		(net 431)
	)
	(segment
		(start 102.262828 88.291742)
		(end 102.239832 88.226023)
		(width 0.11)
		(layer "F.Cu")
		(net 431)
	)
	(segment
		(start 102.753 81.847436)
		(end 102.753 81.741)
		(width 0.11)
		(layer "F.Cu")
		(net 431)
	)
	(segment
		(start 101.751416 88.026001)
		(end 101.733998 88.008583)
		(width 0.11)
		(layer "F.Cu")
		(net 431)
	)
	(segment
		(start 104.135 82.629436)
		(end 103.620564 82.115)
		(width 0.11)
		(layer "F.Cu")
		(net 431)
	)
	(segment
		(start 102.028881 88.057795)
		(end 101.959692 88.05)
		(width 0.11)
		(layer "F.Cu")
		(net 431)
	)
	(segment
		(start 102.753 81.741)
		(end 103.659 80.835)
		(width 0.11)
		(layer "F.Cu")
		(net 431)
	)
	(segment
		(start 102.202788 88.167068)
		(end 102.153555 88.117835)
		(width 0.11)
		(layer "F.Cu")
		(net 431)
	)
	(segment
		(start 102.0946 88.679208)
		(end 102.153555 88.642164)
		(width 0.11)
		(layer "F.Cu")
		(net 431)
	)
	(segment
		(start 102.153555 88.997835)
		(end 102.0946 88.960791)
		(width 0.11)
		(layer "F.Cu")
		(net 431)
	)
	(segment
		(start 101.71 86.575564)
		(end 104.135 84.150564)
		(width 0.11)
		(layer "F.Cu")
		(net 431)
	)
	(segment
		(start 102.262828 88.468257)
		(end 102.270624 88.399068)
		(width 0.11)
		(layer "F.Cu")
		(net 431)
	)
	(segment
		(start 101.82 89.59)
		(end 101.959692 89.59)
		(width 0.11)
		(layer "F.Cu")
		(net 431)
	)
	(segment
		(start 102.262828 89.348257)
		(end 102.270624 89.279068)
		(width 0.11)
		(layer "F.Cu")
		(net 431)
	)
	(segment
		(start 101.795522 88.047242)
		(end 101.772272 88.039106)
		(width 0.11)
		(layer "F.Cu")
		(net 431)
	)
	(segment
		(start 101.959692 88.05)
		(end 101.82 88.05)
		(width 0.11)
		(layer "F.Cu")
		(net 431)
	)
	(segment
		(start 102.028881 89.582204)
		(end 102.0946 89.559208)
		(width 0.11)
		(layer "F.Cu")
		(net 431)
	)
	(segment
		(start 105.244599 79.904999)
		(end 104.665 80.484598)
		(width 0.11)
		(layer "F.Cu")
		(net 432)
	)
	(segment
		(start 104.665 80.484598)
		(end 104.665 89.339436)
		(width 0.11)
		(layer "F.Cu")
		(net 432)
	)
	(segment
		(start 102.49 92.657851)
		(end 102.35 92.797851)
		(width 0.11)
		(layer "F.Cu")
		(net 432)
	)
	(segment
		(start 106.792999 79.904999)
		(end 105.244599 79.904999)
		(width 0.11)
		(layer "F.Cu")
		(net 432)
	)
	(segment
		(start 102.49 91.514436)
		(end 102.49 92.657851)
		(width 0.11)
		(layer "F.Cu")
		(net 432)
	)
	(segment
		(start 107.723 80.835)
		(end 106.792999 79.904999)
		(width 0.11)
		(layer "F.Cu")
		(net 432)
	)
	(segment
		(start 104.665 89.339436)
		(end 102.49 91.514436)
		(width 0.11)
		(layer "F.Cu")
		(net 432)
	)
	(segment
		(start 104.885 84.865)
		(end 104.885 89.430564)
		(width 0.11)
		(layer "F.Cu")
		(net 433)
	)
	(segment
		(start 104.899855 84.799917)
		(end 104.888761 84.831621)
		(width 0.11)
		(layer "F.Cu")
		(net 433)
	)
	(segment
		(start 104.969918 82.000145)
		(end 105.001622 82.011239)
		(width 0.11)
		(layer "F.Cu")
		(net 433)
	)
	(segment
		(start 105.268122 82.311239)
		(end 105.234743 82.315)
		(width 0.11)
		(layer "F.Cu")
		(net 433)
	)
	(segment
		(start 104.917726 84.771476)
		(end 104.899855 84.799917)
		(width 0.11)
		(layer "F.Cu")
		(net 433)
	)
	(segment
		(start 104.899855 84.199917)
		(end 104.888761 84.231621)
		(width 0.11)
		(layer "F.Cu")
		(net 433)
	)
	(segment
		(start 105.268122 84.111239)
		(end 105.234743 84.115)
		(width 0.11)
		(layer "F.Cu")
		(net 433)
	)
	(segment
		(start 105.035 82.315)
		(end 105.001622 82.31876)
		(width 0.11)
		(layer "F.Cu")
		(net 433)
	)
	(segment
		(start 105.035 83.215)
		(end 105.234743 83.215)
		(width 0.11)
		(layer "F.Cu")
		(net 433)
	)
	(segment
		(start 104.917726 83.158523)
		(end 104.941477 83.182274)
		(width 0.11)
		(layer "F.Cu")
		(net 433)
	)
	(segment
		(start 105.268122 82.01876)
		(end 105.299826 82.029854)
		(width 0.11)
		(layer "F.Cu")
		(net 433)
	)
	(segment
		(start 104.969918 83.200145)
		(end 105.001622 83.211239)
		(width 0.11)
		(layer "F.Cu")
		(net 433)
	)
	(segment
		(start 104.899855 83.599917)
		(end 104.888761 83.631621)
		(width 0.11)
		(layer "F.Cu")
		(net 433)
	)
	(segment
		(start 105.234743 82.915)
		(end 105.035 82.915)
		(width 0.11)
		(layer "F.Cu")
		(net 433)
	)
	(segment
		(start 105.299826 82.029854)
		(end 105.328267 82.047725)
		(width 0.11)
		(layer "F.Cu")
		(net 433)
	)
	(segment
		(start 105.299826 83.500145)
		(end 105.268122 83.511239)
		(width 0.11)
		(layer "F.Cu")
		(net 433)
	)
	(segment
		(start 105.380983 84.531621)
		(end 105.384743 84.565)
		(width 0.11)
		(layer "F.Cu")
		(net 433)
	)
	(segment
		(start 105.352018 82.258523)
		(end 105.328267 82.282274)
		(width 0.11)
		(layer "F.Cu")
		(net 433)
	)
	(segment
		(start 104.888761 84.231621)
		(end 104.885 84.265)
		(width 0.11)
		(layer "F.Cu")
		(net 433)
	)
	(segment
		(start 104.888761 84.298378)
		(end 104.899855 84.330082)
		(width 0.11)
		(layer "F.Cu")
		(net 433)
	)
	(segment
		(start 105.384743 84.565)
		(end 105.380983 84.598378)
		(width 0.11)
		(layer "F.Cu")
		(net 433)
	)
	(segment
		(start 104.969918 82.929854)
		(end 104.941477 82.947725)
		(width 0.11)
		(layer "F.Cu")
		(net 433)
	)
	(segment
		(start 105.369889 83.299917)
		(end 105.380983 83.331621)
		(width 0.11)
		(layer "F.Cu")
		(net 433)
	)
	(segment
		(start 104.885 81.865)
		(end 104.888761 81.898378)
		(width 0.11)
		(layer "F.Cu")
		(net 433)
	)
	(segment
		(start 105.328267 82.647725)
		(end 105.352018 82.671476)
		(width 0.11)
		(layer "F.Cu")
		(net 433)
	)
	(segment
		(start 104.885 83.665)
		(end 104.888761 83.698378)
		(width 0.11)
		(layer "F.Cu")
		(net 433)
	)
	(segment
		(start 104.941477 82.947725)
		(end 104.917726 82.971476)
		(width 0.11)
		(layer "F.Cu")
		(net 433)
	)
	(segment
		(start 105.369889 84.499917)
		(end 105.380983 84.531621)
		(width 0.11)
		(layer "F.Cu")
		(net 433)
	)
	(segment
		(start 104.885 89.430564)
		(end 102.71 91.605564)
		(width 0.11)
		(layer "F.Cu")
		(net 433)
	)
	(segment
		(start 105.328267 84.082274)
		(end 105.299826 84.100145)
		(width 0.11)
		(layer "F.Cu")
		(net 433)
	)
	(segment
		(start 105.380983 83.331621)
		(end 105.384743 83.365)
		(width 0.11)
		(layer "F.Cu")
		(net 433)
	)
	(segment
		(start 104.885 83.065)
		(end 104.888761 83.098378)
		(width 0.11)
		(layer "F.Cu")
		(net 433)
	)
	(segment
		(start 104.941477 82.582274)
		(end 104.969918 82.600145)
		(width 0.11)
		(layer "F.Cu")
		(net 433)
	)
	(segment
		(start 105.234743 83.215)
		(end 105.268122 83.21876)
		(width 0.11)
		(layer "F.Cu")
		(net 433)
	)
	(segment
		(start 104.969918 83.800145)
		(end 105.001622 83.811239)
		(width 0.11)
		(layer "F.Cu")
		(net 433)
	)
	(segment
		(start 105.299826 82.629854)
		(end 105.328267 82.647725)
		(width 0.11)
		(layer "F.Cu")
		(net 433)
	)
	(segment
		(start 105.001622 83.811239)
		(end 105.035 83.815)
		(width 0.11)
		(layer "F.Cu")
		(net 433)
	)
	(segment
		(start 104.888761 83.031621)
		(end 104.885 83.065)
		(width 0.11)
		(layer "F.Cu")
		(net 433)
	)
	(segment
		(start 104.888761 81.898378)
		(end 104.899855 81.930082)
		(width 0.11)
		(layer "F.Cu")
		(net 433)
	)
	(segment
		(start 105.384743 83.965)
		(end 105.380983 83.998378)
		(width 0.11)
		(layer "F.Cu")
		(net 433)
	)
	(segment
		(start 105.352018 84.658523)
		(end 105.328267 84.682274)
		(width 0.11)
		(layer "F.Cu")
		(net 433)
	)
	(segment
		(start 104.941477 84.147725)
		(end 104.917726 84.171476)
		(width 0.11)
		(layer "F.Cu")
		(net 433)
	)
	(segment
		(start 105.380983 83.398378)
		(end 105.369889 83.430082)
		(width 0.11)
		(layer "F.Cu")
		(net 433)
	)
	(segment
		(start 105.035 84.115)
		(end 105.001622 84.11876)
		(width 0.11)
		(layer "F.Cu")
		(net 433)
	)
	(segment
		(start 104.899855 82.530082)
		(end 104.917726 82.558523)
		(width 0.11)
		(layer "F.Cu")
		(net 433)
	)
	(segment
		(start 104.888761 83.098378)
		(end 104.899855 83.130082)
		(width 0.11)
		(layer "F.Cu")
		(net 433)
	)
	(segment
		(start 105.380983 82.131621)
		(end 105.384743 82.165)
		(width 0.11)
		(layer "F.Cu")
		(net 433)
	)
	(segment
		(start 105.299826 83.829854)
		(end 105.328267 83.847725)
		(width 0.11)
		(layer "F.Cu")
		(net 433)
	)
	(segment
		(start 105.384743 82.765)
		(end 105.380983 82.798378)
		(width 0.11)
		(layer "F.Cu")
		(net 433)
	)
	(segment
		(start 105.234743 82.315)
		(end 105.035 82.315)
		(width 0.11)
		(layer "F.Cu")
		(net 433)
	)
	(segment
		(start 105.001622 84.71876)
		(end 104.969918 84.729854)
		(width 0.11)
		(layer "F.Cu")
		(net 433)
	)
	(segment
		(start 104.885 81.641)
		(end 104.885 81.865)
		(width 0.11)
		(layer "F.Cu")
		(net 433)
	)
	(segment
		(start 104.899855 81.930082)
		(end 104.917726 81.958523)
		(width 0.11)
		(layer "F.Cu")
		(net 433)
	)
	(segment
		(start 104.941477 83.782274)
		(end 104.969918 83.800145)
		(width 0.11)
		(layer "F.Cu")
		(net 433)
	)
	(segment
		(start 105.234743 82.015)
		(end 105.268122 82.01876)
		(width 0.11)
		(layer "F.Cu")
		(net 433)
	)
	(segment
		(start 105.369889 84.030082)
		(end 105.352018 84.058523)
		(width 0.11)
		(layer "F.Cu")
		(net 433)
	)
	(segment
		(start 104.899855 82.399917)
		(end 104.888761 82.431621)
		(width 0.11)
		(layer "F.Cu")
		(net 433)
	)
	(segment
		(start 104.917726 82.371476)
		(end 104.899855 82.399917)
		(width 0.11)
		(layer "F.Cu")
		(net 433)
	)
	(segment
		(start 104.941477 83.182274)
		(end 104.969918 83.200145)
		(width 0.11)
		(layer "F.Cu")
		(net 433)
	)
	(segment
		(start 105.299826 84.429854)
		(end 105.328267 84.447725)
		(width 0.11)
		(layer "F.Cu")
		(net 433)
	)
	(segment
		(start 104.888761 83.698378)
		(end 104.899855 83.730082)
		(width 0.11)
		(layer "F.Cu")
		(net 433)
	)
	(segment
		(start 105.380983 84.598378)
		(end 105.369889 84.630082)
		(width 0.11)
		(layer "F.Cu")
		(net 433)
	)
	(segment
		(start 104.941477 82.347725)
		(end 104.917726 82.371476)
		(width 0.11)
		(layer "F.Cu")
		(net 433)
	)
	(segment
		(start 105.035 82.915)
		(end 105.001622 82.91876)
		(width 0.11)
		(layer "F.Cu")
		(net 433)
	)
	(segment
		(start 104.917726 83.571476)
		(end 104.899855 83.599917)
		(width 0.11)
		(layer "F.Cu")
		(net 433)
	)
	(segment
		(start 105.328267 82.282274)
		(end 105.299826 82.300145)
		(width 0.11)
		(layer "F.Cu")
		(net 433)
	)
	(segment
		(start 105.299826 82.300145)
		(end 105.268122 82.311239)
		(width 0.11)
		(layer "F.Cu")
		(net 433)
	)
	(segment
		(start 104.917726 81.958523)
		(end 104.941477 81.982274)
		(width 0.11)
		(layer "F.Cu")
		(net 433)
	)
	(segment
		(start 104.941477 84.382274)
		(end 104.969918 84.400145)
		(width 0.11)
		(layer "F.Cu")
		(net 433)
	)
	(segment
		(start 105.035 84.715)
		(end 105.001622 84.71876)
		(width 0.11)
		(layer "F.Cu")
		(net 433)
	)
	(segment
		(start 105.234743 83.515)
		(end 105.035 83.515)
		(width 0.11)
		(layer "F.Cu")
		(net 433)
	)
	(segment
		(start 105.268122 84.41876)
		(end 105.299826 84.429854)
		(width 0.11)
		(layer "F.Cu")
		(net 433)
	)
	(segment
		(start 104.969918 83.529854)
		(end 104.941477 83.547725)
		(width 0.11)
		(layer "F.Cu")
		(net 433)
	)
	(segment
		(start 105.691 80.835)
		(end 104.885 81.641)
		(width 0.11)
		(layer "F.Cu")
		(net 433)
	)
	(segment
		(start 102.71 91.605564)
		(end 102.71 92.657851)
		(width 0.11)
		(layer "F.Cu")
		(net 433)
	)
	(segment
		(start 105.001622 83.211239)
		(end 105.035 83.215)
		(width 0.11)
		(layer "F.Cu")
		(net 433)
	)
	(segment
		(start 105.234743 83.815)
		(end 105.268122 83.81876)
		(width 0.11)
		(layer "F.Cu")
		(net 433)
	)
	(segment
		(start 105.299826 84.100145)
		(end 105.268122 84.111239)
		(width 0.11)
		(layer "F.Cu")
		(net 433)
	)
	(segment
		(start 105.328267 83.847725)
		(end 105.352018 83.871476)
		(width 0.11)
		(layer "F.Cu")
		(net 433)
	)
	(segment
		(start 105.001622 82.31876)
		(end 104.969918 82.329854)
		(width 0.11)
		(layer "F.Cu")
		(net 433)
	)
	(segment
		(start 105.384743 83.365)
		(end 105.380983 83.398378)
		(width 0.11)
		(layer "F.Cu")
		(net 433)
	)
	(segment
		(start 105.035 83.515)
		(end 105.001622 83.51876)
		(width 0.11)
		(layer "F.Cu")
		(net 433)
	)
	(segment
		(start 104.969918 84.729854)
		(end 104.941477 84.747725)
		(width 0.11)
		(layer "F.Cu")
		(net 433)
	)
	(segment
		(start 105.352018 82.858523)
		(end 105.328267 82.882274)
		(width 0.11)
		(layer "F.Cu")
		(net 433)
	)
	(segment
		(start 104.969918 84.129854)
		(end 104.941477 84.147725)
		(width 0.11)
		(layer "F.Cu")
		(net 433)
	)
	(segment
		(start 105.352018 82.671476)
		(end 105.369889 82.699917)
		(width 0.11)
		(layer "F.Cu")
		(net 433)
	)
	(segment
		(start 105.369889 84.630082)
		(end 105.352018 84.658523)
		(width 0.11)
		(layer "F.Cu")
		(net 433)
	)
	(segment
		(start 105.268122 83.511239)
		(end 105.234743 83.515)
		(width 0.11)
		(layer "F.Cu")
		(net 433)
	)
	(segment
		(start 105.001622 82.011239)
		(end 105.035 82.015)
		(width 0.11)
		(layer "F.Cu")
		(net 433)
	)
	(segment
		(start 105.234743 84.115)
		(end 105.035 84.115)
		(width 0.11)
		(layer "F.Cu")
		(net 433)
	)
	(segment
		(start 104.941477 81.982274)
		(end 104.969918 82.000145)
		(width 0.11)
		(layer "F.Cu")
		(net 433)
	)
	(segment
		(start 105.380983 83.998378)
		(end 105.369889 84.030082)
		(width 0.11)
		(layer "F.Cu")
		(net 433)
	)
	(segment
		(start 105.001622 84.411239)
		(end 105.035 84.415)
		(width 0.11)
		(layer "F.Cu")
		(net 433)
	)
	(segment
		(start 104.917726 82.971476)
		(end 104.899855 82.999917)
		(width 0.11)
		(layer "F.Cu")
		(net 433)
	)
	(segment
		(start 104.899855 83.130082)
		(end 104.917726 83.158523)
		(width 0.11)
		(layer "F.Cu")
		(net 433)
	)
	(segment
		(start 105.035 82.615)
		(end 105.234743 82.615)
		(width 0.11)
		(layer "F.Cu")
		(net 433)
	)
	(segment
		(start 104.917726 83.758523)
		(end 104.941477 83.782274)
		(width 0.11)
		(layer "F.Cu")
		(net 433)
	)
	(segment
		(start 105.380983 83.931621)
		(end 105.384743 83.965)
		(width 0.11)
		(layer "F.Cu")
		(net 433)
	)
	(segment
		(start 104.885 82.465)
		(end 104.888761 82.498378)
		(width 0.11)
		(layer "F.Cu")
		(net 433)
	)
	(segment
		(start 105.268122 83.21876)
		(end 105.299826 83.229854)
		(width 0.11)
		(layer "F.Cu")
		(net 433)
	)
	(segment
		(start 105.369889 82.230082)
		(end 105.352018 82.258523)
		(width 0.11)
		(layer "F.Cu")
		(net 433)
	)
	(segment
		(start 105.328267 84.447725)
		(end 105.352018 84.471476)
		(width 0.11)
		(layer "F.Cu")
		(net 433)
	)
	(segment
		(start 105.369889 82.099917)
		(end 105.380983 82.131621)
		(width 0.11)
		(layer "F.Cu")
		(net 433)
	)
	(segment
		(start 105.001622 83.51876)
		(end 104.969918 83.529854)
		(width 0.11)
		(layer "F.Cu")
		(net 433)
	)
	(segment
		(start 104.941477 83.547725)
		(end 104.917726 83.571476)
		(width 0.11)
		(layer "F.Cu")
		(net 433)
	)
	(segment
		(start 105.268122 82.61876)
		(end 105.299826 82.629854)
		(width 0.11)
		(layer "F.Cu")
		(net 433)
	)
	(segment
		(start 104.917726 82.558523)
		(end 104.941477 82.582274)
		(width 0.11)
		(layer "F.Cu")
		(net 433)
	)
	(segment
		(start 104.969918 82.329854)
		(end 104.941477 82.347725)
		(width 0.11)
		(layer "F.Cu")
		(net 433)
	)
	(segment
		(start 104.888761 82.431621)
		(end 104.885 82.465)
		(width 0.11)
		(layer "F.Cu")
		(net 433)
	)
	(segment
		(start 105.001622 82.611239)
		(end 105.035 82.615)
		(width 0.11)
		(layer "F.Cu")
		(net 433)
	)
	(segment
		(start 105.384743 82.165)
		(end 105.380983 82.198378)
		(width 0.11)
		(layer "F.Cu")
		(net 433)
	)
	(segment
		(start 105.234743 82.615)
		(end 105.268122 82.61876)
		(width 0.11)
		(layer "F.Cu")
		(net 433)
	)
	(segment
		(start 104.888761 83.631621)
		(end 104.885 83.665)
		(width 0.11)
		(layer "F.Cu")
		(net 433)
	)
	(segment
		(start 105.035 84.415)
		(end 105.234743 84.415)
		(width 0.11)
		(layer "F.Cu")
		(net 433)
	)
	(segment
		(start 104.899855 82.999917)
		(end 104.888761 83.031621)
		(width 0.11)
		(layer "F.Cu")
		(net 433)
	)
	(segment
		(start 105.352018 83.458523)
		(end 105.328267 83.482274)
		(width 0.11)
		(layer "F.Cu")
		(net 433)
	)
	(segment
		(start 104.899855 83.730082)
		(end 104.917726 83.758523)
		(width 0.11)
		(layer "F.Cu")
		(net 433)
	)
	(segment
		(start 105.328267 83.482274)
		(end 105.299826 83.500145)
		(width 0.11)
		(layer "F.Cu")
		(net 433)
	)
	(segment
		(start 105.234743 84.715)
		(end 105.035 84.715)
		(width 0.11)
		(layer "F.Cu")
		(net 433)
	)
	(segment
		(start 105.380983 82.731621)
		(end 105.384743 82.765)
		(width 0.11)
		(layer "F.Cu")
		(net 433)
	)
	(segment
		(start 104.899855 84.330082)
		(end 104.917726 84.358523)
		(width 0.11)
		(layer "F.Cu")
		(net 433)
	)
	(segment
		(start 105.369889 82.830082)
		(end 105.352018 82.858523)
		(width 0.11)
		(layer "F.Cu")
		(net 433)
	)
	(segment
		(start 105.352018 83.871476)
		(end 105.369889 83.899917)
		(width 0.11)
		(layer "F.Cu")
		(net 433)
	)
	(segment
		(start 105.268122 83.81876)
		(end 105.299826 83.829854)
		(width 0.11)
		(layer "F.Cu")
		(net 433)
	)
	(segment
		(start 104.888761 84.831621)
		(end 104.885 84.865)
		(width 0.11)
		(layer "F.Cu")
		(net 433)
	)
	(segment
		(start 105.328267 84.682274)
		(end 105.299826 84.700145)
		(width 0.11)
		(layer "F.Cu")
		(net 433)
	)
	(segment
		(start 104.917726 84.171476)
		(end 104.899855 84.199917)
		(width 0.11)
		(layer "F.Cu")
		(net 433)
	)
	(segment
		(start 105.035 82.015)
		(end 105.234743 82.015)
		(width 0.11)
		(layer "F.Cu")
		(net 433)
	)
	(segment
		(start 105.234743 84.415)
		(end 105.268122 84.41876)
		(width 0.11)
		(layer "F.Cu")
		(net 433)
	)
	(segment
		(start 105.299826 83.229854)
		(end 105.328267 83.247725)
		(width 0.11)
		(layer "F.Cu")
		(net 433)
	)
	(segment
		(start 105.268122 82.911239)
		(end 105.234743 82.915)
		(width 0.11)
		(layer "F.Cu")
		(net 433)
	)
	(segment
		(start 105.035 83.815)
		(end 105.234743 83.815)
		(width 0.11)
		(layer "F.Cu")
		(net 433)
	)
	(segment
		(start 104.969918 84.400145)
		(end 105.001622 84.411239)
		(width 0.11)
		(layer "F.Cu")
		(net 433)
	)
	(segment
		(start 104.941477 84.747725)
		(end 104.917726 84.771476)
		(width 0.11)
		(layer "F.Cu")
		(net 433)
	)
	(segment
		(start 104.888761 82.498378)
		(end 104.899855 82.530082)
		(width 0.11)
		(layer "F.Cu")
		(net 433)
	)
	(segment
		(start 105.380983 82.798378)
		(end 105.369889 82.830082)
		(width 0.11)
		(layer "F.Cu")
		(net 433)
	)
	(segment
		(start 105.369889 82.699917)
		(end 105.380983 82.731621)
		(width 0.11)
		(layer "F.Cu")
		(net 433)
	)
	(segment
		(start 102.71 92.657851)
		(end 102.85 92.797851)
		(width 0.11)
		(layer "F.Cu")
		(net 433)
	)
	(segment
		(start 105.328267 82.882274)
		(end 105.299826 82.900145)
		(width 0.11)
		(layer "F.Cu")
		(net 433)
	)
	(segment
		(start 104.969918 82.600145)
		(end 105.001622 82.611239)
		(width 0.11)
		(layer "F.Cu")
		(net 433)
	)
	(segment
		(start 104.885 84.265)
		(end 104.888761 84.298378)
		(width 0.11)
		(layer "F.Cu")
		(net 433)
	)
	(segment
		(start 105.268122 84.711239)
		(end 105.234743 84.715)
		(width 0.11)
		(layer "F.Cu")
		(net 433)
	)
	(segment
		(start 105.380983 82.198378)
		(end 105.369889 82.230082)
		(width 0.11)
		(layer "F.Cu")
		(net 433)
	)
	(segment
		(start 105.369889 83.899917)
		(end 105.380983 83.931621)
		(width 0.11)
		(layer "F.Cu")
		(net 433)
	)
	(segment
		(start 105.328267 83.247725)
		(end 105.352018 83.271476)
		(width 0.11)
		(layer "F.Cu")
		(net 433)
	)
	(segment
		(start 104.917726 84.358523)
		(end 104.941477 84.382274)
		(width 0.11)
		(layer "F.Cu")
		(net 433)
	)
	(segment
		(start 105.352018 83.271476)
		(end 105.369889 83.299917)
		(width 0.11)
		(layer "F.Cu")
		(net 433)
	)
	(segment
		(start 105.369889 83.430082)
		(end 105.352018 83.458523)
		(width 0.11)
		(layer "F.Cu")
		(net 433)
	)
	(segment
		(start 105.352018 84.058523)
		(end 105.328267 84.082274)
		(width 0.11)
		(layer "F.Cu")
		(net 433)
	)
	(segment
		(start 105.299826 82.900145)
		(end 105.268122 82.911239)
		(width 0.11)
		(layer "F.Cu")
		(net 433)
	)
	(segment
		(start 105.352018 84.471476)
		(end 105.369889 84.499917)
		(width 0.11)
		(layer "F.Cu")
		(net 433)
	)
	(segment
		(start 105.352018 82.071476)
		(end 105.369889 82.099917)
		(width 0.11)
		(layer "F.Cu")
		(net 433)
	)
	(segment
		(start 105.001622 82.91876)
		(end 104.969918 82.929854)
		(width 0.11)
		(layer "F.Cu")
		(net 433)
	)
	(segment
		(start 105.328267 82.047725)
		(end 105.352018 82.071476)
		(width 0.11)
		(layer "F.Cu")
		(net 433)
	)
	(segment
		(start 105.299826 84.700145)
		(end 105.268122 84.711239)
		(width 0.11)
		(layer "F.Cu")
		(net 433)
	)
	(segment
		(start 105.001622 84.11876)
		(end 104.969918 84.129854)
		(width 0.11)
		(layer "F.Cu")
		(net 433)
	)
	(segment
		(start 107.060514 85.459164)
		(end 107.119469 85.496208)
		(width 0.11)
		(layer "F.Cu")
		(net 434)
	)
	(segment
		(start 108.220282 86.616106)
		(end 108.197032 86.624242)
		(width 0.11)
		(layer "F.Cu")
		(net 434)
	)
	(segment
		(start 108.172554 86.627)
		(end 107.254377 86.627)
		(width 0.11)
		(layer "F.Cu")
		(net 434)
	)
	(segment
		(start 103.99 92.657851)
		(end 103.85 92.797851)
		(width 0.11)
		(layer "F.Cu")
		(net 434)
	)
	(segment
		(start 107.011281 85.864068)
		(end 106.974237 85.923023)
		(width 0.11)
		(layer "F.Cu")
		(net 434)
	)
	(segment
		(start 107.185188 85.754795)
		(end 107.119469 85.777791)
		(width 0.11)
		(layer "F.Cu")
		(net 434)
	)
	(segment
		(start 107.571583 84.843001)
		(end 107.550727 84.856106)
		(width 0.11)
		(layer "F.Cu")
		(net 434)
	)
	(segment
		(start 107.503 84.867)
		(end 107.254377 84.867)
		(width 0.11)
		(layer "F.Cu")
		(net 434)
	)
	(segment
		(start 107.254377 86.407)
		(end 108.172554 86.407)
		(width 0.11)
		(layer "F.Cu")
		(net 434)
	)
	(segment
		(start 107.060514 87.219164)
		(end 107.119469 87.256208)
		(width 0.11)
		(layer "F.Cu")
		(net 434)
	)
	(segment
		(start 107.119469 84.897791)
		(end 107.060514 84.934835)
		(width 0.11)
		(layer "F.Cu")
		(net 434)
	)
	(segment
		(start 108.220282 85.736106)
		(end 108.197032 85.744242)
		(width 0.11)
		(layer "F.Cu")
		(net 434)
	)
	(segment
		(start 107.589001 84.825583)
		(end 107.571583 84.843001)
		(width 0.11)
		(layer "F.Cu")
		(net 434)
	)
	(segment
		(start 106.943446 85.177931)
		(end 106.943446 85.216068)
		(width 0.11)
		(layer "F.Cu")
		(net 434)
	)
	(segment
		(start 106.951241 86.165257)
		(end 106.974237 86.230976)
		(width 0.11)
		(layer "F.Cu")
		(net 434)
	)
	(segment
		(start 108.279797 85.661477)
		(end 108.271661 85.684727)
		(width 0.11)
		(layer "F.Cu")
		(net 434)
	)
	(segment
		(start 106.707 83.375)
		(end 107.613 84.281)
		(width 0.11)
		(layer "F.Cu")
		(net 434)
	)
	(segment
		(start 106.951241 85.285257)
		(end 106.974237 85.350976)
		(width 0.11)
		(layer "F.Cu")
		(net 434)
	)
	(segment
		(start 108.220282 86.417893)
		(end 108.241138 86.430998)
		(width 0.11)
		(layer "F.Cu")
		(net 434)
	)
	(segment
		(start 107.602106 87.349272)
		(end 107.610242 87.372522)
		(width 0.11)
		(layer "F.Cu")
		(net 434)
	)
	(segment
		(start 107.254377 86.627)
		(end 107.185188 86.634795)
		(width 0.11)
		(layer "F.Cu")
		(net 434)
	)
	(segment
		(start 108.271661 85.684727)
		(end 108.258556 85.705583)
		(width 0.11)
		(layer "F.Cu")
		(net 434)
	)
	(segment
		(start 107.610242 87.372522)
		(end 107.613 87.397)
		(width 0.11)
		(layer "F.Cu")
		(net 434)
	)
	(segment
		(start 107.503 87.287)
		(end 107.527477 87.289757)
		(width 0.11)
		(layer "F.Cu")
		(net 434)
	)
	(segment
		(start 107.119469 86.657791)
		(end 107.060514 86.694835)
		(width 0.11)
		(layer "F.Cu")
		(net 434)
	)
	(segment
		(start 108.282554 86.517)
		(end 108.279797 86.541477)
		(width 0.11)
		(layer "F.Cu")
		(net 434)
	)
	(segment
		(start 108.258556 86.585583)
		(end 108.241138 86.603001)
		(width 0.11)
		(layer "F.Cu")
		(net 434)
	)
	(segment
		(start 107.060514 84.934835)
		(end 107.011281 84.984068)
		(width 0.11)
		(layer "F.Cu")
		(net 434)
	)
	(segment
		(start 108.172554 85.527)
		(end 108.197032 85.529757)
		(width 0.11)
		(layer "F.Cu")
		(net 434)
	)
	(segment
		(start 107.254377 85.527)
		(end 108.172554 85.527)
		(width 0.11)
		(layer "F.Cu")
		(net 434)
	)
	(segment
		(start 106.974237 85.923023)
		(end 106.951241 85.988742)
		(width 0.11)
		(layer "F.Cu")
		(net 434)
	)
	(segment
		(start 107.550727 84.856106)
		(end 107.527477 84.864242)
		(width 0.11)
		(layer "F.Cu")
		(net 434)
	)
	(segment
		(start 107.613 84.757)
		(end 107.610242 84.781477)
		(width 0.11)
		(layer "F.Cu")
		(net 434)
	)
	(segment
		(start 107.119469 87.256208)
		(end 107.185188 87.279204)
		(width 0.11)
		(layer "F.Cu")
		(net 434)
	)
	(segment
		(start 106.951241 85.988742)
		(end 106.943446 86.057931)
		(width 0.11)
		(layer "F.Cu")
		(net 434)
	)
	(segment
		(start 107.254377 84.867)
		(end 107.185188 84.874795)
		(width 0.11)
		(layer "F.Cu")
		(net 434)
	)
	(segment
		(start 108.172554 86.407)
		(end 108.197032 86.409757)
		(width 0.11)
		(layer "F.Cu")
		(net 434)
	)
	(segment
		(start 106.951241 85.108742)
		(end 106.943446 85.177931)
		(width 0.11)
		(layer "F.Cu")
		(net 434)
	)
	(segment
		(start 106.943446 86.937931)
		(end 106.943446 86.976068)
		(width 0.11)
		(layer "F.Cu")
		(net 434)
	)
	(segment
		(start 107.185188 87.279204)
		(end 107.254377 87.287)
		(width 0.11)
		(layer "F.Cu")
		(net 434)
	)
	(segment
		(start 108.271661 85.589272)
		(end 108.279797 85.612522)
		(width 0.11)
		(layer "F.Cu")
		(net 434)
	)
	(segment
		(start 107.185188 85.519204)
		(end 107.254377 85.527)
		(width 0.11)
		(layer "F.Cu")
		(net 434)
	)
	(segment
		(start 108.220282 85.537893)
		(end 108.241138 85.550998)
		(width 0.11)
		(layer "F.Cu")
		(net 434)
	)
	(segment
		(start 106.943446 86.057931)
		(end 106.943446 86.096068)
		(width 0.11)
		(layer "F.Cu")
		(net 434)
	)
	(segment
		(start 106.974237 86.230976)
		(end 107.011281 86.289931)
		(width 0.11)
		(layer "F.Cu")
		(net 434)
	)
	(segment
		(start 107.613 84.281)
		(end 107.613 84.757)
		(width 0.11)
		(layer "F.Cu")
		(net 434)
	)
	(segment
		(start 108.241138 85.723001)
		(end 108.220282 85.736106)
		(width 0.11)
		(layer "F.Cu")
		(net 434)
	)
	(segment
		(start 107.527477 87.289757)
		(end 107.550727 87.297893)
		(width 0.11)
		(layer "F.Cu")
		(net 434)
	)
	(segment
		(start 108.258556 86.448416)
		(end 108.271661 86.469272)
		(width 0.11)
		(layer "F.Cu")
		(net 434)
	)
	(segment
		(start 106.943446 86.096068)
		(end 106.951241 86.165257)
		(width 0.11)
		(layer "F.Cu")
		(net 434)
	)
	(segment
		(start 107.610242 84.781477)
		(end 107.602106 84.804727)
		(width 0.11)
		(layer "F.Cu")
		(net 434)
	)
	(segment
		(start 103.99 91.774436)
		(end 103.99 92.657851)
		(width 0.11)
		(layer "F.Cu")
		(net 434)
	)
	(segment
		(start 108.279797 86.492522)
		(end 108.282554 86.517)
		(width 0.11)
		(layer "F.Cu")
		(net 434)
	)
	(segment
		(start 107.011281 85.409931)
		(end 107.060514 85.459164)
		(width 0.11)
		(layer "F.Cu")
		(net 434)
	)
	(segment
		(start 107.254377 87.287)
		(end 107.503 87.287)
		(width 0.11)
		(layer "F.Cu")
		(net 434)
	)
	(segment
		(start 108.197032 86.409757)
		(end 108.220282 86.417893)
		(width 0.11)
		(layer "F.Cu")
		(net 434)
	)
	(segment
		(start 108.279797 86.541477)
		(end 108.271661 86.564727)
		(width 0.11)
		(layer "F.Cu")
		(net 434)
	)
	(segment
		(start 108.241138 85.550998)
		(end 108.258556 85.568416)
		(width 0.11)
		(layer "F.Cu")
		(net 434)
	)
	(segment
		(start 106.974237 86.803023)
		(end 106.951241 86.868742)
		(width 0.11)
		(layer "F.Cu")
		(net 434)
	)
	(segment
		(start 107.119469 86.376208)
		(end 107.185188 86.399204)
		(width 0.11)
		(layer "F.Cu")
		(net 434)
	)
	(segment
		(start 107.119469 85.777791)
		(end 107.060514 85.814835)
		(width 0.11)
		(layer "F.Cu")
		(net 434)
	)
	(segment
		(start 107.185188 86.634795)
		(end 107.119469 86.657791)
		(width 0.11)
		(layer "F.Cu")
		(net 434)
	)
	(segment
		(start 107.589001 87.328416)
		(end 107.602106 87.349272)
		(width 0.11)
		(layer "F.Cu")
		(net 434)
	)
	(segment
		(start 107.613 88.151436)
		(end 103.99 91.774436)
		(width 0.11)
		(layer "F.Cu")
		(net 434)
	)
	(segment
		(start 108.258556 85.568416)
		(end 108.271661 85.589272)
		(width 0.11)
		(layer "F.Cu")
		(net 434)
	)
	(segment
		(start 106.951241 86.868742)
		(end 106.943446 86.937931)
		(width 0.11)
		(layer "F.Cu")
		(net 434)
	)
	(segment
		(start 108.241138 86.430998)
		(end 108.258556 86.448416)
		(width 0.11)
		(layer "F.Cu")
		(net 434)
	)
	(segment
		(start 107.613 87.397)
		(end 107.613 88.151436)
		(width 0.11)
		(layer "F.Cu")
		(net 434)
	)
	(segment
		(start 107.602106 84.804727)
		(end 107.589001 84.825583)
		(width 0.11)
		(layer "F.Cu")
		(net 434)
	)
	(segment
		(start 106.974237 87.110976)
		(end 107.011281 87.169931)
		(width 0.11)
		(layer "F.Cu")
		(net 434)
	)
	(segment
		(start 107.185188 84.874795)
		(end 107.119469 84.897791)
		(width 0.11)
		(layer "F.Cu")
		(net 434)
	)
	(segment
		(start 107.011281 86.289931)
		(end 107.060514 86.339164)
		(width 0.11)
		(layer "F.Cu")
		(net 434)
	)
	(segment
		(start 108.279797 85.612522)
		(end 108.282554 85.637)
		(width 0.11)
		(layer "F.Cu")
		(net 434)
	)
	(segment
		(start 107.254377 85.747)
		(end 107.185188 85.754795)
		(width 0.11)
		(layer "F.Cu")
		(net 434)
	)
	(segment
		(start 106.943446 86.976068)
		(end 106.951241 87.045257)
		(width 0.11)
		(layer "F.Cu")
		(net 434)
	)
	(segment
		(start 108.172554 85.747)
		(end 107.254377 85.747)
		(width 0.11)
		(layer "F.Cu")
		(net 434)
	)
	(segment
		(start 108.197032 85.744242)
		(end 108.172554 85.747)
		(width 0.11)
		(layer "F.Cu")
		(net 434)
	)
	(segment
		(start 107.011281 86.744068)
		(end 106.974237 86.803023)
		(width 0.11)
		(layer "F.Cu")
		(net 434)
	)
	(segment
		(start 106.974237 85.350976)
		(end 107.011281 85.409931)
		(width 0.11)
		(layer "F.Cu")
		(net 434)
	)
	(segment
		(start 107.060514 85.814835)
		(end 107.011281 85.864068)
		(width 0.11)
		(layer "F.Cu")
		(net 434)
	)
	(segment
		(start 108.258556 85.705583)
		(end 108.241138 85.723001)
		(width 0.11)
		(layer "F.Cu")
		(net 434)
	)
	(segment
		(start 107.060514 86.694835)
		(end 107.011281 86.744068)
		(width 0.11)
		(layer "F.Cu")
		(net 434)
	)
	(segment
		(start 107.011281 84.984068)
		(end 106.974237 85.043023)
		(width 0.11)
		(layer "F.Cu")
		(net 434)
	)
	(segment
		(start 108.282554 85.637)
		(end 108.279797 85.661477)
		(width 0.11)
		(layer "F.Cu")
		(net 434)
	)
	(segment
		(start 108.241138 86.603001)
		(end 108.220282 86.616106)
		(width 0.11)
		(layer "F.Cu")
		(net 434)
	)
	(segment
		(start 106.943446 85.216068)
		(end 106.951241 85.285257)
		(width 0.11)
		(layer "F.Cu")
		(net 434)
	)
	(segment
		(start 106.974237 85.043023)
		(end 106.951241 85.108742)
		(width 0.11)
		(layer "F.Cu")
		(net 434)
	)
	(segment
		(start 107.119469 85.496208)
		(end 107.185188 85.519204)
		(width 0.11)
		(layer "F.Cu")
		(net 434)
	)
	(segment
		(start 107.550727 87.297893)
		(end 107.571583 87.310998)
		(width 0.11)
		(layer "F.Cu")
		(net 434)
	)
	(segment
		(start 106.951241 87.045257)
		(end 106.974237 87.110976)
		(width 0.11)
		(layer "F.Cu")
		(net 434)
	)
	(segment
		(start 107.571583 87.310998)
		(end 107.589001 87.328416)
		(width 0.11)
		(layer "F.Cu")
		(net 434)
	)
	(segment
		(start 108.271661 86.564727)
		(end 108.258556 86.585583)
		(width 0.11)
		(layer "F.Cu")
		(net 434)
	)
	(segment
		(start 107.527477 84.864242)
		(end 107.503 84.867)
		(width 0.11)
		(layer "F.Cu")
		(net 434)
	)
	(segment
		(start 108.197032 85.529757)
		(end 108.220282 85.537893)
		(width 0.11)
		(layer "F.Cu")
		(net 434)
	)
	(segment
		(start 107.060514 86.339164)
		(end 107.119469 86.376208)
		(width 0.11)
		(layer "F.Cu")
		(net 434)
	)
	(segment
		(start 108.197032 86.624242)
		(end 108.172554 86.627)
		(width 0.11)
		(layer "F.Cu")
		(net 434)
	)
	(segment
		(start 107.011281 87.169931)
		(end 107.060514 87.219164)
		(width 0.11)
		(layer "F.Cu")
		(net 434)
	)
	(segment
		(start 107.185188 86.399204)
		(end 107.254377 86.407)
		(width 0.11)
		(layer "F.Cu")
		(net 434)
	)
	(segment
		(start 108.271661 86.469272)
		(end 108.279797 86.492522)
		(width 0.11)
		(layer "F.Cu")
		(net 434)
	)
	(segment
		(start 107.248968 85.304242)
		(end 107.273446 85.307)
		(width 0.11)
		(layer "F.Cu")
		(net 435)
	)
	(segment
		(start 107.163446 86.077)
		(end 107.166203 86.101477)
		(width 0.11)
		(layer "F.Cu")
		(net 435)
	)
	(segment
		(start 107.225718 85.097893)
		(end 107.204862 85.110998)
		(width 0.11)
		(layer "F.Cu")
		(net 435)
	)
	(segment
		(start 107.825204 87.308742)
		(end 107.833 87.377931)
		(width 0.11)
		(layer "F.Cu")
		(net 435)
	)
	(segment
		(start 107.273446 86.847)
		(end 107.248968 86.849757)
		(width 0.11)
		(layer "F.Cu")
		(net 435)
	)
	(segment
		(start 107.833 84.776068)
		(end 107.825204 84.845257)
		(width 0.11)
		(layer "F.Cu")
		(net 435)
	)
	(segment
		(start 107.187444 87.025583)
		(end 107.204862 87.043001)
		(width 0.11)
		(layer "F.Cu")
		(net 435)
	)
	(segment
		(start 107.174339 86.029272)
		(end 107.166203 86.052522)
		(width 0.11)
		(layer "F.Cu")
		(net 435)
	)
	(segment
		(start 107.656976 85.056208)
		(end 107.591257 85.079204)
		(width 0.11)
		(layer "F.Cu")
		(net 435)
	)
	(segment
		(start 108.191623 86.847)
		(end 107.273446 86.847)
		(width 0.11)
		(layer "F.Cu")
		(net 435)
	)
	(segment
		(start 107.225718 85.977893)
		(end 107.204862 85.990998)
		(width 0.11)
		(layer "F.Cu")
		(net 435)
	)
	(segment
		(start 107.174339 86.909272)
		(end 107.166203 86.932522)
		(width 0.11)
		(layer "F.Cu")
		(net 435)
	)
	(segment
		(start 107.204862 85.110998)
		(end 107.187444 85.128416)
		(width 0.11)
		(layer "F.Cu")
		(net 435)
	)
	(segment
		(start 107.591257 85.079204)
		(end 107.522068 85.087)
		(width 0.11)
		(layer "F.Cu")
		(net 435)
	)
	(segment
		(start 108.502554 85.656068)
		(end 108.494759 85.725257)
		(width 0.11)
		(layer "F.Cu")
		(net 435)
	)
	(segment
		(start 107.765164 87.184068)
		(end 107.802208 87.243023)
		(width 0.11)
		(layer "F.Cu")
		(net 435)
	)
	(segment
		(start 107.248968 86.184242)
		(end 107.273446 86.187)
		(width 0.11)
		(layer "F.Cu")
		(net 435)
	)
	(segment
		(start 107.765164 84.969931)
		(end 107.715931 85.019164)
		(width 0.11)
		(layer "F.Cu")
		(net 435)
	)
	(segment
		(start 108.434719 86.304068)
		(end 108.471763 86.363023)
		(width 0.11)
		(layer "F.Cu")
		(net 435)
	)
	(segment
		(start 107.166203 85.221477)
		(end 107.174339 85.244727)
		(width 0.11)
		(layer "F.Cu")
		(net 435)
	)
	(segment
		(start 107.174339 87.004727)
		(end 107.187444 87.025583)
		(width 0.11)
		(layer "F.Cu")
		(net 435)
	)
	(segment
		(start 108.326531 86.217791)
		(end 108.385486 86.254835)
		(width 0.11)
		(layer "F.Cu")
		(net 435)
	)
	(segment
		(start 108.434719 86.729931)
		(end 108.385486 86.779164)
		(width 0.11)
		(layer "F.Cu")
		(net 435)
	)
	(segment
		(start 108.739 83.375)
		(end 107.833 84.281)
		(width 0.11)
		(layer "F.Cu")
		(net 435)
	)
	(segment
		(start 108.502554 85.617931)
		(end 108.502554 85.656068)
		(width 0.11)
		(layer "F.Cu")
		(net 435)
	)
	(segment
		(start 107.273446 87.067)
		(end 107.522068 87.067)
		(width 0.11)
		(layer "F.Cu")
		(net 435)
	)
	(segment
		(start 107.591257 87.074795)
		(end 107.656976 87.097791)
		(width 0.11)
		(layer "F.Cu")
		(net 435)
	)
	(segment
		(start 107.187444 85.265583)
		(end 107.204862 85.283001)
		(width 0.11)
		(layer "F.Cu")
		(net 435)
	)
	(segment
		(start 107.715931 87.134835)
		(end 107.765164 87.184068)
		(width 0.11)
		(layer "F.Cu")
		(net 435)
	)
	(segment
		(start 108.494759 86.428742)
		(end 108.502554 86.497931)
		(width 0.11)
		(layer "F.Cu")
		(net 435)
	)
	(segment
		(start 107.225718 86.857893)
		(end 107.204862 86.870998)
		(width 0.11)
		(layer "F.Cu")
		(net 435)
	)
	(segment
		(start 108.260812 86.194795)
		(end 108.326531 86.217791)
		(width 0.11)
		(layer "F.Cu")
		(net 435)
	)
	(segment
		(start 107.802208 84.910976)
		(end 107.765164 84.969931)
		(width 0.11)
		(layer "F.Cu")
		(net 435)
	)
	(segment
		(start 108.385486 85.374835)
		(end 108.434719 85.424068)
		(width 0.11)
		(layer "F.Cu")
		(net 435)
	)
	(segment
		(start 108.260812 86.839204)
		(end 108.191623 86.847)
		(width 0.11)
		(layer "F.Cu")
		(net 435)
	)
	(segment
		(start 107.166203 86.101477)
		(end 107.174339 86.124727)
		(width 0.11)
		(layer "F.Cu")
		(net 435)
	)
	(segment
		(start 108.326531 86.816208)
		(end 108.260812 86.839204)
		(width 0.11)
		(layer "F.Cu")
		(net 435)
	)
	(segment
		(start 107.225718 85.296106)
		(end 107.248968 85.304242)
		(width 0.11)
		(layer "F.Cu")
		(net 435)
	)
	(segment
		(start 108.471763 86.363023)
		(end 108.494759 86.428742)
		(width 0.11)
		(layer "F.Cu")
		(net 435)
	)
	(segment
		(start 108.326531 85.337791)
		(end 108.385486 85.374835)
		(width 0.11)
		(layer "F.Cu")
		(net 435)
	)
	(segment
		(start 107.174339 86.124727)
		(end 107.187444 86.145583)
		(width 0.11)
		(layer "F.Cu")
		(net 435)
	)
	(segment
		(start 108.326531 85.936208)
		(end 108.260812 85.959204)
		(width 0.11)
		(layer "F.Cu")
		(net 435)
	)
	(segment
		(start 107.187444 85.128416)
		(end 107.174339 85.149272)
		(width 0.11)
		(layer "F.Cu")
		(net 435)
	)
	(segment
		(start 108.191623 85.307)
		(end 108.260812 85.314795)
		(width 0.11)
		(layer "F.Cu")
		(net 435)
	)
	(segment
		(start 107.273446 85.087)
		(end 107.248968 85.089757)
		(width 0.11)
		(layer "F.Cu")
		(net 435)
	)
	(segment
		(start 107.522068 87.067)
		(end 107.591257 87.074795)
		(width 0.11)
		(layer "F.Cu")
		(net 435)
	)
	(segment
		(start 104.21 91.865564)
		(end 104.21 92.657851)
		(width 0.11)
		(layer "F.Cu")
		(net 435)
	)
	(segment
		(start 107.204862 87.043001)
		(end 107.225718 87.056106)
		(width 0.11)
		(layer "F.Cu")
		(net 435)
	)
	(segment
		(start 107.833 88.242564)
		(end 104.21 91.865564)
		(width 0.11)
		(layer "F.Cu")
		(net 435)
	)
	(segment
		(start 107.833 87.377931)
		(end 107.833 88.242564)
		(width 0.11)
		(layer "F.Cu")
		(net 435)
	)
	(segment
		(start 108.385486 85.899164)
		(end 108.326531 85.936208)
		(width 0.11)
		(layer "F.Cu")
		(net 435)
	)
	(segment
		(start 107.225718 87.056106)
		(end 107.248968 87.064242)
		(width 0.11)
		(layer "F.Cu")
		(net 435)
	)
	(segment
		(start 107.174339 85.244727)
		(end 107.187444 85.265583)
		(width 0.11)
		(layer "F.Cu")
		(net 435)
	)
	(segment
		(start 104.21 92.657851)
		(end 104.35 92.797851)
		(width 0.11)
		(layer "F.Cu")
		(net 435)
	)
	(segment
		(start 107.163446 85.197)
		(end 107.166203 85.221477)
		(width 0.11)
		(layer "F.Cu")
		(net 435)
	)
	(segment
		(start 107.225718 86.176106)
		(end 107.248968 86.184242)
		(width 0.11)
		(layer "F.Cu")
		(net 435)
	)
	(segment
		(start 107.166203 85.172522)
		(end 107.163446 85.197)
		(width 0.11)
		(layer "F.Cu")
		(net 435)
	)
	(segment
		(start 107.166203 86.052522)
		(end 107.163446 86.077)
		(width 0.11)
		(layer "F.Cu")
		(net 435)
	)
	(segment
		(start 108.471763 85.483023)
		(end 108.494759 85.548742)
		(width 0.11)
		(layer "F.Cu")
		(net 435)
	)
	(segment
		(start 107.166203 86.932522)
		(end 107.163446 86.957)
		(width 0.11)
		(layer "F.Cu")
		(net 435)
	)
	(segment
		(start 107.163446 86.957)
		(end 107.166203 86.981477)
		(width 0.11)
		(layer "F.Cu")
		(net 435)
	)
	(segment
		(start 107.656976 87.097791)
		(end 107.715931 87.134835)
		(width 0.11)
		(layer "F.Cu")
		(net 435)
	)
	(segment
		(start 108.260812 85.959204)
		(end 108.191623 85.967)
		(width 0.11)
		(layer "F.Cu")
		(net 435)
	)
	(segment
		(start 108.434719 85.424068)
		(end 108.471763 85.483023)
		(width 0.11)
		(layer "F.Cu")
		(net 435)
	)
	(segment
		(start 107.833 84.281)
		(end 107.833 84.776068)
		(width 0.11)
		(layer "F.Cu")
		(net 435)
	)
	(segment
		(start 107.187444 86.008416)
		(end 107.174339 86.029272)
		(width 0.11)
		(layer "F.Cu")
		(net 435)
	)
	(segment
		(start 107.248968 86.849757)
		(end 107.225718 86.857893)
		(width 0.11)
		(layer "F.Cu")
		(net 435)
	)
	(segment
		(start 107.204862 85.283001)
		(end 107.225718 85.296106)
		(width 0.11)
		(layer "F.Cu")
		(net 435)
	)
	(segment
		(start 107.715931 85.019164)
		(end 107.656976 85.056208)
		(width 0.11)
		(layer "F.Cu")
		(net 435)
	)
	(segment
		(start 107.204862 86.163001)
		(end 107.225718 86.176106)
		(width 0.11)
		(layer "F.Cu")
		(net 435)
	)
	(segment
		(start 107.248968 87.064242)
		(end 107.273446 87.067)
		(width 0.11)
		(layer "F.Cu")
		(net 435)
	)
	(segment
		(start 108.191623 85.967)
		(end 107.273446 85.967)
		(width 0.11)
		(layer "F.Cu")
		(net 435)
	)
	(segment
		(start 108.385486 86.254835)
		(end 108.434719 86.304068)
		(width 0.11)
		(layer "F.Cu")
		(net 435)
	)
	(segment
		(start 107.522068 85.087)
		(end 107.273446 85.087)
		(width 0.11)
		(layer "F.Cu")
		(net 435)
	)
	(segment
		(start 107.204862 86.870998)
		(end 107.187444 86.888416)
		(width 0.11)
		(layer "F.Cu")
		(net 435)
	)
	(segment
		(start 108.494759 85.548742)
		(end 108.502554 85.617931)
		(width 0.11)
		(layer "F.Cu")
		(net 435)
	)
	(segment
		(start 108.191623 86.187)
		(end 108.260812 86.194795)
		(width 0.11)
		(layer "F.Cu")
		(net 435)
	)
	(segment
		(start 108.494759 85.725257)
		(end 108.471763 85.790976)
		(width 0.11)
		(layer "F.Cu")
		(net 435)
	)
	(segment
		(start 108.434719 85.849931)
		(end 108.385486 85.899164)
		(width 0.11)
		(layer "F.Cu")
		(net 435)
	)
	(segment
		(start 108.260812 85.314795)
		(end 108.326531 85.337791)
		(width 0.11)
		(layer "F.Cu")
		(net 435)
	)
	(segment
		(start 107.248968 85.969757)
		(end 107.225718 85.977893)
		(width 0.11)
		(layer "F.Cu")
		(net 435)
	)
	(segment
		(start 107.273446 85.967)
		(end 107.248968 85.969757)
		(width 0.11)
		(layer "F.Cu")
		(net 435)
	)
	(segment
		(start 108.385486 86.779164)
		(end 108.326531 86.816208)
		(width 0.11)
		(layer "F.Cu")
		(net 435)
	)
	(segment
		(start 108.494759 86.605257)
		(end 108.471763 86.670976)
		(width 0.11)
		(layer "F.Cu")
		(net 435)
	)
	(segment
		(start 107.187444 86.145583)
		(end 107.204862 86.163001)
		(width 0.11)
		(layer "F.Cu")
		(net 435)
	)
	(segment
		(start 108.471763 86.670976)
		(end 108.434719 86.729931)
		(width 0.11)
		(layer "F.Cu")
		(net 435)
	)
	(segment
		(start 107.825204 84.845257)
		(end 107.802208 84.910976)
		(width 0.11)
		(layer "F.Cu")
		(net 435)
	)
	(segment
		(start 107.802208 87.243023)
		(end 107.825204 87.308742)
		(width 0.11)
		(layer "F.Cu")
		(net 435)
	)
	(segment
		(start 107.174339 85.149272)
		(end 107.166203 85.172522)
		(width 0.11)
		(layer "F.Cu")
		(net 435)
	)
	(segment
		(start 108.502554 86.536068)
		(end 108.494759 86.605257)
		(width 0.11)
		(layer "F.Cu")
		(net 435)
	)
	(segment
		(start 107.273446 85.307)
		(end 108.191623 85.307)
		(width 0.11)
		(layer "F.Cu")
		(net 435)
	)
	(segment
		(start 107.248968 85.089757)
		(end 107.225718 85.097893)
		(width 0.11)
		(layer "F.Cu")
		(net 435)
	)
	(segment
		(start 108.502554 86.497931)
		(end 108.502554 86.536068)
		(width 0.11)
		(layer "F.Cu")
		(net 435)
	)
	(segment
		(start 107.187444 86.888416)
		(end 107.174339 86.909272)
		(width 0.11)
		(layer "F.Cu")
		(net 435)
	)
	(segment
		(start 107.166203 86.981477)
		(end 107.174339 87.004727)
		(width 0.11)
		(layer "F.Cu")
		(net 435)
	)
	(segment
		(start 107.204862 85.990998)
		(end 107.187444 86.008416)
		(width 0.11)
		(layer "F.Cu")
		(net 435)
	)
	(segment
		(start 107.273446 86.187)
		(end 108.191623 86.187)
		(width 0.11)
		(layer "F.Cu")
		(net 435)
	)
	(segment
		(start 108.471763 85.790976)
		(end 108.434719 85.849931)
		(width 0.11)
		(layer "F.Cu")
		(net 435)
	)
	(segment
		(start 126.925 108.94)
		(end 126.925 107.225)
		(width 0.15)
		(layer "F.Cu")
		(net 442)
	)
	(segment
		(start 117.62503 106.52497)
		(end 116.775 107.375)
		(width 0.15)
		(layer "F.Cu")
		(net 442)
	)
	(segment
		(start 126.22497 106.52497)
		(end 117.62503 106.52497)
		(width 0.15)
		(layer "F.Cu")
		(net 442)
	)
	(segment
		(start 108.275 110.675)
		(end 107.775 111.175)
		(width 0.15)
		(layer "F.Cu")
		(net 442)
	)
	(segment
		(start 109.575 107.375)
		(end 108.275 108.675)
		(width 0.15)
		(layer "F.Cu")
		(net 442)
	)
	(segment
		(start 108.275 108.675)
		(end 108.275 110.675)
		(width 0.15)
		(layer "F.Cu")
		(net 442)
	)
	(segment
		(start 126.925 107.225)
		(end 126.22497 106.52497)
		(width 0.15)
		(layer "F.Cu")
		(net 442)
	)
	(segment
		(start 116.775 107.375)
		(end 109.575 107.375)
		(width 0.15)
		(layer "F.Cu")
		(net 442)
	)
	(segment
		(start 108.775 108.875)
		(end 108.775 109.175)
		(width 0.15)
		(layer "F.Cu")
		(net 444)
	)
	(segment
		(start 109.975 107.675)
		(end 108.775 108.875)
		(width 0.15)
		(layer "F.Cu")
		(net 444)
	)
	(segment
		(start 125.925 108.94)
		(end 125.925 107.125)
		(width 0.15)
		(layer "F.Cu")
		(net 444)
	)
	(segment
		(start 125.925 107.125)
		(end 125.57498 106.77498)
		(width 0.15)
		(layer "F.Cu")
		(net 444)
	)
	(segment
		(start 117.97502 106.77498)
		(end 117.075 107.675)
		(width 0.15)
		(layer "F.Cu")
		(net 444)
	)
	(segment
		(start 117.075 107.675)
		(end 109.975 107.675)
		(width 0.15)
		(layer "F.Cu")
		(net 444)
	)
	(segment
		(start 125.57498 106.77498)
		(end 117.97502 106.77498)
		(width 0.15)
		(layer "F.Cu")
		(net 444)
	)
	(segment
		(start 118.32501 107.02499)
		(end 117.275 108.075)
		(width 0.15)
		(layer "F.Cu")
		(net 445)
	)
	(segment
		(start 117.275 108.075)
		(end 110.245998 108.075)
		(width 0.15)
		(layer "F.Cu")
		(net 445)
	)
	(segment
		(start 125.425 108.94)
		(end 125.425 107.425)
		(width 0.15)
		(layer "F.Cu")
		(net 445)
	)
	(segment
		(start 110.245998 108.075)
		(end 109.275 109.045998)
		(width 0.15)
		(layer "F.Cu")
		(net 445)
	)
	(segment
		(start 109.275 109.675)
		(end 108.775 110.175)
		(width 0.15)
		(layer "F.Cu")
		(net 445)
	)
	(segment
		(start 125.425 107.425)
		(end 125.02499 107.02499)
		(width 0.15)
		(layer "F.Cu")
		(net 445)
	)
	(segment
		(start 109.275 109.045998)
		(end 109.275 109.675)
		(width 0.15)
		(layer "F.Cu")
		(net 445)
	)
	(segment
		(start 125.02499 107.02499)
		(end 118.32501 107.02499)
		(width 0.15)
		(layer "F.Cu")
		(net 445)
	)
	(segment
		(start 124.675 107.275)
		(end 118.575 107.275)
		(width 0.15)
		(layer "F.Cu")
		(net 446)
	)
	(segment
		(start 124.925 108.94)
		(end 124.925 107.525)
		(width 0.15)
		(layer "F.Cu")
		(net 446)
	)
	(segment
		(start 118.575 107.275)
		(end 117.375 108.475)
		(width 0.15)
		(layer "F.Cu")
		(net 446)
	)
	(segment
		(start 110.475 108.475)
		(end 109.775 109.175)
		(width 0.15)
		(layer "F.Cu")
		(net 446)
	)
	(segment
		(start 124.925 107.525)
		(end 124.675 107.275)
		(width 0.15)
		(layer "F.Cu")
		(net 446)
	)
	(segment
		(start 117.375 108.475)
		(end 110.475 108.475)
		(width 0.15)
		(layer "F.Cu")
		(net 446)
	)
	(segment
		(start 108.775 112.175)
		(end 109.275 111.675)
		(width 0.15)
		(layer "F.Cu")
		(net 447)
	)
	(segment
		(start 124.425 108.94)
		(end 124.425 107.925)
		(width 0.15)
		(layer "F.Cu")
		(net 447)
	)
	(segment
		(start 124.425 107.925)
		(end 124.475 107.875)
		(width 0.15)
		(layer "F.Cu")
		(net 447)
	)
	(via blind
		(at 109.275 111.675)
		(size 0.5)
		(drill 0.2)
		(layers "F.Cu" "In2.Cu")
		(net 447)
	)
	(via blind
		(at 124.475 107.875)
		(size 0.5)
		(drill 0.2)
		(layers "F.Cu" "In2.Cu")
		(net 447)
	)
	(segment
		(start 122.675 112.675)
		(end 111.699278 112.675)
		(width 0.15)
		(layer "In2.Cu")
		(net 447)
	)
	(segment
		(start 124.475 110.875)
		(end 122.675 112.675)
		(width 0.15)
		(layer "In2.Cu")
		(net 447)
	)
	(segment
		(start 124.475 107.875)
		(end 124.475 110.875)
		(width 0.15)
		(layer "In2.Cu")
		(net 447)
	)
	(segment
		(start 111.699278 112.675)
		(end 110.699278 111.675)
		(width 0.15)
		(layer "In2.Cu")
		(net 447)
	)
	(segment
		(start 109.275 111.675)
		(end 110.699278 111.675)
		(width 0.15)
		(layer "In2.Cu")
		(net 447)
	)
	(segment
		(start 111.775 109.175)
		(end 118.775 109.175)
		(width 0.15)
		(layer "F.Cu")
		(net 448)
	)
	(segment
		(start 119.225 109.625)
		(end 122.74 109.625)
		(width 0.15)
		(layer "F.Cu")
		(net 448)
	)
	(segment
		(start 118.775 109.175)
		(end 119.225 109.625)
		(width 0.15)
		(layer "F.Cu")
		(net 448)
	)
	(segment
		(start 119.125 110.125)
		(end 122.74 110.125)
		(width 0.15)
		(layer "F.Cu")
		(net 449)
	)
	(segment
		(start 111.145998 110.175)
		(end 111.645998 109.675)
		(width 0.15)
		(layer "F.Cu")
		(net 449)
	)
	(segment
		(start 118.675 109.675)
		(end 119.125 110.125)
		(width 0.15)
		(layer "F.Cu")
		(net 449)
	)
	(segment
		(start 110.775 110.175)
		(end 111.145998 110.175)
		(width 0.15)
		(layer "F.Cu")
		(net 449)
	)
	(segment
		(start 111.645998 109.675)
		(end 118.675 109.675)
		(width 0.15)
		(layer "F.Cu")
		(net 449)
	)
	(segment
		(start 119.025 110.625)
		(end 118.575 110.175)
		(width 0.15)
		(layer "F.Cu")
		(net 450)
	)
	(segment
		(start 112.128553 110.175)
		(end 111.775 110.175)
		(width 0.15)
		(layer "F.Cu")
		(net 450)
	)
	(segment
		(start 122.74 110.625)
		(end 119.025 110.625)
		(width 0.15)
		(layer "F.Cu")
		(net 450)
	)
	(segment
		(start 111.775 110.175)
		(end 113.975 110.175)
		(width 0.15)
		(layer "F.Cu")
		(net 450)
	)
	(segment
		(start 118.575 110.175)
		(end 112.128553 110.175)
		(width 0.15)
		(layer "F.Cu")
		(net 450)
	)
	(segment
		(start 111.200001 110.749999)
		(end 118.449999 110.749999)
		(width 0.15)
		(layer "F.Cu")
		(net 451)
	)
	(segment
		(start 118.825 111.125)
		(end 122.74 111.125)
		(width 0.15)
		(layer "F.Cu")
		(net 451)
	)
	(segment
		(start 118.449999 110.749999)
		(end 118.825 111.125)
		(width 0.15)
		(layer "F.Cu")
		(net 451)
	)
	(segment
		(start 110.775 111.175)
		(end 111.200001 110.749999)
		(width 0.15)
		(layer "F.Cu")
		(net 451)
	)
	(segment
		(start 111.775 111.175)
		(end 118.075 111.175)
		(width 0.15)
		(layer "F.Cu")
		(net 452)
	)
	(segment
		(start 118.075 111.175)
		(end 118.525 111.625)
		(width 0.15)
		(layer "F.Cu")
		(net 452)
	)
	(segment
		(start 118.525 111.625)
		(end 122.74 111.625)
		(width 0.15)
		(layer "F.Cu")
		(net 452)
	)
	(segment
		(start 111.200001 111.749999)
		(end 117.949999 111.749999)
		(width 0.15)
		(layer "F.Cu")
		(net 453)
	)
	(segment
		(start 110.775 112.175)
		(end 111.200001 111.749999)
		(width 0.15)
		(layer "F.Cu")
		(net 453)
	)
	(segment
		(start 117.949999 111.749999)
		(end 118.325 112.125)
		(width 0.15)
		(layer "F.Cu")
		(net 453)
	)
	(segment
		(start 118.325 112.125)
		(end 122.74 112.125)
		(width 0.15)
		(layer "F.Cu")
		(net 453)
	)
	(segment
		(start 111.275 112.675)
		(end 122.69 112.675)
		(width 0.15)
		(layer "F.Cu")
		(net 454)
	)
	(segment
		(start 122.69 112.675)
		(end 122.74 112.625)
		(width 0.15)
		(layer "F.Cu")
		(net 454)
	)
	(segment
		(start 110.775 113.175)
		(end 111.275 112.675)
		(width 0.15)
		(layer "F.Cu")
		(net 454)
	)
	(segment
		(start 111.775 113.175)
		(end 122.69 113.175)
		(width 0.15)
		(layer "F.Cu")
		(net 455)
	)
	(segment
		(start 122.69 113.175)
		(end 122.74 113.125)
		(width 0.15)
		(layer "F.Cu")
		(net 455)
	)
	(segment
		(start 125.3075 122.675)
		(end 126.725 124.0925)
		(width 0.15)
		(layer "F.Cu")
		(net 457)
	)
	(segment
		(start 111.275 122.675)
		(end 125.3075 122.675)
		(width 0.15)
		(layer "F.Cu")
		(net 457)
	)
	(segment
		(start 110.775 123.175)
		(end 111.275 122.675)
		(width 0.15)
		(layer "F.Cu")
		(net 457)
	)
	(segment
		(start 126.725 124.0925)
		(end 126.725 125.04)
		(width 0.15)
		(layer "F.Cu")
		(net 457)
	)
	(segment
		(start 124.875 122.975)
		(end 112.775 122.975)
		(width 0.15)
		(layer "F.Cu")
		(net 458)
	)
	(segment
		(start 125.725 125.04)
		(end 125.725 123.825)
		(width 0.15)
		(layer "F.Cu")
		(net 458)
	)
	(segment
		(start 111.775 123.175)
		(end 112.575 123.175)
		(width 0.15)
		(layer "F.Cu")
		(net 458)
	)
	(segment
		(start 125.725 123.825)
		(end 124.875 122.975)
		(width 0.15)
		(layer "F.Cu")
		(net 458)
	)
	(segment
		(start 112.575 123.175)
		(end 112.775 122.975)
		(width 0.15)
		(layer "F.Cu")
		(net 458)
	)
	(segment
		(start 124.675 123.275)
		(end 122.625 123.275)
		(width 0.15)
		(layer "F.Cu")
		(net 459)
	)
	(segment
		(start 122.625 123.275)
		(end 121.725 124.175)
		(width 0.15)
		(layer "F.Cu")
		(net 459)
	)
	(segment
		(start 111.775 124.175)
		(end 121.725 124.175)
		(width 0.15)
		(layer "F.Cu")
		(net 459)
	)
	(segment
		(start 125.225 125.04)
		(end 125.225 123.825)
		(width 0.15)
		(layer "F.Cu")
		(net 459)
	)
	(segment
		(start 125.225 123.825)
		(end 124.675 123.275)
		(width 0.15)
		(layer "F.Cu")
		(net 459)
	)
	(segment
		(start 121.675 124.675)
		(end 111.275 124.675)
		(width 0.15)
		(layer "F.Cu")
		(net 460)
	)
	(segment
		(start 124.725 123.895998)
		(end 124.404002 123.575)
		(width 0.15)
		(layer "F.Cu")
		(net 460)
	)
	(segment
		(start 124.404002 123.575)
		(end 122.775 123.575)
		(width 0.15)
		(layer "F.Cu")
		(net 460)
	)
	(segment
		(start 111.275 124.675)
		(end 110.775 125.175)
		(width 0.15)
		(layer "F.Cu")
		(net 460)
	)
	(segment
		(start 124.725 125.04)
		(end 124.725 123.895998)
		(width 0.15)
		(layer "F.Cu")
		(net 460)
	)
	(segment
		(start 122.775 123.575)
		(end 121.675 124.675)
		(width 0.15)
		(layer "F.Cu")
		(net 460)
	)
	(segment
		(start 124.225 125.04)
		(end 124.225 124.125)
		(width 0.15)
		(layer "F.Cu")
		(net 461)
	)
	(segment
		(start 124.225 124.125)
		(end 124.275 124.075)
		(width 0.15)
		(layer "F.Cu")
		(net 461)
	)
	(segment
		(start 107.775 127.175)
		(end 108.275 127.675)
		(width 0.15)
		(layer "F.Cu")
		(net 461)
	)
	(via blind
		(at 108.275 127.675)
		(size 0.5)
		(drill 0.2)
		(layers "F.Cu" "In2.Cu")
		(net 461)
	)
	(via blind
		(at 124.275 124.075)
		(size 0.5)
		(drill 0.2)
		(layers "F.Cu" "In2.Cu")
		(net 461)
	)
	(segment
		(start 120.655 128.175)
		(end 108.775 128.175)
		(width 0.15)
		(layer "In2.Cu")
		(net 461)
	)
	(segment
		(start 124.275 124.555)
		(end 120.655 128.175)
		(width 0.15)
		(layer "In2.Cu")
		(net 461)
	)
	(segment
		(start 108.775 128.175)
		(end 108.275 127.675)
		(width 0.15)
		(layer "In2.Cu")
		(net 461)
	)
	(segment
		(start 124.275 124.075)
		(end 124.275 124.555)
		(width 0.15)
		(layer "In2.Cu")
		(net 461)
	)
	(segment
		(start 120.425 125.725)
		(end 119.875 125.175)
		(width 0.15)
		(layer "F.Cu")
		(net 462)
	)
	(segment
		(start 111.775 125.175)
		(end 119.875 125.175)
		(width 0.15)
		(layer "F.Cu")
		(net 462)
	)
	(segment
		(start 122.54 125.725)
		(end 120.425 125.725)
		(width 0.15)
		(layer "F.Cu")
		(net 462)
	)
	(segment
		(start 111.200001 125.749999)
		(end 110.775 126.175)
		(width 0.15)
		(layer "F.Cu")
		(net 463)
	)
	(segment
		(start 122.54 126.225)
		(end 120.425 126.225)
		(width 0.15)
		(layer "F.Cu")
		(net 463)
	)
	(segment
		(start 120.425 126.225)
		(end 119.949999 125.749999)
		(width 0.15)
		(layer "F.Cu")
		(net 463)
	)
	(segment
		(start 119.949999 125.749999)
		(end 111.200001 125.749999)
		(width 0.15)
		(layer "F.Cu")
		(net 463)
	)
	(segment
		(start 111.775 126.175)
		(end 119.675 126.175)
		(width 0.15)
		(layer "F.Cu")
		(net 464)
	)
	(segment
		(start 122.54 126.725)
		(end 120.225 126.725)
		(width 0.15)
		(layer "F.Cu")
		(net 464)
	)
	(segment
		(start 120.225 126.725)
		(end 119.675 126.175)
		(width 0.15)
		(layer "F.Cu")
		(net 464)
	)
	(segment
		(start 119.825 127.225)
		(end 122.54 127.225)
		(width 0.15)
		(layer "F.Cu")
		(net 465)
	)
	(segment
		(start 111.275 126.675)
		(end 119.275 126.675)
		(width 0.15)
		(layer "F.Cu")
		(net 465)
	)
	(segment
		(start 110.775 127.175)
		(end 111.275 126.675)
		(width 0.15)
		(layer "F.Cu")
		(net 465)
	)
	(segment
		(start 119.275 126.675)
		(end 119.825 127.225)
		(width 0.15)
		(layer "F.Cu")
		(net 465)
	)
	(segment
		(start 122.49 127.675)
		(end 122.54 127.725)
		(width 0.15)
		(layer "F.Cu")
		(net 466)
	)
	(segment
		(start 110.275 127.675)
		(end 122.49 127.675)
		(width 0.15)
		(layer "F.Cu")
		(net 466)
	)
	(segment
		(start 109.775 127.175)
		(end 110.275 127.675)
		(width 0.15)
		(layer "F.Cu")
		(net 466)
	)
	(segment
		(start 111.775 128.175)
		(end 122.49 128.175)
		(width 0.15)
		(layer "F.Cu")
		(net 467)
	)
	(segment
		(start 122.49 128.175)
		(end 122.54 128.225)
		(width 0.15)
		(layer "F.Cu")
		(net 467)
	)
	(segment
		(start 122.49 128.675)
		(end 122.54 128.725)
		(width 0.15)
		(layer "F.Cu")
		(net 468)
	)
	(segment
		(start 111.275 128.675)
		(end 122.49 128.675)
		(width 0.15)
		(layer "F.Cu")
		(net 468)
	)
	(segment
		(start 110.775 128.175)
		(end 111.275 128.675)
		(width 0.15)
		(layer "F.Cu")
		(net 468)
	)
	(segment
		(start 122.49 129.175)
		(end 122.54 129.225)
		(width 0.15)
		(layer "F.Cu")
		(net 469)
	)
	(segment
		(start 111.775 129.175)
		(end 122.49 129.175)
		(width 0.15)
		(layer "F.Cu")
		(net 469)
	)
	(segment
		(start 93.775 130.175)
		(end 94.275 130.675)
		(width 0.15)
		(layer "F.Cu")
		(net 474)
	)
	(segment
		(start 92.975 145.575)
		(end 92.975 146.174988)
		(width 0.1)
		(layer "F.Cu")
		(net 474)
	)
	(segment
		(start 92.975 146.174988)
		(end 92.974988 146.175)
		(width 0.1)
		(layer "F.Cu")
		(net 474)
	)
	(via blind
		(at 94.275 130.675)
		(size 0.5)
		(drill 0.2)
		(layers "F.Cu" "In5.Cu")
		(net 474)
	)
	(via blind
		(at 92.974988 146.175)
		(size 0.5)
		(drill 0.2)
		(layers "F.Cu" "In5.Cu")
		(net 474)
	)
	(segment
		(start 93.553871 131.005245)
		(end 93.536363 131.019207)
		(width 0.1)
		(layer "In5.Cu")
		(net 474)
	)
	(segment
		(start 92.901499 144.715839)
		(end 92.952914 144.748145)
		(width 0.1)
		(layer "In5.Cu")
		(net 474)
	)
	(segment
		(start 93.282087 145.194766)
		(end 93.275 145.257665)
		(width 0.1)
		(layer "In5.Cu")
		(net 474)
	)
	(segment
		(start 93.336668 145.081426)
		(end 93.302992 145.135021)
		(width 0.1)
		(layer "In5.Cu")
		(net 474)
	)
	(segment
		(start 93.915833 131.554103)
		(end 93.920816 131.575935)
		(width 0.1)
		(layer "In5.Cu")
		(net 474)
	)
	(segment
		(start 94.240696 144.831611)
		(end 94.248092 144.852747)
		(width 0.1)
		(layer "In5.Cu")
		(net 474)
	)
	(segment
		(start 93.507702 131.078721)
		(end 93.507702 131.101114)
		(width 0.1)
		(layer "In5.Cu")
		(net 474)
	)
	(segment
		(start 94.051086 131.388961)
		(end 94.033578 131.375)
		(width 0.1)
		(layer "In5.Cu")
		(net 474)
	)
	(segment
		(start 93.574046 130.995529)
		(end 93.553871 131.005245)
		(width 0.1)
		(layer "In5.Cu")
		(net 474)
	)
	(segment
		(start 94.115485 131.40366)
		(end 94.093092 131.40366)
		(width 0.1)
		(layer "In5.Cu")
		(net 474)
	)
	(segment
		(start 92.952914 144.748145)
		(end 93.010229 144.768201)
		(width 0.1)
		(layer "In5.Cu")
		(net 474)
	)
	(segment
		(start 94.093092 131.40366)
		(end 94.071261 131.398677)
		(width 0.1)
		(layer "In5.Cu")
		(net 474)
	)
	(segment
		(start 94.228783 144.812651)
		(end 94.240696 144.831611)
		(width 0.1)
		(layer "In5.Cu")
		(net 474)
	)
	(segment
		(start 93.61827 130.990546)
		(end 93.595878 130.990546)
		(width 0.1)
		(layer "In5.Cu")
		(net 474)
	)
	(segment
		(start 93.906117 131.640334)
		(end 93.892157 131.657842)
		(width 0.1)
		(layer "In5.Cu")
		(net 474)
	)
	(segment
		(start 93.906117 131.533928)
		(end 93.915833 131.554103)
		(width 0.1)
		(layer "In5.Cu")
		(net 474)
	)
	(segment
		(start 94.071261 131.398677)
		(end 94.051086 131.388961)
		(width 0.1)
		(layer "In5.Cu")
		(net 474)
	)
	(segment
		(start 93.557665 144.975)
		(end 93.494766 144.982087)
		(width 0.1)
		(layer "In5.Cu")
		(net 474)
	)
	(segment
		(start 92.858561 144.672901)
		(end 92.901499 144.715839)
		(width 0.1)
		(layer "In5.Cu")
		(net 474)
	)
	(segment
		(start 94.172852 144.777507)
		(end 94.193988 144.784903)
		(width 0.1)
		(layer "In5.Cu")
		(net 474)
	)
	(segment
		(start 94.137317 131.398677)
		(end 94.115485 131.40366)
		(width 0.1)
		(layer "In5.Cu")
		(net 474)
	)
	(segment
		(start 92.901499 144.23416)
		(end 92.858561 144.277098)
		(width 0.1)
		(layer "In5.Cu")
		(net 474)
	)
	(segment
		(start 94.1506 144.975)
		(end 93.557665 144.975)
		(width 0.1)
		(layer "In5.Cu")
		(net 474)
	)
	(segment
		(start 94.212948 144.796816)
		(end 94.228783 144.812651)
		(width 0.1)
		(layer "In5.Cu")
		(net 474)
	)
	(segment
		(start 93.660277 131.005245)
		(end 93.640102 130.995529)
		(width 0.1)
		(layer "In5.Cu")
		(net 474)
	)
	(segment
		(start 94.240696 144.918388)
		(end 94.228783 144.937348)
		(width 0.1)
		(layer "In5.Cu")
		(net 474)
	)
	(segment
		(start 92.806199 144.385828)
		(end 92.7994 144.446169)
		(width 0.1)
		(layer "In5.Cu")
		(net 474)
	)
	(segment
		(start 93.512685 131.056889)
		(end 93.507702 131.078721)
		(width 0.1)
		(layer "In5.Cu")
		(net 474)
	)
	(segment
		(start 94.157492 131.388961)
		(end 94.137317 131.398677)
		(width 0.1)
		(layer "In5.Cu")
		(net 474)
	)
	(segment
		(start 93.255845 144.141942)
		(end 93.241943 144.155844)
		(width 0.1)
		(layer "In5.Cu")
		(net 474)
	)
	(segment
		(start 93.435021 145.002992)
		(end 93.381426 145.036668)
		(width 0.1)
		(layer "In5.Cu")
		(net 474)
	)
	(segment
		(start 94.1506 144.775)
		(end 94.172852 144.777507)
		(width 0.1)
		(layer "In5.Cu")
		(net 474)
	)
	(segment
		(start 94.275 131.275)
		(end 94.175 131.375)
		(width 0.1)
		(layer "In5.Cu")
		(net 474)
	)
	(segment
		(start 92.7994 144.50383)
		(end 92.806199 144.564171)
		(width 0.1)
		(layer "In5.Cu")
		(net 474)
	)
	(segment
		(start 94.275 130.675)
		(end 94.275 131.275)
		(width 0.1)
		(layer "In5.Cu")
		(net 474)
	)
	(segment
		(start 93.381426 145.036668)
		(end 93.336668 145.081426)
		(width 0.1)
		(layer "In5.Cu")
		(net 474)
	)
	(segment
		(start 94.228783 144.937348)
		(end 94.212948 144.953183)
		(width 0.1)
		(layer "In5.Cu")
		(net 474)
	)
	(segment
		(start 93.892155 131.51642)
		(end 93.906117 131.533928)
		(width 0.1)
		(layer "In5.Cu")
		(net 474)
	)
	(segment
		(start 92.952914 144.201854)
		(end 92.901499 144.23416)
		(width 0.1)
		(layer "In5.Cu")
		(net 474)
	)
	(segment
		(start 93.206738 144.172798)
		(end 93.1872 144.175)
		(width 0.1)
		(layer "In5.Cu")
		(net 474)
	)
	(segment
		(start 93.677785 131.019207)
		(end 93.660277 131.005245)
		(width 0.1)
		(layer "In5.Cu")
		(net 474)
	)
	(segment
		(start 94.2506 144.875)
		(end 94.248092 144.897252)
		(width 0.1)
		(layer "In5.Cu")
		(net 474)
	)
	(segment
		(start 93.275 144.0872)
		(end 93.272799 144.106737)
		(width 0.1)
		(layer "In5.Cu")
		(net 474)
	)
	(segment
		(start 93.920816 131.575935)
		(end 93.920816 131.598327)
		(width 0.1)
		(layer "In5.Cu")
		(net 474)
	)
	(segment
		(start 93.241943 144.155844)
		(end 93.225295 144.166305)
		(width 0.1)
		(layer "In5.Cu")
		(net 474)
	)
	(segment
		(start 94.212948 144.953183)
		(end 94.193988 144.965096)
		(width 0.1)
		(layer "In5.Cu")
		(net 474)
	)
	(segment
		(start 92.826255 144.621486)
		(end 92.858561 144.672901)
		(width 0.1)
		(layer "In5.Cu")
		(net 474)
	)
	(segment
		(start 94.172852 144.972492)
		(end 94.1506 144.975)
		(width 0.1)
		(layer "In5.Cu")
		(net 474)
	)
	(segment
		(start 93.522401 131.036714)
		(end 93.512685 131.056889)
		(width 0.1)
		(layer "In5.Cu")
		(net 474)
	)
	(segment
		(start 93.275 132.275)
		(end 93.892157 131.657842)
		(width 0.1)
		(layer "In5.Cu")
		(net 474)
	)
	(segment
		(start 93.272799 144.106737)
		(end 93.266306 144.125294)
		(width 0.1)
		(layer "In5.Cu")
		(net 474)
	)
	(segment
		(start 93.512685 131.122945)
		(end 93.522401 131.14312)
		(width 0.1)
		(layer "In5.Cu")
		(net 474)
	)
	(segment
		(start 92.7994 144.446169)
		(end 92.7994 144.50383)
		(width 0.1)
		(layer "In5.Cu")
		(net 474)
	)
	(segment
		(start 93.595878 130.990546)
		(end 93.574046 130.995529)
		(width 0.1)
		(layer "In5.Cu")
		(net 474)
	)
	(segment
		(start 93.266306 144.125294)
		(end 93.255845 144.141942)
		(width 0.1)
		(layer "In5.Cu")
		(net 474)
	)
	(segment
		(start 93.522401 131.14312)
		(end 93.536363 131.160628)
		(width 0.1)
		(layer "In5.Cu")
		(net 474)
	)
	(segment
		(start 93.494766 144.982087)
		(end 93.435021 145.002992)
		(width 0.1)
		(layer "In5.Cu")
		(net 474)
	)
	(segment
		(start 92.858561 144.277098)
		(end 92.826255 144.328513)
		(width 0.1)
		(layer "In5.Cu")
		(net 474)
	)
	(segment
		(start 94.193988 144.784903)
		(end 94.212948 144.796816)
		(width 0.1)
		(layer "In5.Cu")
		(net 474)
	)
	(segment
		(start 93.302992 145.135021)
		(end 93.282087 145.194766)
		(width 0.1)
		(layer "In5.Cu")
		(net 474)
	)
	(segment
		(start 93.07057 144.175)
		(end 93.010229 144.181798)
		(width 0.1)
		(layer "In5.Cu")
		(net 474)
	)
	(segment
		(start 93.507702 131.101114)
		(end 93.512685 131.122945)
		(width 0.1)
		(layer "In5.Cu")
		(net 474)
	)
	(segment
		(start 94.248092 144.852747)
		(end 94.2506 144.875)
		(width 0.1)
		(layer "In5.Cu")
		(net 474)
	)
	(segment
		(start 94.193988 144.965096)
		(end 94.172852 144.972492)
		(width 0.1)
		(layer "In5.Cu")
		(net 474)
	)
	(segment
		(start 93.920816 131.598327)
		(end 93.915833 131.620159)
		(width 0.1)
		(layer "In5.Cu")
		(net 474)
	)
	(segment
		(start 93.07057 144.775)
		(end 94.1506 144.775)
		(width 0.1)
		(layer "In5.Cu")
		(net 474)
	)
	(segment
		(start 93.1872 144.175)
		(end 93.07057 144.175)
		(width 0.1)
		(layer "In5.Cu")
		(net 474)
	)
	(segment
		(start 93.915833 131.620159)
		(end 93.906117 131.640334)
		(width 0.1)
		(layer "In5.Cu")
		(net 474)
	)
	(segment
		(start 93.536363 131.019207)
		(end 93.522401 131.036714)
		(width 0.1)
		(layer "In5.Cu")
		(net 474)
	)
	(segment
		(start 92.826255 144.328513)
		(end 92.806199 144.385828)
		(width 0.1)
		(layer "In5.Cu")
		(net 474)
	)
	(segment
		(start 93.640102 130.995529)
		(end 93.61827 130.990546)
		(width 0.1)
		(layer "In5.Cu")
		(net 474)
	)
	(segment
		(start 93.275 132.275)
		(end 93.275 144.0872)
		(width 0.1)
		(layer "In5.Cu")
		(net 474)
	)
	(segment
		(start 94.248092 144.897252)
		(end 94.240696 144.918388)
		(width 0.1)
		(layer "In5.Cu")
		(net 474)
	)
	(segment
		(start 94.033578 131.375)
		(end 93.677785 131.019207)
		(width 0.1)
		(layer "In5.Cu")
		(net 474)
	)
	(segment
		(start 93.225295 144.166305)
		(end 93.206738 144.172798)
		(width 0.1)
		(layer "In5.Cu")
		(net 474)
	)
	(segment
		(start 93.010229 144.181798)
		(end 92.952914 144.201854)
		(width 0.1)
		(layer "In5.Cu")
		(net 474)
	)
	(segment
		(start 94.175 131.375)
		(end 94.157492 131.388961)
		(width 0.1)
		(layer "In5.Cu")
		(net 474)
	)
	(segment
		(start 93.275 145.257665)
		(end 93.275 145.874988)
		(width 0.1)
		(layer "In5.Cu")
		(net 474)
	)
	(segment
		(start 93.275 145.874988)
		(end 92.974988 146.175)
		(width 0.1)
		(layer "In5.Cu")
		(net 474)
	)
	(segment
		(start 93.536363 131.160628)
		(end 93.892155 131.51642)
		(width 0.1)
		(layer "In5.Cu")
		(net 474)
	)
	(segment
		(start 93.010229 144.768201)
		(end 93.07057 144.775)
		(width 0.1)
		(layer "In5.Cu")
		(net 474)
	)
	(segment
		(start 92.806199 144.564171)
		(end 92.826255 144.621486)
		(width 0.1)
		(layer "In5.Cu")
		(net 474)
	)
	(segment
		(start 93.775 145.575)
		(end 93.775 146.175014)
		(width 0.1)
		(layer "F.Cu")
		(net 475)
	)
	(segment
		(start 94.775 130.175)
		(end 94.275 129.675)
		(width 0.15)
		(layer "F.Cu")
		(net 475)
	)
	(via blind
		(at 93.775 146.175014)
		(size 0.5)
		(drill 0.2)
		(layers "F.Cu" "In5.Cu")
		(net 475)
	)
	(via blind
		(at 94.275 129.675)
		(size 0.5)
		(drill 0.2)
		(layers "F.Cu" "In5.Cu")
		(net 475)
	)
	(segment
		(start 93.008095 144.525294)
		(end 93.001602 144.506737)
		(width 0.1)
		(layer "In5.Cu")
		(net 475)
	)
	(segment
		(start 93.372902 144.315839)
		(end 93.41584 144.272901)
		(width 0.1)
		(layer "In5.Cu")
		(net 475)
	)
	(segment
		(start 93.468202 144.164171)
		(end 93.475 144.10383)
		(width 0.1)
		(layer "In5.Cu")
		(net 475)
	)
	(segment
		(start 92.9994 144.4872)
		(end 92.9994 144.4628)
		(width 0.1)
		(layer "In5.Cu")
		(net 475)
	)
	(segment
		(start 93.575 145.175)
		(end 94.167934 145.175)
		(width 0.1)
		(layer "In5.Cu")
		(net 475)
	)
	(segment
		(start 94.388931 145.068573)
		(end 94.422607 145.014978)
		(width 0.1)
		(layer "In5.Cu")
		(net 475)
	)
	(segment
		(start 93.049106 144.383694)
		(end 93.067663 144.377201)
		(width 0.1)
		(layer "In5.Cu")
		(net 475)
	)
	(segment
		(start 94.4506 144.857665)
		(end 94.443512 144.794766)
		(width 0.1)
		(layer "In5.Cu")
		(net 475)
	)
	(segment
		(start 94.388931 144.681426)
		(end 94.344173 144.636668)
		(width 0.1)
		(layer "In5.Cu")
		(net 475)
	)
	(segment
		(start 93.475 144.10383)
		(end 93.475 132.375)
		(width 0.1)
		(layer "In5.Cu")
		(net 475)
	)
	(segment
		(start 93.477507 145.252747)
		(end 93.484903 145.231611)
		(width 0.1)
		(layer "In5.Cu")
		(net 475)
	)
	(segment
		(start 93.41584 144.272901)
		(end 93.448146 144.221486)
		(width 0.1)
		(layer "In5.Cu")
		(net 475)
	)
	(segment
		(start 94.443512 144.794766)
		(end 94.422607 144.735021)
		(width 0.1)
		(layer "In5.Cu")
		(net 475)
	)
	(segment
		(start 93.264172 144.368201)
		(end 93.321487 144.348145)
		(width 0.1)
		(layer "In5.Cu")
		(net 475)
	)
	(segment
		(start 93.512651 145.196816)
		(end 93.531611 145.184903)
		(width 0.1)
		(layer "In5.Cu")
		(net 475)
	)
	(segment
		(start 94.344173 144.636668)
		(end 94.290578 144.602992)
		(width 0.1)
		(layer "In5.Cu")
		(net 475)
	)
	(segment
		(start 94.344173 145.113331)
		(end 94.388931 145.068573)
		(width 0.1)
		(layer "In5.Cu")
		(net 475)
	)
	(segment
		(start 93.531611 145.184903)
		(end 93.552747 145.177507)
		(width 0.1)
		(layer "In5.Cu")
		(net 475)
	)
	(segment
		(start 93.475 132.375)
		(end 94.675 131.175)
		(width 0.1)
		(layer "In5.Cu")
		(net 475)
	)
	(segment
		(start 94.230833 145.167912)
		(end 94.290578 145.147007)
		(width 0.1)
		(layer "In5.Cu")
		(net 475)
	)
	(segment
		(start 94.675 131.175)
		(end 94.675 130.075)
		(width 0.1)
		(layer "In5.Cu")
		(net 475)
	)
	(segment
		(start 93.049106 144.566305)
		(end 93.032458 144.555844)
		(width 0.1)
		(layer "In5.Cu")
		(net 475)
	)
	(segment
		(start 93.018556 144.541942)
		(end 93.008095 144.525294)
		(width 0.1)
		(layer "In5.Cu")
		(net 475)
	)
	(segment
		(start 94.290578 145.147007)
		(end 94.344173 145.113331)
		(width 0.1)
		(layer "In5.Cu")
		(net 475)
	)
	(segment
		(start 94.167934 145.175)
		(end 94.230833 145.167912)
		(width 0.1)
		(layer "In5.Cu")
		(net 475)
	)
	(segment
		(start 93.0872 144.375)
		(end 93.203831 144.375)
		(width 0.1)
		(layer "In5.Cu")
		(net 475)
	)
	(segment
		(start 93.018556 144.408057)
		(end 93.032458 144.394155)
		(width 0.1)
		(layer "In5.Cu")
		(net 475)
	)
	(segment
		(start 94.4506 144.892334)
		(end 94.4506 144.857665)
		(width 0.1)
		(layer "In5.Cu")
		(net 475)
	)
	(segment
		(start 93.0872 144.575)
		(end 93.067663 144.572798)
		(width 0.1)
		(layer "In5.Cu")
		(net 475)
	)
	(segment
		(start 93.067663 144.377201)
		(end 93.0872 144.375)
		(width 0.1)
		(layer "In5.Cu")
		(net 475)
	)
	(segment
		(start 93.448146 144.221486)
		(end 93.468202 144.164171)
		(width 0.1)
		(layer "In5.Cu")
		(net 475)
	)
	(segment
		(start 94.167934 144.575)
		(end 93.0872 144.575)
		(width 0.1)
		(layer "In5.Cu")
		(net 475)
	)
	(segment
		(start 93.775 146.175014)
		(end 93.475 145.875014)
		(width 0.1)
		(layer "In5.Cu")
		(net 475)
	)
	(segment
		(start 93.032458 144.555844)
		(end 93.018556 144.541942)
		(width 0.1)
		(layer "In5.Cu")
		(net 475)
	)
	(segment
		(start 94.422607 144.735021)
		(end 94.388931 144.681426)
		(width 0.1)
		(layer "In5.Cu")
		(net 475)
	)
	(segment
		(start 93.321487 144.348145)
		(end 93.372902 144.315839)
		(width 0.1)
		(layer "In5.Cu")
		(net 475)
	)
	(segment
		(start 94.290578 144.602992)
		(end 94.230833 144.582087)
		(width 0.1)
		(layer "In5.Cu")
		(net 475)
	)
	(segment
		(start 94.230833 144.582087)
		(end 94.167934 144.575)
		(width 0.1)
		(layer "In5.Cu")
		(net 475)
	)
	(segment
		(start 93.552747 145.177507)
		(end 93.575 145.175)
		(width 0.1)
		(layer "In5.Cu")
		(net 475)
	)
	(segment
		(start 94.422607 145.014978)
		(end 94.443512 144.955233)
		(width 0.1)
		(layer "In5.Cu")
		(net 475)
	)
	(segment
		(start 93.001602 144.506737)
		(end 92.9994 144.4872)
		(width 0.1)
		(layer "In5.Cu")
		(net 475)
	)
	(segment
		(start 93.203831 144.375)
		(end 93.264172 144.368201)
		(width 0.1)
		(layer "In5.Cu")
		(net 475)
	)
	(segment
		(start 94.675 130.075)
		(end 94.275 129.675)
		(width 0.1)
		(layer "In5.Cu")
		(net 475)
	)
	(segment
		(start 93.008095 144.424705)
		(end 93.018556 144.408057)
		(width 0.1)
		(layer "In5.Cu")
		(net 475)
	)
	(segment
		(start 93.032458 144.394155)
		(end 93.049106 144.383694)
		(width 0.1)
		(layer "In5.Cu")
		(net 475)
	)
	(segment
		(start 93.475 145.875014)
		(end 93.475 145.275)
		(width 0.1)
		(layer "In5.Cu")
		(net 475)
	)
	(segment
		(start 94.443512 144.955233)
		(end 94.4506 144.892334)
		(width 0.1)
		(layer "In5.Cu")
		(net 475)
	)
	(segment
		(start 92.9994 144.4628)
		(end 93.001602 144.443262)
		(width 0.1)
		(layer "In5.Cu")
		(net 475)
	)
	(segment
		(start 93.001602 144.443262)
		(end 93.008095 144.424705)
		(width 0.1)
		(layer "In5.Cu")
		(net 475)
	)
	(segment
		(start 93.496816 145.212651)
		(end 93.512651 145.196816)
		(width 0.1)
		(layer "In5.Cu")
		(net 475)
	)
	(segment
		(start 93.475 145.275)
		(end 93.477507 145.252747)
		(width 0.1)
		(layer "In5.Cu")
		(net 475)
	)
	(segment
		(start 93.484903 145.231611)
		(end 93.496816 145.212651)
		(width 0.1)
		(layer "In5.Cu")
		(net 475)
	)
	(segment
		(start 93.067663 144.572798)
		(end 93.049106 144.566305)
		(width 0.1)
		(layer "In5.Cu")
		(net 475)
	)
	(segment
		(start 98.775 129.175)
		(end 98.374968 129.575032)
		(width 0.15)
		(layer "F.Cu")
		(net 476)
	)
	(segment
		(start 96.975 148.775)
		(end 96.575 148.375)
		(width 0.1)
		(layer "F.Cu")
		(net 476)
	)
	(segment
		(start 98.374968 129.575032)
		(end 98.374968 129.67501)
		(width 0.15)
		(layer "F.Cu")
		(net 476)
	)
	(via blind
		(at 96.575 148.375)
		(size 0.5)
		(drill 0.2)
		(layers "F.Cu" "In5.Cu")
		(net 476)
	)
	(via blind
		(at 98.374968 129.67501)
		(size 0.5)
		(drill 0.2)
		(layers "F.Cu" "In5.Cu")
		(net 476)
	)
	(segment
		(start 98.575 131.575)
		(end 98.257665 131.575)
		(width 0.1)
		(layer "In5.Cu")
		(net 476)
	)
	(segment
		(start 97.346494 148.132182)
		(end 97.366668 148.122467)
		(width 0.1)
		(layer "In5.Cu")
		(net 476)
	)
	(segment
		(start 97.398678 148.437318)
		(end 97.40366 148.415487)
		(width 0.1)
		(layer "In5.Cu")
		(net 476)
	)
	(segment
		(start 98.637348 130.153183)
		(end 98.653183 130.137348)
		(width 0.1)
		(layer "In5.Cu")
		(net 476)
	)
	(segment
		(start 97.300324 148.228051)
		(end 97.300325 148.205657)
		(width 0.1)
		(layer "In5.Cu")
		(net 476)
	)
	(segment
		(start 98.194766 130.182087)
		(end 98.257665 130.175)
		(width 0.1)
		(layer "In5.Cu")
		(net 476)
	)
	(segment
		(start 97.300325 148.205657)
		(end 97.305308 148.183826)
		(width 0.1)
		(layer "In5.Cu")
		(net 476)
	)
	(segment
		(start 98.257665 130.975)
		(end 98.975 130.975)
		(width 0.1)
		(layer "In5.Cu")
		(net 476)
	)
	(segment
		(start 97.4529 148.132182)
		(end 97.470407 148.146144)
		(width 0.1)
		(layer "In5.Cu")
		(net 476)
	)
	(segment
		(start 97.982087 131.194766)
		(end 98.002992 131.135021)
		(width 0.1)
		(layer "In5.Cu")
		(net 476)
	)
	(segment
		(start 97.982087 130.555233)
		(end 97.975 130.492334)
		(width 0.1)
		(layer "In5.Cu")
		(net 476)
	)
	(segment
		(start 97.375 148.475)
		(end 97.388961 148.457494)
		(width 0.1)
		(layer "In5.Cu")
		(net 476)
	)
	(segment
		(start 98.675 129.975042)
		(end 98.374968 129.67501)
		(width 0.1)
		(layer "In5.Cu")
		(net 476)
	)
	(segment
		(start 98.081426 131.036668)
		(end 98.135021 131.002992)
		(width 0.1)
		(layer "In5.Cu")
		(net 476)
	)
	(segment
		(start 98.036668 130.668573)
		(end 98.002992 130.614978)
		(width 0.1)
		(layer "In5.Cu")
		(net 476)
	)
	(segment
		(start 98.036668 131.468573)
		(end 98.002992 131.414978)
		(width 0.1)
		(layer "In5.Cu")
		(net 476)
	)
	(segment
		(start 98.036668 131.081426)
		(end 98.081426 131.036668)
		(width 0.1)
		(layer "In5.Cu")
		(net 476)
	)
	(segment
		(start 97.470407 148.146144)
		(end 97.516422 148.192159)
		(width 0.1)
		(layer "In5.Cu")
		(net 476)
	)
	(segment
		(start 98.081426 130.713331)
		(end 98.036668 130.668573)
		(width 0.1)
		(layer "In5.Cu")
		(net 476)
	)
	(segment
		(start 98.081426 131.513331)
		(end 98.036668 131.468573)
		(width 0.1)
		(layer "In5.Cu")
		(net 476)
	)
	(segment
		(start 97.388501 148.117483)
		(end 97.410893 148.117484)
		(width 0.1)
		(layer "In5.Cu")
		(net 476)
	)
	(segment
		(start 98.675 130.075)
		(end 98.675 129.975042)
		(width 0.1)
		(layer "In5.Cu")
		(net 476)
	)
	(segment
		(start 97.975 130.457665)
		(end 97.982087 130.394766)
		(width 0.1)
		(layer "In5.Cu")
		(net 476)
	)
	(segment
		(start 98.194766 130.767912)
		(end 98.135021 130.747007)
		(width 0.1)
		(layer "In5.Cu")
		(net 476)
	)
	(segment
		(start 96.575 148.375)
		(end 96.775 148.575)
		(width 0.1)
		(layer "In5.Cu")
		(net 476)
	)
	(segment
		(start 97.554106 148.215836)
		(end 97.575937 148.22082)
		(width 0.1)
		(layer "In5.Cu")
		(net 476)
	)
	(segment
		(start 97.640336 148.206121)
		(end 97.657844 148.192159)
		(width 0.1)
		(layer "In5.Cu")
		(net 476)
	)
	(segment
		(start 97.275 148.575)
		(end 97.375 148.475)
		(width 0.1)
		(layer "In5.Cu")
		(net 476)
	)
	(segment
		(start 98.135021 130.747007)
		(end 98.081426 130.713331)
		(width 0.1)
		(layer "In5.Cu")
		(net 476)
	)
	(segment
		(start 97.982087 130.394766)
		(end 98.002992 130.335021)
		(width 0.1)
		(layer "In5.Cu")
		(net 476)
	)
	(segment
		(start 97.975 131.257665)
		(end 97.982087 131.194766)
		(width 0.1)
		(layer "In5.Cu")
		(net 476)
	)
	(segment
		(start 97.366668 148.122467)
		(end 97.388501 148.117483)
		(width 0.1)
		(layer "In5.Cu")
		(net 476)
	)
	(segment
		(start 97.305308 148.183826)
		(end 97.315023 148.163652)
		(width 0.1)
		(layer "In5.Cu")
		(net 476)
	)
	(segment
		(start 98.036668 130.281426)
		(end 98.081426 130.236668)
		(width 0.1)
		(layer "In5.Cu")
		(net 476)
	)
	(segment
		(start 97.657844 148.192159)
		(end 97.622486 148.227514)
		(width 0.1)
		(layer "In5.Cu")
		(net 476)
	)
	(segment
		(start 98.672492 130.097252)
		(end 98.675 130.075)
		(width 0.1)
		(layer "In5.Cu")
		(net 476)
	)
	(segment
		(start 98.637348 131.596816)
		(end 98.618388 131.584903)
		(width 0.1)
		(layer "In5.Cu")
		(net 476)
	)
	(segment
		(start 98.653183 130.137348)
		(end 98.665096 130.118388)
		(width 0.1)
		(layer "In5.Cu")
		(net 476)
	)
	(segment
		(start 97.403661 148.393093)
		(end 97.398678 148.371262)
		(width 0.1)
		(layer "In5.Cu")
		(net 476)
	)
	(segment
		(start 97.620162 148.215836)
		(end 97.640336 148.206121)
		(width 0.1)
		(layer "In5.Cu")
		(net 476)
	)
	(segment
		(start 97.410893 148.117484)
		(end 97.432724 148.122467)
		(width 0.1)
		(layer "In5.Cu")
		(net 476)
	)
	(segment
		(start 98.194766 130.982087)
		(end 98.257665 130.975)
		(width 0.1)
		(layer "In5.Cu")
		(net 476)
	)
	(segment
		(start 97.398678 148.371262)
		(end 97.388961 148.351088)
		(width 0.1)
		(layer "In5.Cu")
		(net 476)
	)
	(segment
		(start 97.975 130.492334)
		(end 97.975 130.457665)
		(width 0.1)
		(layer "In5.Cu")
		(net 476)
	)
	(segment
		(start 97.598331 148.220819)
		(end 97.620162 148.215836)
		(width 0.1)
		(layer "In5.Cu")
		(net 476)
	)
	(segment
		(start 98.002992 131.414978)
		(end 97.982087 131.355233)
		(width 0.1)
		(layer "In5.Cu")
		(net 476)
	)
	(segment
		(start 98.257665 130.775)
		(end 98.194766 130.767912)
		(width 0.1)
		(layer "In5.Cu")
		(net 476)
	)
	(segment
		(start 98.597252 131.577507)
		(end 98.575 131.575)
		(width 0.1)
		(layer "In5.Cu")
		(net 476)
	)
	(segment
		(start 98.975 130.975)
		(end 98.975 130.775)
		(width 0.1)
		(layer "In5.Cu")
		(net 476)
	)
	(segment
		(start 98.135021 131.002992)
		(end 98.194766 130.982087)
		(width 0.1)
		(layer "In5.Cu")
		(net 476)
	)
	(segment
		(start 98.618388 131.584903)
		(end 98.597252 131.577507)
		(width 0.1)
		(layer "In5.Cu")
		(net 476)
	)
	(segment
		(start 97.516422 148.192159)
		(end 97.53393 148.206121)
		(width 0.1)
		(layer "In5.Cu")
		(net 476)
	)
	(segment
		(start 97.388961 148.351088)
		(end 97.374999 148.33358)
		(width 0.1)
		(layer "In5.Cu")
		(net 476)
	)
	(segment
		(start 97.982087 131.355233)
		(end 97.975 131.292334)
		(width 0.1)
		(layer "In5.Cu")
		(net 476)
	)
	(segment
		(start 97.315023 148.163652)
		(end 97.328985 148.146144)
		(width 0.1)
		(layer "In5.Cu")
		(net 476)
	)
	(segment
		(start 97.40366 148.415487)
		(end 97.403661 148.393093)
		(width 0.1)
		(layer "In5.Cu")
		(net 476)
	)
	(segment
		(start 96.775 148.575)
		(end 97.275 148.575)
		(width 0.1)
		(layer "In5.Cu")
		(net 476)
	)
	(segment
		(start 98.672492 131.652747)
		(end 98.665096 131.631611)
		(width 0.1)
		(layer "In5.Cu")
		(net 476)
	)
	(segment
		(start 97.622486 148.227514)
		(end 98.675 147.175)
		(width 0.1)
		(layer "In5.Cu")
		(net 476)
	)
	(segment
		(start 98.002992 130.614978)
		(end 97.982087 130.555233)
		(width 0.1)
		(layer "In5.Cu")
		(net 476)
	)
	(segment
		(start 98.675 131.675)
		(end 98.672492 131.652747)
		(width 0.1)
		(layer "In5.Cu")
		(net 476)
	)
	(segment
		(start 98.618388 130.165096)
		(end 98.637348 130.153183)
		(width 0.1)
		(layer "In5.Cu")
		(net 476)
	)
	(segment
		(start 98.257665 130.175)
		(end 98.575 130.175)
		(width 0.1)
		(layer "In5.Cu")
		(net 476)
	)
	(segment
		(start 98.975 130.775)
		(end 98.257665 130.775)
		(width 0.1)
		(layer "In5.Cu")
		(net 476)
	)
	(segment
		(start 98.653183 131.612651)
		(end 98.637348 131.596816)
		(width 0.1)
		(layer "In5.Cu")
		(net 476)
	)
	(segment
		(start 97.388961 148.457494)
		(end 97.398678 148.437318)
		(width 0.1)
		(layer "In5.Cu")
		(net 476)
	)
	(segment
		(start 98.194766 131.567912)
		(end 98.135021 131.547007)
		(width 0.1)
		(layer "In5.Cu")
		(net 476)
	)
	(segment
		(start 98.081426 130.236668)
		(end 98.135021 130.202992)
		(width 0.1)
		(layer "In5.Cu")
		(net 476)
	)
	(segment
		(start 97.328985 148.287566)
		(end 97.315023 148.270058)
		(width 0.1)
		(layer "In5.Cu")
		(net 476)
	)
	(segment
		(start 97.328985 148.146144)
		(end 97.346494 148.132182)
		(width 0.1)
		(layer "In5.Cu")
		(net 476)
	)
	(segment
		(start 98.665096 131.631611)
		(end 98.653183 131.612651)
		(width 0.1)
		(layer "In5.Cu")
		(net 476)
	)
	(segment
		(start 97.315023 148.270058)
		(end 97.305308 148.249882)
		(width 0.1)
		(layer "In5.Cu")
		(net 476)
	)
	(segment
		(start 98.665096 130.118388)
		(end 98.672492 130.097252)
		(width 0.1)
		(layer "In5.Cu")
		(net 476)
	)
	(segment
		(start 97.975 131.292334)
		(end 97.975 131.257665)
		(width 0.1)
		(layer "In5.Cu")
		(net 476)
	)
	(segment
		(start 98.002992 131.135021)
		(end 98.036668 131.081426)
		(width 0.1)
		(layer "In5.Cu")
		(net 476)
	)
	(segment
		(start 98.675 147.175)
		(end 98.675 131.675)
		(width 0.1)
		(layer "In5.Cu")
		(net 476)
	)
	(segment
		(start 98.135021 130.202992)
		(end 98.194766 130.182087)
		(width 0.1)
		(layer "In5.Cu")
		(net 476)
	)
	(segment
		(start 97.575937 148.22082)
		(end 97.598331 148.220819)
		(width 0.1)
		(layer "In5.Cu")
		(net 476)
	)
	(segment
		(start 98.597252 130.172492)
		(end 98.618388 130.165096)
		(width 0.1)
		(layer "In5.Cu")
		(net 476)
	)
	(segment
		(start 97.432724 148.122467)
		(end 97.4529 148.132182)
		(width 0.1)
		(layer "In5.Cu")
		(net 476)
	)
	(segment
		(start 98.257665 131.575)
		(end 98.194766 131.567912)
		(width 0.1)
		(layer "In5.Cu")
		(net 476)
	)
	(segment
		(start 97.374999 148.33358)
		(end 97.328985 148.287566)
		(width 0.1)
		(layer "In5.Cu")
		(net 476)
	)
	(segment
		(start 97.53393 148.206121)
		(end 97.554106 148.215836)
		(width 0.1)
		(layer "In5.Cu")
		(net 476)
	)
	(segment
		(start 97.305308 148.249882)
		(end 97.300324 148.228051)
		(width 0.1)
		(layer "In5.Cu")
		(net 476)
	)
	(segment
		(start 98.002992 130.335021)
		(end 98.036668 130.281426)
		(width 0.1)
		(layer "In5.Cu")
		(net 476)
	)
	(segment
		(start 98.575 130.175)
		(end 98.597252 130.172492)
		(width 0.1)
		(layer "In5.Cu")
		(net 476)
	)
	(segment
		(start 98.135021 131.547007)
		(end 98.081426 131.513331)
		(width 0.1)
		(layer "In5.Cu")
		(net 476)
	)
	(segment
		(start 99.275 129.675)
		(end 99.174979 129.675)
		(width 0.15)
		(layer "F.Cu")
		(net 477)
	)
	(segment
		(start 96.175 148.775)
		(end 96.575 149.175)
		(width 0.1)
		(layer "F.Cu")
		(net 477)
	)
	(segment
		(start 99.775 129.175)
		(end 99.275 129.675)
		(width 0.15)
		(layer "F.Cu")
		(net 477)
	)
	(via blind
		(at 96.575 149.175)
		(size 0.5)
		(drill 0.2)
		(layers "F.Cu" "In5.Cu")
		(net 477)
	)
	(via blind
		(at 99.174979 129.675)
		(size 0.5)
		(drill 0.2)
		(layers "F.Cu" "In5.Cu")
		(net 477)
	)
	(segment
		(start 98.231611 130.565096)
		(end 98.252747 130.572492)
		(width 0.1)
		(layer "In5.Cu")
		(net 477)
	)
	(segment
		(start 99.175 130.986556)
		(end 99.170276 131.028489)
		(width 0.1)
		(layer "In5.Cu")
		(net 477)
	)
	(segment
		(start 98.875 131.657665)
		(end 98.875 147.257858)
		(width 0.1)
		(layer "In5.Cu")
		(net 477)
	)
	(segment
		(start 98.813331 131.481426)
		(end 98.847007 131.535021)
		(width 0.1)
		(layer "In5.Cu")
		(net 477)
	)
	(segment
		(start 96.875 148.875)
		(end 96.575 149.175)
		(width 0.1)
		(layer "In5.Cu")
		(net 477)
	)
	(segment
		(start 98.212651 131.196816)
		(end 98.196816 131.212651)
		(width 0.1)
		(layer "In5.Cu")
		(net 477)
	)
	(segment
		(start 98.196816 131.337348)
		(end 98.212651 131.353183)
		(width 0.1)
		(layer "In5.Cu")
		(net 477)
	)
	(segment
		(start 98.867912 130.155233)
		(end 98.847007 130.214978)
		(width 0.1)
		(layer "In5.Cu")
		(net 477)
	)
	(segment
		(start 98.177507 131.252747)
		(end 98.175 131.275)
		(width 0.1)
		(layer "In5.Cu")
		(net 477)
	)
	(segment
		(start 98.177507 130.452747)
		(end 98.175 130.475)
		(width 0.1)
		(layer "In5.Cu")
		(net 477)
	)
	(segment
		(start 98.231611 131.365096)
		(end 98.252747 131.372492)
		(width 0.1)
		(layer "In5.Cu")
		(net 477)
	)
	(segment
		(start 98.655233 130.367912)
		(end 98.592334 130.375)
		(width 0.1)
		(layer "In5.Cu")
		(net 477)
	)
	(segment
		(start 98.986557 131.175)
		(end 98.275 131.175)
		(width 0.1)
		(layer "In5.Cu")
		(net 477)
	)
	(segment
		(start 98.184903 130.518388)
		(end 98.196816 130.537348)
		(width 0.1)
		(layer "In5.Cu")
		(net 477)
	)
	(segment
		(start 99.10405 131.133887)
		(end 99.06832 131.156338)
		(width 0.1)
		(layer "In5.Cu")
		(net 477)
	)
	(segment
		(start 98.847007 130.214978)
		(end 98.813331 130.268573)
		(width 0.1)
		(layer "In5.Cu")
		(net 477)
	)
	(segment
		(start 99.133888 130.64595)
		(end 99.156339 130.68168)
		(width 0.1)
		(layer "In5.Cu")
		(net 477)
	)
	(segment
		(start 98.184903 131.231611)
		(end 98.177507 131.252747)
		(width 0.1)
		(layer "In5.Cu")
		(net 477)
	)
	(segment
		(start 99.170276 130.72151)
		(end 99.175 130.763443)
		(width 0.1)
		(layer "In5.Cu")
		(net 477)
	)
	(segment
		(start 98.252747 131.372492)
		(end 98.275 131.375)
		(width 0.1)
		(layer "In5.Cu")
		(net 477)
	)
	(segment
		(start 99.170276 131.028489)
		(end 99.156339 131.068319)
		(width 0.1)
		(layer "In5.Cu")
		(net 477)
	)
	(segment
		(start 98.275 131.375)
		(end 98.592334 131.375)
		(width 0.1)
		(layer "In5.Cu")
		(net 477)
	)
	(segment
		(start 98.177507 131.297252)
		(end 98.184903 131.318388)
		(width 0.1)
		(layer "In5.Cu")
		(net 477)
	)
	(segment
		(start 98.252747 131.177507)
		(end 98.231611 131.184903)
		(width 0.1)
		(layer "In5.Cu")
		(net 477)
	)
	(segment
		(start 99.02849 131.170275)
		(end 98.986557 131.175)
		(width 0.1)
		(layer "In5.Cu")
		(net 477)
	)
	(segment
		(start 98.875 130.092334)
		(end 98.867912 130.155233)
		(width 0.1)
		(layer "In5.Cu")
		(net 477)
	)
	(segment
		(start 98.867912 131.594766)
		(end 98.875 131.657665)
		(width 0.1)
		(layer "In5.Cu")
		(net 477)
	)
	(segment
		(start 99.174979 129.675)
		(end 98.875 129.974979)
		(width 0.1)
		(layer "In5.Cu")
		(net 477)
	)
	(segment
		(start 98.252747 130.377507)
		(end 98.231611 130.384903)
		(width 0.1)
		(layer "In5.Cu")
		(net 477)
	)
	(segment
		(start 98.714978 130.347007)
		(end 98.655233 130.367912)
		(width 0.1)
		(layer "In5.Cu")
		(net 477)
	)
	(segment
		(start 98.196816 130.412651)
		(end 98.184903 130.431611)
		(width 0.1)
		(layer "In5.Cu")
		(net 477)
	)
	(segment
		(start 98.275 130.575)
		(end 98.986557 130.575)
		(width 0.1)
		(layer "In5.Cu")
		(net 477)
	)
	(segment
		(start 98.714978 131.402992)
		(end 98.768573 131.436668)
		(width 0.1)
		(layer "In5.Cu")
		(net 477)
	)
	(segment
		(start 98.212651 130.396816)
		(end 98.196816 130.412651)
		(width 0.1)
		(layer "In5.Cu")
		(net 477)
	)
	(segment
		(start 98.175 131.275)
		(end 98.177507 131.297252)
		(width 0.1)
		(layer "In5.Cu")
		(net 477)
	)
	(segment
		(start 98.275 130.375)
		(end 98.252747 130.377507)
		(width 0.1)
		(layer "In5.Cu")
		(net 477)
	)
	(segment
		(start 99.10405 130.616112)
		(end 99.133888 130.64595)
		(width 0.1)
		(layer "In5.Cu")
		(net 477)
	)
	(segment
		(start 98.184903 131.318388)
		(end 98.196816 131.337348)
		(width 0.1)
		(layer "In5.Cu")
		(net 477)
	)
	(segment
		(start 98.252747 130.572492)
		(end 98.275 130.575)
		(width 0.1)
		(layer "In5.Cu")
		(net 477)
	)
	(segment
		(start 98.813331 130.268573)
		(end 98.768573 130.313331)
		(width 0.1)
		(layer "In5.Cu")
		(net 477)
	)
	(segment
		(start 98.986557 130.575)
		(end 99.02849 130.579724)
		(width 0.1)
		(layer "In5.Cu")
		(net 477)
	)
	(segment
		(start 97.257858 148.875)
		(end 96.875 148.875)
		(width 0.1)
		(layer "In5.Cu")
		(net 477)
	)
	(segment
		(start 99.02849 130.579724)
		(end 99.06832 130.593661)
		(width 0.1)
		(layer "In5.Cu")
		(net 477)
	)
	(segment
		(start 99.06832 130.593661)
		(end 99.10405 130.616112)
		(width 0.1)
		(layer "In5.Cu")
		(net 477)
	)
	(segment
		(start 98.275 131.175)
		(end 98.252747 131.177507)
		(width 0.1)
		(layer "In5.Cu")
		(net 477)
	)
	(segment
		(start 98.768573 131.436668)
		(end 98.813331 131.481426)
		(width 0.1)
		(layer "In5.Cu")
		(net 477)
	)
	(segment
		(start 98.768573 130.313331)
		(end 98.714978 130.347007)
		(width 0.1)
		(layer "In5.Cu")
		(net 477)
	)
	(segment
		(start 98.655233 131.382087)
		(end 98.714978 131.402992)
		(width 0.1)
		(layer "In5.Cu")
		(net 477)
	)
	(segment
		(start 98.592334 130.375)
		(end 98.275 130.375)
		(width 0.1)
		(layer "In5.Cu")
		(net 477)
	)
	(segment
		(start 98.212651 131.353183)
		(end 98.231611 131.365096)
		(width 0.1)
		(layer "In5.Cu")
		(net 477)
	)
	(segment
		(start 98.184903 130.431611)
		(end 98.177507 130.452747)
		(width 0.1)
		(layer "In5.Cu")
		(net 477)
	)
	(segment
		(start 98.592334 131.375)
		(end 98.655233 131.382087)
		(width 0.1)
		(layer "In5.Cu")
		(net 477)
	)
	(segment
		(start 99.133888 131.104049)
		(end 99.10405 131.133887)
		(width 0.1)
		(layer "In5.Cu")
		(net 477)
	)
	(segment
		(start 98.231611 131.184903)
		(end 98.212651 131.196816)
		(width 0.1)
		(layer "In5.Cu")
		(net 477)
	)
	(segment
		(start 98.175 130.475)
		(end 98.177507 130.497252)
		(width 0.1)
		(layer "In5.Cu")
		(net 477)
	)
	(segment
		(start 99.156339 130.68168)
		(end 99.170276 130.72151)
		(width 0.1)
		(layer "In5.Cu")
		(net 477)
	)
	(segment
		(start 99.156339 131.068319)
		(end 99.133888 131.104049)
		(width 0.1)
		(layer "In5.Cu")
		(net 477)
	)
	(segment
		(start 98.875 147.257858)
		(end 97.257858 148.875)
		(width 0.1)
		(layer "In5.Cu")
		(net 477)
	)
	(segment
		(start 98.196816 130.537348)
		(end 98.212651 130.553183)
		(width 0.1)
		(layer "In5.Cu")
		(net 477)
	)
	(segment
		(start 98.231611 130.384903)
		(end 98.212651 130.396816)
		(width 0.1)
		(layer "In5.Cu")
		(net 477)
	)
	(segment
		(start 98.212651 130.553183)
		(end 98.231611 130.565096)
		(width 0.1)
		(layer "In5.Cu")
		(net 477)
	)
	(segment
		(start 99.06832 131.156338)
		(end 99.02849 131.170275)
		(width 0.1)
		(layer "In5.Cu")
		(net 477)
	)
	(segment
		(start 98.847007 131.535021)
		(end 98.867912 131.594766)
		(width 0.1)
		(layer "In5.Cu")
		(net 477)
	)
	(segment
		(start 98.177507 130.497252)
		(end 98.184903 130.518388)
		(width 0.1)
		(layer "In5.Cu")
		(net 477)
	)
	(segment
		(start 98.196816 131.212651)
		(end 98.184903 131.231611)
		(width 0.1)
		(layer "In5.Cu")
		(net 477)
	)
	(segment
		(start 99.175 130.763443)
		(end 99.175 130.986556)
		(width 0.1)
		(layer "In5.Cu")
		(net 477)
	)
	(segment
		(start 98.875 129.974979)
		(end 98.875 130.092334)
		(width 0.1)
		(layer "In5.Cu")
		(net 477)
	)
	(segment
		(start 99.375 145.575)
		(end 99.075 145.875)
		(width 0.1)
		(layer "F.Cu")
		(net 478)
	)
	(segment
		(start 99.89839 146.07499)
		(end 100.6984 146.875)
		(width 0.1)
		(layer "F.Cu")
		(net 478)
	)
	(segment
		(start 103.775 127.175)
		(end 104.275 127.675)
		(width 0.15)
		(layer "F.Cu")
		(net 478)
	)
	(segment
		(start 104.721447 146.875)
		(end 104.921447 146.675)
		(width 0.1)
		(layer "F.Cu")
		(net 478)
	)
	(segment
		(start 99.075 145.992144)
		(end 99.157846 146.07499)
		(width 0.1)
		(layer "F.Cu")
		(net 478)
	)
	(segment
		(start 99.075 145.875)
		(end 99.075 145.992144)
		(width 0.1)
		(layer "F.Cu")
		(net 478)
	)
	(segment
		(start 99.157846 146.07499)
		(end 99.89839 146.07499)
		(width 0.1)
		(layer "F.Cu")
		(net 478)
	)
	(segment
		(start 100.6984 146.875)
		(end 104.721447 146.875)
		(width 0.1)
		(layer "F.Cu")
		(net 478)
	)
	(segment
		(start 104.921447 146.675)
		(end 105.275 146.675)
		(width 0.1)
		(layer "F.Cu")
		(net 478)
	)
	(via blind
		(at 104.275 127.675)
		(size 0.5)
		(drill 0.2)
		(layers "F.Cu" "In5.Cu")
		(net 478)
	)
	(via
		(at 105.275 146.675)
		(size 0.5)
		(drill 0.2)
		(layers "F.Cu" "B.Cu")
		(net 478)
	)
	(segment
		(start 105.074 147.375)
		(end 105.275 147.174)
		(width 0.15)
		(layer "B.Cu")
		(net 478)
	)
	(segment
		(start 105.074 147.79)
		(end 105.074 147.375)
		(width 0.15)
		(layer "B.Cu")
		(net 478)
	)
	(segment
		(start 105.275 147.174)
		(end 105.275 146.675)
		(width 0.15)
		(layer "B.Cu")
		(net 478)
	)
	(segment
		(start 104.575 141.875)
		(end 104.575 145.275)
		(width 0.1)
		(layer "In5.Cu")
		(net 478)
	)
	(segment
		(start 104.275 141.575)
		(end 104.575 141.875)
		(width 0.1)
		(layer "In5.Cu")
		(net 478)
	)
	(segment
		(start 105.375 146.575)
		(end 105.275 146.675)
		(width 0.1)
		(layer "In5.Cu")
		(net 478)
	)
	(segment
		(start 104.275 127.675)
		(end 104.275 141.575)
		(width 0.1)
		(layer "In5.Cu")
		(net 478)
	)
	(segment
		(start 105.375 146.075)
		(end 105.375 146.575)
		(width 0.1)
		(layer "In5.Cu")
		(net 478)
	)
	(segment
		(start 104.575 145.275)
		(end 105.375 146.075)
		(width 0.1)
		(layer "In5.Cu")
		(net 478)
	)
	(segment
		(start 99.815544 146.275)
		(end 100.615544 147.075)
		(width 0.1)
		(layer "F.Cu")
		(net 479)
	)
	(segment
		(start 98.875 145.875)
		(end 98.875 146.075)
		(width 0.1)
		(layer "F.Cu")
		(net 479)
	)
	(segment
		(start 98.875 146.075)
		(end 99.075 146.275)
		(width 0.1)
		(layer "F.Cu")
		(net 479)
	)
	(segment
		(start 99.075 146.275)
		(end 99.815544 146.275)
		(width 0.1)
		(layer "F.Cu")
		(net 479)
	)
	(segment
		(start 100.615544 147.075)
		(end 105.475013 147.075)
		(width 0.1)
		(layer "F.Cu")
		(net 479)
	)
	(segment
		(start 103.775 126.175)
		(end 104.275 126.675)
		(width 0.15)
		(layer "F.Cu")
		(net 479)
	)
	(segment
		(start 98.575 145.575)
		(end 98.875 145.875)
		(width 0.1)
		(layer "F.Cu")
		(net 479)
	)
	(segment
		(start 105.475013 147.075)
		(end 105.875013 146.675)
		(width 0.1)
		(layer "F.Cu")
		(net 479)
	)
	(via blind
		(at 104.275 126.675)
		(size 0.5)
		(drill 0.2)
		(layers "F.Cu" "In5.Cu")
		(net 479)
	)
	(via
		(at 105.875013 146.675)
		(size 0.5)
		(drill 0.2)
		(layers "F.Cu" "B.Cu")
		(net 479)
	)
	(segment
		(start 105.875013 147.176013)
		(end 105.875013 146.675)
		(width 0.15)
		(layer "B.Cu")
		(net 479)
	)
	(segment
		(start 106.074 147.375)
		(end 105.875013 147.176013)
		(width 0.15)
		(layer "B.Cu")
		(net 479)
	)
	(segment
		(start 106.074 147.79)
		(end 106.074 147.375)
		(width 0.15)
		(layer "B.Cu")
		(net 479)
	)
	(segment
		(start 104.775 141.792144)
		(end 104.775011 145.192153)
		(width 0.1)
		(layer "In5.Cu")
		(net 479)
	)
	(segment
		(start 104.47501 141.492154)
		(end 104.775 141.792144)
		(width 0.1)
		(layer "In5.Cu")
		(net 479)
	)
	(segment
		(start 104.77501 127.87499)
		(end 104.47501 128.17499)
		(width 0.1)
		(layer "In5.Cu")
		(net 479)
	)
	(segment
		(start 105.875013 146.675)
		(end 105.625014 146.425001)
		(width 0.1)
		(layer "In5.Cu")
		(net 479)
	)
	(segment
		(start 104.775011 145.192153)
		(end 105.575 145.975)
		(width 0.1)
		(layer "In5.Cu")
		(net 479)
	)
	(segment
		(start 105.625014 146.425001)
		(end 105.625014 146.025014)
		(width 0.1)
		(layer "In5.Cu")
		(net 479)
	)
	(segment
		(start 105.625014 146.025014)
		(end 105.575 145.975)
		(width 0.1)
		(layer "In5.Cu")
		(net 479)
	)
	(segment
		(start 104.275 126.675)
		(end 104.77501 127.17501)
		(width 0.1)
		(layer "In5.Cu")
		(net 479)
	)
	(segment
		(start 104.77501 127.17501)
		(end 104.77501 127.87499)
		(width 0.1)
		(layer "In5.Cu")
		(net 479)
	)
	(segment
		(start 104.47501 128.17499)
		(end 104.47501 141.492154)
		(width 0.1)
		(layer "In5.Cu")
		(net 479)
	)
	(segment
		(start 90.775 127.175)
		(end 91.275 127.675)
		(width 0.15)
		(layer "F.Cu")
		(net 489)
	)
	(via blind
		(at 91.275 127.675)
		(size 0.5)
		(drill 0.2)
		(layers "F.Cu" "In5.Cu")
		(net 489)
	)
	(via
		(at 95.74 160.385)
		(size 0.5)
		(drill 0.2)
		(layers "F.Cu" "B.Cu")
		(net 489)
	)
	(segment
		(start 95.74 160.385)
		(end 95.51 160.615)
		(width 0.15)
		(layer "B.Cu")
		(net 489)
	)
	(segment
		(start 95.51 160.615)
		(end 95.51 161.605)
		(width 0.15)
		(layer "B.Cu")
		(net 489)
	)
	(segment
		(start 95.51 161.605)
		(end 95.885 161.98)
		(width 0.15)
		(layer "B.Cu")
		(net 489)
	)
	(segment
		(start 95.625009 158.778733)
		(end 94.541276 157.695)
		(width 0.11)
		(layer "In5.Cu")
		(net 489)
	)
	(segment
		(start 88.935 154.035)
		(end 88.935 128.155)
		(width 0.11)
		(layer "In5.Cu")
		(net 489)
	)
	(segment
		(start 94.541276 157.695)
		(end 92.595 157.695)
		(width 0.11)
		(layer "In5.Cu")
		(net 489)
	)
	(segment
		(start 95.625 159.043838)
		(end 95.625009 159.043829)
		(width 0.11)
		(layer "In5.Cu")
		(net 489)
	)
	(segment
		(start 95.77 160.385)
		(end 95.77 159.93)
		(width 0.11)
		(layer "In5.Cu")
		(net 489)
	)
	(segment
		(start 92.595 157.695)
		(end 88.935 154.035)
		(width 0.11)
		(layer "In5.Cu")
		(net 489)
	)
	(segment
		(start 88.935 128.155)
		(end 89.735 127.355)
		(width 0.11)
		(layer "In5.Cu")
		(net 489)
	)
	(segment
		(start 95.77 159.93)
		(end 95.625 159.785)
		(width 0.11)
		(layer "In5.Cu")
		(net 489)
	)
	(segment
		(start 95.625 159.785)
		(end 95.625 159.043838)
		(width 0.11)
		(layer "In5.Cu")
		(net 489)
	)
	(segment
		(start 89.735 127.355)
		(end 90.955 127.355)
		(width 0.11)
		(layer "In5.Cu")
		(net 489)
	)
	(segment
		(start 90.955 127.355)
		(end 91.275 127.675)
		(width 0.11)
		(layer "In5.Cu")
		(net 489)
	)
	(segment
		(start 95.625009 159.043829)
		(end 95.625009 158.778733)
		(width 0.11)
		(layer "In5.Cu")
		(net 489)
	)
	(segment
		(start 91.775 127.175)
		(end 91.275 126.675)
		(width 0.15)
		(layer "F.Cu")
		(net 490)
	)
	(via blind
		(at 91.275 126.675)
		(size 0.5)
		(drill 0.2)
		(layers "F.Cu" "In5.Cu")
		(net 490)
	)
	(via
		(at 95.03 160.385)
		(size 0.5)
		(drill 0.2)
		(layers "F.Cu" "B.Cu")
		(net 490)
	)
	(segment
		(start 95.03 160.385)
		(end 95.26 160.615)
		(width 0.15)
		(layer "B.Cu")
		(net 490)
	)
	(segment
		(start 95.26 161.605)
		(end 94.885 161.98)
		(width 0.15)
		(layer "B.Cu")
		(net 490)
	)
	(segment
		(start 95.26 160.615)
		(end 95.26 161.605)
		(width 0.15)
		(layer "B.Cu")
		(net 490)
	)
	(segment
		(start 95.06 160.385)
		(end 95.06 160)
		(width 0.11)
		(layer "In5.Cu")
		(net 490)
	)
	(segment
		(start 88.615 128.008724)
		(end 89.608724 127.015)
		(width 0.11)
		(layer "In5.Cu")
		(net 490)
	)
	(segment
		(start 94.408724 158.015)
		(end 92.415 158.015)
		(width 0.11)
		(layer "In5.Cu")
		(net 490)
	)
	(segment
		(start 92.415 158.015)
		(end 88.615 154.215)
		(width 0.11)
		(layer "In5.Cu")
		(net 490)
	)
	(segment
		(start 89.608724 127.015)
		(end 90.935 127.015)
		(width 0.11)
		(layer "In5.Cu")
		(net 490)
	)
	(segment
		(start 95.305 158.911276)
		(end 94.408724 158.015)
		(width 0.11)
		(layer "In5.Cu")
		(net 490)
	)
	(segment
		(start 95.06 160)
		(end 95.305 159.755)
		(width 0.11)
		(layer "In5.Cu")
		(net 490)
	)
	(segment
		(start 88.615 154.215)
		(end 88.615 128.008724)
		(width 0.11)
		(layer "In5.Cu")
		(net 490)
	)
	(segment
		(start 90.935 127.015)
		(end 91.275 126.675)
		(width 0.11)
		(layer "In5.Cu")
		(net 490)
	)
	(segment
		(start 95.305 159.755)
		(end 95.305 158.911276)
		(width 0.11)
		(layer "In5.Cu")
		(net 490)
	)
	(segment
		(start 83.86 112.68)
		(end 92.28 112.68)
		(width 0.15)
		(layer "F.Cu")
		(net 503)
	)
	(segment
		(start 92.28 112.68)
		(end 92.775 113.175)
		(width 0.15)
		(layer "F.Cu")
		(net 503)
	)
	(segment
		(start 94.775 110.185)
		(end 94.275 109.685)
		(width 0.15)
		(layer "F.Cu")
		(net 521)
	)
	(segment
		(start 71.415 167.38)
		(end 71.415 164.265)
		(width 0.15)
		(layer "F.Cu")
		(net 521)
	)
	(segment
		(start 71.415 164.265)
		(end 71.215 164.065)
		(width 0.15)
		(layer "F.Cu")
		(net 521)
	)
	(via blind
		(at 94.275 109.685)
		(size 0.5)
		(drill 0.2)
		(layers "F.Cu" "In5.Cu")
		(net 521)
	)
	(via
		(at 71.215 164.065)
		(size 0.5)
		(drill 0.2)
		(layers "F.Cu" "B.Cu")
		(net 521)
	)
	(segment
		(start 93.785013 110.174987)
		(end 90.16227 110.174987)
		(width 0.15)
		(layer "In5.Cu")
		(net 521)
	)
	(segment
		(start 94.275 109.685)
		(end 93.785013 110.174987)
		(width 0.15)
		(layer "In5.Cu")
		(net 521)
	)
	(segment
		(start 78.550047 156.729953)
		(end 71.215 164.065)
		(width 0.15)
		(layer "In5.Cu")
		(net 521)
	)
	(segment
		(start 90.16227 110.174987)
		(end 78.550047 121.78721)
		(width 0.15)
		(layer "In5.Cu")
		(net 521)
	)
	(segment
		(start 78.550047 121.78721)
		(end 78.550047 156.729953)
		(width 0.15)
		(layer "In5.Cu")
		(net 521)
	)
	(segment
		(start 92.54 161.59)
		(end 92.425 161.475)
		(width 0.15)
		(layer "F.Cu")
		(net 522)
	)
	(segment
		(start 92.425 159.725)
		(end 90.275 157.575)
		(width 0.15)
		(layer "F.Cu")
		(net 522)
	)
	(segment
		(start 77.899902 155.647132)
		(end 88.400685 155.647132)
		(width 0.15)
		(layer "F.Cu")
		(net 522)
	)
	(segment
		(start 94.775 109.185)
		(end 94.275 108.685)
		(width 0.15)
		(layer "F.Cu")
		(net 522)
	)
	(segment
		(start 90.275 157.575)
		(end 88.400685 155.647132)
		(width 0.15)
		(layer "F.Cu")
		(net 522)
	)
	(segment
		(start 92.425 161.475)
		(end 92.425 159.725)
		(width 0.15)
		(layer "F.Cu")
		(net 522)
	)
	(via blind
		(at 77.899902 155.647132)
		(size 0.5)
		(drill 0.2)
		(layers "F.Cu" "In2.Cu")
		(net 522)
	)
	(via
		(at 92.54 161.59)
		(size 0.5)
		(drill 0.2)
		(layers "F.Cu" "B.Cu")
		(net 522)
	)
	(via blind
		(at 94.275 108.685)
		(size 0.5)
		(drill 0.2)
		(layers "F.Cu" "In2.Cu")
		(net 522)
	)
	(segment
		(start 92.54 161.59)
		(end 92.46 161.51)
		(width 0.15)
		(layer "B.Cu")
		(net 522)
	)
	(segment
		(start 92.46 161.51)
		(end 92.46 160.875)
		(width 0.15)
		(layer "B.Cu")
		(net 522)
	)
	(segment
		(start 94.275 108.685)
		(end 89.165 108.685)
		(width 0.15)
		(layer "In2.Cu")
		(net 522)
	)
	(segment
		(start 89.165 108.685)
		(end 77.899902 119.950098)
		(width 0.15)
		(layer "In2.Cu")
		(net 522)
	)
	(segment
		(start 77.899902 119.950098)
		(end 77.899902 155.647132)
		(width 0.15)
		(layer "In2.Cu")
		(net 522)
	)
	(segment
		(start 90.775 115.175)
		(end 91.275 114.675)
		(width 0.15)
		(layer "F.Cu")
		(net 523)
	)
	(segment
		(start 83.275 123.075)
		(end 83.19 123.16)
		(width 0.15)
		(layer "F.Cu")
		(net 523)
	)
	(segment
		(start 83.275 122.375)
		(end 83.275 123.075)
		(width 0.15)
		(layer "F.Cu")
		(net 523)
	)
	(via blind
		(at 91.275 114.675)
		(size 0.5)
		(drill 0.2)
		(layers "F.Cu" "In2.Cu")
		(net 523)
	)
	(via blind
		(at 83.275 122.375)
		(size 0.5)
		(drill 0.2)
		(layers "F.Cu" "In2.Cu")
		(net 523)
	)
	(segment
		(start 91.275 114.675)
		(end 91.085 114.865)
		(width 0.15)
		(layer "In2.Cu")
		(net 523)
	)
	(segment
		(start 88.536444 114.865)
		(end 83.275 120.126444)
		(width 0.15)
		(layer "In2.Cu")
		(net 523)
	)
	(segment
		(start 83.275 120.126444)
		(end 83.275 122.375)
		(width 0.15)
		(layer "In2.Cu")
		(net 523)
	)
	(segment
		(start 91.085 114.865)
		(end 88.536444 114.865)
		(width 0.15)
		(layer "In2.Cu")
		(net 523)
	)
	(segment
		(start 81.575 122.48)
		(end 81.575 121.775)
		(width 0.15)
		(layer "F.Cu")
		(net 524)
	)
	(segment
		(start 81.19 122.865)
		(end 81.575 122.48)
		(width 0.15)
		(layer "F.Cu")
		(net 524)
	)
	(segment
		(start 94.775 115.175)
		(end 94.275 115.675)
		(width 0.15)
		(layer "F.Cu")
		(net 524)
	)
	(segment
		(start 81.19 123.16)
		(end 81.19 122.865)
		(width 0.15)
		(layer "F.Cu")
		(net 524)
	)
	(via blind
		(at 81.575 121.775)
		(size 0.5)
		(drill 0.2)
		(layers "F.Cu" "In2.Cu")
		(net 524)
	)
	(via blind
		(at 94.275 115.675)
		(size 0.5)
		(drill 0.2)
		(layers "F.Cu" "In2.Cu")
		(net 524)
	)
	(segment
		(start 88.185 114.365)
		(end 88.175 114.375)
		(width 0.15)
		(layer "In2.Cu")
		(net 524)
	)
	(segment
		(start 94.275 115.675)
		(end 94.275 115.575)
		(width 0.15)
		(layer "In2.Cu")
		(net 524)
	)
	(segment
		(start 91.05501 113.87499)
		(end 90.565 114.365)
		(width 0.15)
		(layer "In2.Cu")
		(net 524)
	)
	(segment
		(start 90.565 114.365)
		(end 88.185 114.365)
		(width 0.15)
		(layer "In2.Cu")
		(net 524)
	)
	(segment
		(start 92.57499 113.87499)
		(end 91.05501 113.87499)
		(width 0.15)
		(layer "In2.Cu")
		(net 524)
	)
	(segment
		(start 94.275 115.575)
		(end 92.57499 113.87499)
		(width 0.15)
		(layer "In2.Cu")
		(net 524)
	)
	(segment
		(start 81.575 120.977888)
		(end 81.575 121.775)
		(width 0.15)
		(layer "In2.Cu")
		(net 524)
	)
	(segment
		(start 88.175 114.375)
		(end 81.575 120.977888)
		(width 0.15)
		(layer "In2.Cu")
		(net 524)
	)
	(segment
		(start 82.175 122.375)
		(end 82.175 123.145)
		(width 0.15)
		(layer "F.Cu")
		(net 525)
	)
	(segment
		(start 93.775 115.175)
		(end 93.275 115.675)
		(width 0.15)
		(layer "F.Cu")
		(net 525)
	)
	(segment
		(start 82.175 123.145)
		(end 82.19 123.16)
		(width 0.15)
		(layer "F.Cu")
		(net 525)
	)
	(via blind
		(at 82.175 122.375)
		(size 0.5)
		(drill 0.2)
		(layers "F.Cu" "In2.Cu")
		(net 525)
	)
	(via blind
		(at 93.275 115.675)
		(size 0.5)
		(drill 0.2)
		(layers "F.Cu" "In2.Cu")
		(net 525)
	)
	(segment
		(start 91.105 114.225)
		(end 92.525 114.225)
		(width 0.15)
		(layer "In2.Cu")
		(net 525)
	)
	(segment
		(start 88.362168 114.615)
		(end 90.715 114.615)
		(width 0.15)
		(layer "In2.Cu")
		(net 525)
	)
	(segment
		(start 82.175 120.802168)
		(end 88.362168 114.615)
		(width 0.15)
		(layer "In2.Cu")
		(net 525)
	)
	(segment
		(start 93.275 114.975)
		(end 93.275 115.675)
		(width 0.15)
		(layer "In2.Cu")
		(net 525)
	)
	(segment
		(start 82.175 122.375)
		(end 82.175 120.802168)
		(width 0.15)
		(layer "In2.Cu")
		(net 525)
	)
	(segment
		(start 92.525 114.225)
		(end 93.275 114.975)
		(width 0.15)
		(layer "In2.Cu")
		(net 525)
	)
	(segment
		(start 90.715 114.615)
		(end 91.105 114.225)
		(width 0.15)
		(layer "In2.Cu")
		(net 525)
	)
	(segment
		(start 91.775 115.175)
		(end 92.275 114.675)
		(width 0.15)
		(layer "F.Cu")
		(net 526)
	)
	(segment
		(start 84.175 123.145)
		(end 84.19 123.16)
		(width 0.15)
		(layer "F.Cu")
		(net 526)
	)
	(segment
		(start 84.175 122.375)
		(end 84.175 123.145)
		(width 0.15)
		(layer "F.Cu")
		(net 526)
	)
	(via blind
		(at 92.275 114.675)
		(size 0.5)
		(drill 0.2)
		(layers "F.Cu" "In2.Cu")
		(net 526)
	)
	(via blind
		(at 84.175 122.375)
		(size 0.5)
		(drill 0.2)
		(layers "F.Cu" "In2.Cu")
		(net 526)
	)
	(segment
		(start 88.699999 115.150001)
		(end 89.199999 115.150001)
		(width 0.15)
		(layer "In2.Cu")
		(net 526)
	)
	(segment
		(start 89.214998 115.165)
		(end 89.199999 115.150001)
		(width 0.15)
		(layer "In2.Cu")
		(net 526)
	)
	(segment
		(start 92.275 114.675)
		(end 91.785 115.165)
		(width 0.15)
		(layer "In2.Cu")
		(net 526)
	)
	(segment
		(start 84.175 119.675)
		(end 84.175 122.375)
		(width 0.15)
		(layer "In2.Cu")
		(net 526)
	)
	(segment
		(start 91.785 115.165)
		(end 89.214998 115.165)
		(width 0.15)
		(layer "In2.Cu")
		(net 526)
	)
	(segment
		(start 88.699999 115.150001)
		(end 84.175 119.675)
		(width 0.15)
		(layer "In2.Cu")
		(net 526)
	)
	(segment
		(start 133 158.125)
		(end 133.35 158.475)
		(width 0.15)
		(layer "F.Cu")
		(net 527)
	)
	(segment
		(start 133.35 158.475)
		(end 136.475 158.475)
		(width 0.15)
		(layer "F.Cu")
		(net 527)
	)
	(segment
		(start 133 157.2)
		(end 133 158.125)
		(width 0.15)
		(layer "F.Cu")
		(net 527)
	)
	(segment
		(start 136.475 158.475)
		(end 137.825 157.125)
		(width 0.15)
		(layer "F.Cu")
		(net 527)
	)
	(segment
		(start 137.825 157.125)
		(end 138.575 157.125)
		(width 0.15)
		(layer "F.Cu")
		(net 527)
	)
	(segment
		(start 95.775 123.175)
		(end 95.275 122.675)
		(width 0.15)
		(layer "F.Cu")
		(net 533)
	)
	(via
		(at 95.275 122.675)
		(size 0.5)
		(drill 0.2)
		(layers "F.Cu" "B.Cu")
		(net 533)
	)
	(segment
		(start 94.56 122.675)
		(end 95.275 122.675)
		(width 0.15)
		(layer "B.Cu")
		(net 533)
	)
	(segment
		(start 86.3 76.005)
		(end 86.25 76.055)
		(width 0.15)
		(layer "F.Cu")
		(net 534)
	)
	(segment
		(start 88.4 76.38)
		(end 88.400001 76.780001)
		(width 0.15)
		(layer "F.Cu")
		(net 534)
	)
	(segment
		(start 86.285 76.84)
		(end 86.3 76.855)
		(width 0.15)
		(layer "F.Cu")
		(net 534)
	)
	(segment
		(start 88.400001 76.780001)
		(end 88.400001 77.08)
		(width 0.15)
		(layer "F.Cu")
		(net 534)
	)
	(segment
		(start 86.235 76.07)
		(end 86.25 76.055)
		(width 0.15)
		(layer "F.Cu")
		(net 534)
	)
	(segment
		(start 86.3 75.35)
		(end 86.3 76.005)
		(width 0.15)
		(layer "F.Cu")
		(net 534)
	)
	(segment
		(start 86.295 76.85)
		(end 86.3 76.855)
		(width 0.25)
		(layer "F.Cu")
		(net 534)
	)
	(segment
		(start 86.235 76.755)
		(end 86.235 76.07)
		(width 0.15)
		(layer "F.Cu")
		(net 534)
	)
	(via
		(at 86.25 76.055)
		(size 0.5)
		(drill 0.2)
		(layers "F.Cu" "B.Cu")
		(net 534)
	)
	(via
		(at 88.400001 77.08)
		(size 0.5)
		(drill 0.2)
		(layers "F.Cu" "B.Cu")
		(net 534)
	)
	(segment
		(start 87.375001 76.055)
		(end 88.400001 77.08)
		(width 0.15)
		(layer "B.Cu")
		(net 534)
	)
	(segment
		(start 86.25 76.055)
		(end 87.375001 76.055)
		(width 0.15)
		(layer "B.Cu")
		(net 534)
	)
	(segment
		(start 86.32 82.775)
		(end 86.32 83.3)
		(width 0.25)
		(layer "F.Cu")
		(net 538)
	)
	(segment
		(start 86.32 83.25)
		(end 86.095 83.475)
		(width 0.25)
		(layer "F.Cu")
		(net 538)
	)
	(segment
		(start 71.765 165.115)
		(end 73 166.35)
		(width 0.15)
		(layer "F.Cu")
		(net 538)
	)
	(segment
		(start 70.515 161.815)
		(end 70.515 162.345)
		(width 0.15)
		(layer "F.Cu")
		(net 538)
	)
	(segment
		(start 71.765 163.595)
		(end 71.765 165.115)
		(width 0.15)
		(layer "F.Cu")
		(net 538)
	)
	(segment
		(start 73 166.35)
		(end 73.515 166.35)
		(width 0.15)
		(layer "F.Cu")
		(net 538)
	)
	(segment
		(start 70.515 162.345)
		(end 71.765 163.595)
		(width 0.15)
		(layer "F.Cu")
		(net 538)
	)
	(via
		(at 86.095 83.475)
		(size 0.5)
		(drill 0.2)
		(layers "F.Cu" "B.Cu")
		(net 538)
	)
	(via
		(at 70.515 161.815)
		(size 0.5)
		(drill 0.2)
		(layers "F.Cu" "B.Cu")
		(net 538)
	)
	(segment
		(start 86.095 82.595)
		(end 86.095 83.475)
		(width 0.15)
		(layer "B.Cu")
		(net 538)
	)
	(segment
		(start 82.466 81.366)
		(end 82.525 81.425)
		(width 0.15)
		(layer "B.Cu")
		(net 538)
	)
	(segment
		(start 82.525 81.425)
		(end 84.925 81.425)
		(width 0.15)
		(layer "B.Cu")
		(net 538)
	)
	(segment
		(start 84.925 81.425)
		(end 86.095 82.595)
		(width 0.15)
		(layer "B.Cu")
		(net 538)
	)
	(segment
		(start 82.466 80.3)
		(end 82.466 81.366)
		(width 0.15)
		(layer "B.Cu")
		(net 538)
	)
	(segment
		(start 72.027001 159.898997)
		(end 72.027001 160.302999)
		(width 0.15)
		(layer "In5.Cu")
		(net 538)
	)
	(segment
		(start 72.265 159.660998)
		(end 72.027001 159.898997)
		(width 0.15)
		(layer "In5.Cu")
		(net 538)
	)
	(segment
		(start 82.970001 90.665997)
		(end 82.970001 114.869999)
		(width 0.15)
		(layer "In5.Cu")
		(net 538)
	)
	(segment
		(start 86.095 87.540998)
		(end 82.970001 90.665997)
		(width 0.15)
		(layer "In5.Cu")
		(net 538)
	)
	(segment
		(start 70.515 161.815)
		(end 72.027001 160.302999)
		(width 0.15)
		(layer "In5.Cu")
		(net 538)
	)
	(segment
		(start 82.970001 114.869999)
		(end 76.735 121.105)
		(width 0.15)
		(layer "In5.Cu")
		(net 538)
	)
	(segment
		(start 76.735 121.105)
		(end 76.735 140.12)
		(width 0.15)
		(layer "In5.Cu")
		(net 538)
	)
	(segment
		(start 72.265 145.685)
		(end 72.265 159.660998)
		(width 0.15)
		(layer "In5.Cu")
		(net 538)
	)
	(segment
		(start 86.095 83.475)
		(end 86.095 87.540998)
		(width 0.15)
		(layer "In5.Cu")
		(net 538)
	)
	(segment
		(start 76.735 140.12)
		(end 72.925 143.93)
		(width 0.15)
		(layer "In5.Cu")
		(net 538)
	)
	(segment
		(start 72.925 143.93)
		(end 72.925 145.025)
		(width 0.15)
		(layer "In5.Cu")
		(net 538)
	)
	(segment
		(start 72.925 145.025)
		(end 72.265 145.685)
		(width 0.15)
		(layer "In5.Cu")
		(net 538)
	)
	(segment
		(start 79.915 109.515)
		(end 79.915 109.915)
		(width 0.15)
		(layer "F.Cu")
		(net 559)
	)
	(segment
		(start 79.915 109.515)
		(end 79.915 110.1525)
		(width 0.15)
		(layer "F.Cu")
		(net 559)
	)
	(segment
		(start 77.415 144.34)
		(end 76.665 144.34)
		(width 0.15)
		(layer "F.Cu")
		(net 559)
	)
	(segment
		(start 80.858587 108.249979)
		(end 79.915 109.193566)
		(width 0.15)
		(layer "F.Cu")
		(net 559)
	)
	(segment
		(start 79.915 109.193566)
		(end 79.915 109.515)
		(width 0.15)
		(layer "F.Cu")
		(net 559)
	)
	(segment
		(start 79.572 154.35212)
		(end 79.572 146.497)
		(width 0.15)
		(layer "F.Cu")
		(net 559)
	)
	(segment
		(start 79.915 110.1525)
		(end 79.9025 110.165)
		(width 0.15)
		(layer "F.Cu")
		(net 559)
	)
	(segment
		(start 79.572 146.497)
		(end 77.415 144.34)
		(width 0.15)
		(layer "F.Cu")
		(net 559)
	)
	(segment
		(start 80.858587 108.249979)
		(end 91.849979 108.249979)
		(width 0.15)
		(layer "F.Cu")
		(net 559)
	)
	(segment
		(start 92.775 109.175)
		(end 91.849979 108.249979)
		(width 0.15)
		(layer "F.Cu")
		(net 559)
	)
	(via
		(at 76.665 144.34)
		(size 0.5)
		(drill 0.2)
		(layers "F.Cu" "B.Cu")
		(net 559)
	)
	(via
		(at 79.9025 110.165)
		(size 0.5)
		(drill 0.2)
		(layers "F.Cu" "B.Cu")
		(net 559)
	)
	(segment
		(start 79.9025 112.738198)
		(end 76.41499 116.225708)
		(width 0.15)
		(layer "B.Cu")
		(net 559)
	)
	(segment
		(start 76.239999 142.990001)
		(end 76.41499 142.81501)
		(width 0.15)
		(layer "B.Cu")
		(net 559)
	)
	(segment
		(start 76.239999 143.914999)
		(end 76.239999 142.990001)
		(width 0.15)
		(layer "B.Cu")
		(net 559)
	)
	(segment
		(start 76.41499 118.98999)
		(end 76.41499 118.69)
		(width 0.15)
		(layer "B.Cu")
		(net 559)
	)
	(segment
		(start 76.665 144.34)
		(end 76.239999 143.914999)
		(width 0.15)
		(layer "B.Cu")
		(net 559)
	)
	(segment
		(start 76.41499 116.225708)
		(end 76.41499 118.98999)
		(width 0.15)
		(layer "B.Cu")
		(net 559)
	)
	(segment
		(start 76.41499 118.69)
		(end 76.41499 126.49001)
		(width 0.15)
		(layer "B.Cu")
		(net 559)
	)
	(segment
		(start 76.41499 142.81501)
		(end 76.41499 118.98999)
		(width 0.15)
		(layer "B.Cu")
		(net 559)
	)
	(segment
		(start 79.9025 110.165)
		(end 79.9025 112.738198)
		(width 0.15)
		(layer "B.Cu")
		(net 559)
	)
	(segment
		(start 81.030011 108.499989)
		(end 91.728991 108.499989)
		(width 0.15)
		(layer "F.Cu")
		(net 560)
	)
	(segment
		(start 92.24 110.64)
		(end 92.24 109.010998)
		(width 0.15)
		(layer "F.Cu")
		(net 560)
	)
	(segment
		(start 80.34 109.19)
		(end 80.34 109.429804)
		(width 0.15)
		(layer "F.Cu")
		(net 560)
	)
	(segment
		(start 81.030011 108.499989)
		(end 80.34 109.19)
		(width 0.15)
		(layer "F.Cu")
		(net 560)
	)
	(segment
		(start 80.072 154.35212)
		(end 80.072 146.022)
		(width 0.15)
		(layer "F.Cu")
		(net 560)
	)
	(segment
		(start 92.24 109.010998)
		(end 91.728991 108.499989)
		(width 0.15)
		(layer "F.Cu")
		(net 560)
	)
	(segment
		(start 77.59 143.54)
		(end 76.665 143.54)
		(width 0.15)
		(layer "F.Cu")
		(net 560)
	)
	(segment
		(start 80.072 146.022)
		(end 77.59 143.54)
		(width 0.15)
		(layer "F.Cu")
		(net 560)
	)
	(segment
		(start 92.775 111.175)
		(end 92.24 110.64)
		(width 0.15)
		(layer "F.Cu")
		(net 560)
	)
	(via
		(at 80.34 109.604804)
		(size 0.5)
		(drill 0.2)
		(layers "F.Cu" "B.Cu")
		(net 560)
	)
	(via
		(at 76.665 143.54)
		(size 0.5)
		(drill 0.2)
		(layers "F.Cu" "B.Cu")
		(net 560)
	)
	(segment
		(start 80.34 109.604804)
		(end 80.34 110.49)
		(width 0.15)
		(layer "B.Cu")
		(net 560)
	)
	(segment
		(start 80.34 110.49)
		(end 80.15251 110.67749)
		(width 0.15)
		(layer "B.Cu")
		(net 560)
	)
	(segment
		(start 76.665 116.329264)
		(end 80.15251 112.841754)
		(width 0.15)
		(layer "B.Cu")
		(net 560)
	)
	(segment
		(start 76.665 143.54)
		(end 76.665 116.329264)
		(width 0.15)
		(layer "B.Cu")
		(net 560)
	)
	(segment
		(start 80.15251 110.67749)
		(end 80.15251 112.841754)
		(width 0.15)
		(layer "B.Cu")
		(net 560)
	)
	(segment
		(start 93.775 109.175)
		(end 92.599969 107.999969)
		(width 0.15)
		(layer "F.Cu")
		(net 561)
	)
	(segment
		(start 79.072 146.897)
		(end 77.315 145.14)
		(width 0.15)
		(layer "F.Cu")
		(net 561)
	)
	(segment
		(start 79.428021 109.326979)
		(end 79.428021 109.528021)
		(width 0.15)
		(layer "F.Cu")
		(net 561)
	)
	(segment
		(start 79.072 154.35212)
		(end 79.072 146.897)
		(width 0.15)
		(layer "F.Cu")
		(net 561)
	)
	(segment
		(start 77.315 145.14)
		(end 76.665 145.14)
		(width 0.15)
		(layer "F.Cu")
		(net 561)
	)
	(segment
		(start 80.755031 107.999969)
		(end 79.428021 109.326979)
		(width 0.15)
		(layer "F.Cu")
		(net 561)
	)
	(segment
		(start 80.755031 107.999969)
		(end 92.599969 107.999969)
		(width 0.15)
		(layer "F.Cu")
		(net 561)
	)
	(via
		(at 79.3775 109.604804)
		(size 0.5)
		(drill 0.2)
		(layers "F.Cu" "B.Cu")
		(net 561)
	)
	(via
		(at 76.665 145.14)
		(size 0.5)
		(drill 0.2)
		(layers "F.Cu" "B.Cu")
		(net 561)
	)
	(segment
		(start 79.3775 109.604804)
		(end 79.3775 112.909632)
		(width 0.15)
		(layer "B.Cu")
		(net 561)
	)
	(segment
		(start 76.16498 142.675717)
		(end 76.16498 116.122152)
		(width 0.15)
		(layer "B.Cu")
		(net 561)
	)
	(segment
		(start 76.16498 116.122152)
		(end 79.3775 112.909632)
		(width 0.15)
		(layer "B.Cu")
		(net 561)
	)
	(segment
		(start 75.915 142.925697)
		(end 76.16498 142.675717)
		(width 0.15)
		(layer "B.Cu")
		(net 561)
	)
	(segment
		(start 76.665 145.14)
		(end 75.915 144.39)
		(width 0.15)
		(layer "B.Cu")
		(net 561)
	)
	(segment
		(start 75.915 144.39)
		(end 75.915 142.925697)
		(width 0.15)
		(layer "B.Cu")
		(net 561)
	)
	(segment
		(start 82.34 156.965)
		(end 83.603694 156.965)
		(width 0.15)
		(layer "F.Cu")
		(net 562)
	)
	(segment
		(start 79.54 156.965)
		(end 82.34 156.965)
		(width 0.15)
		(layer "F.Cu")
		(net 562)
	)
	(segment
		(start 90.775 111.175)
		(end 90.435 111.515)
		(width 0.15)
		(layer "F.Cu")
		(net 562)
	)
	(segment
		(start 83.19 156.965)
		(end 83.29 156.965)
		(width 0.15)
		(layer "F.Cu")
		(net 562)
	)
	(segment
		(start 79.072 158.45122)
		(end 79.072 157.433)
		(width 0.15)
		(layer "F.Cu")
		(net 562)
	)
	(segment
		(start 80.89 111.515)
		(end 90.435 111.515)
		(width 0.15)
		(layer "F.Cu")
		(net 562)
	)
	(segment
		(start 79.072 157.433)
		(end 79.54 156.965)
		(width 0.15)
		(layer "F.Cu")
		(net 562)
	)
	(segment
		(start 82.34 156.965)
		(end 83.19 156.965)
		(width 0.15)
		(layer "F.Cu")
		(net 562)
	)
	(segment
		(start 80.89 111.515)
		(end 80.865 111.49)
		(width 0.15)
		(layer "F.Cu")
		(net 562)
	)
	(segment
		(start 83.603694 156.965)
		(end 83.765807 157.127113)
		(width 0.15)
		(layer "F.Cu")
		(net 562)
	)
	(via
		(at 83.765807 157.127113)
		(size 0.5)
		(drill 0.2)
		(layers "F.Cu" "B.Cu")
		(net 562)
	)
	(via
		(at 80.865 111.49)
		(size 0.5)
		(drill 0.2)
		(layers "F.Cu" "B.Cu")
		(net 562)
	)
	(segment
		(start 83.564489 149.218076)
		(end 77.16502 142.818607)
		(width 0.15)
		(layer "B.Cu")
		(net 562)
	)
	(segment
		(start 83.765807 157.127113)
		(end 83.765807 156.090807)
		(width 0.15)
		(layer "B.Cu")
		(net 562)
	)
	(segment
		(start 83.765807 156.090807)
		(end 83.564489 155.889489)
		(width 0.15)
		(layer "B.Cu")
		(net 562)
	)
	(segment
		(start 80.69 111.665)
		(end 80.865 111.49)
		(width 0.15)
		(layer "B.Cu")
		(net 562)
	)
	(segment
		(start 77.815008 115.889992)
		(end 77.815008 115.886388)
		(width 0.15)
		(layer "B.Cu")
		(net 562)
	)
	(segment
		(start 77.815008 115.886388)
		(end 80.69 113.011396)
		(width 0.15)
		(layer "B.Cu")
		(net 562)
	)
	(segment
		(start 77.79 115.915)
		(end 77.815008 115.889992)
		(width 0.15)
		(layer "B.Cu")
		(net 562)
	)
	(segment
		(start 83.564489 155.889489)
		(end 83.564489 149.218076)
		(width 0.15)
		(layer "B.Cu")
		(net 562)
	)
	(segment
		(start 80.69 113.011396)
		(end 80.69 111.665)
		(width 0.15)
		(layer "B.Cu")
		(net 562)
	)
	(segment
		(start 77.16502 142.818607)
		(end 77.16502 116.53998)
		(width 0.15)
		(layer "B.Cu")
		(net 562)
	)
	(segment
		(start 77.16502 116.53998)
		(end 77.79 115.915)
		(width 0.15)
		(layer "B.Cu")
		(net 562)
	)
	(segment
		(start 81.515 111.79)
		(end 81.115 112.19)
		(width 0.15)
		(layer "F.Cu")
		(net 563)
	)
	(segment
		(start 79.765 157.265)
		(end 83.291042 157.265)
		(width 0.15)
		(layer "F.Cu")
		(net 563)
	)
	(segment
		(start 90.775 112.175)
		(end 90.39 111.79)
		(width 0.15)
		(layer "F.Cu")
		(net 563)
	)
	(segment
		(start 83.291042 157.265)
		(end 83.753021 157.726979)
		(width 0.15)
		(layer "F.Cu")
		(net 563)
	)
	(segment
		(start 79.572 157.458)
		(end 79.765 157.265)
		(width 0.15)
		(layer "F.Cu")
		(net 563)
	)
	(segment
		(start 79.572 158.45122)
		(end 79.572 157.458)
		(width 0.15)
		(layer "F.Cu")
		(net 563)
	)
	(segment
		(start 81.515 111.79)
		(end 90.39 111.79)
		(width 0.15)
		(layer "F.Cu")
		(net 563)
	)
	(via
		(at 83.753021 157.726979)
		(size 0.5)
		(drill 0.2)
		(layers "F.Cu" "B.Cu")
		(net 563)
	)
	(via
		(at 81.115 112.19)
		(size 0.5)
		(drill 0.2)
		(layers "F.Cu" "B.Cu")
		(net 563)
	)
	(segment
		(start 83.814999 149.115018)
		(end 83.814999 155.590001)
		(width 0.15)
		(layer "B.Cu")
		(net 563)
	)
	(segment
		(start 77.415029 142.715048)
		(end 83.814999 149.115018)
		(width 0.15)
		(layer "B.Cu")
		(net 563)
	)
	(segment
		(start 83.814999 155.590001)
		(end 84.190808 155.96581)
		(width 0.15)
		(layer "B.Cu")
		(net 563)
	)
	(segment
		(start 84.190808 155.96581)
		(end 84.190808 157.514192)
		(width 0.15)
		(layer "B.Cu")
		(net 563)
	)
	(segment
		(start 83.978021 157.726979)
		(end 83.753021 157.726979)
		(width 0.15)
		(layer "B.Cu")
		(net 563)
	)
	(segment
		(start 84.190808 157.514192)
		(end 83.978021 157.726979)
		(width 0.15)
		(layer "B.Cu")
		(net 563)
	)
	(segment
		(start 81.115 112.943566)
		(end 77.415029 116.643537)
		(width 0.15)
		(layer "B.Cu")
		(net 563)
	)
	(segment
		(start 81.115 112.19)
		(end 81.115 112.943566)
		(width 0.15)
		(layer "B.Cu")
		(net 563)
	)
	(segment
		(start 77.415029 116.643537)
		(end 77.415029 142.715048)
		(width 0.15)
		(layer "B.Cu")
		(net 563)
	)
	(segment
		(start 84.296876 113.508126)
		(end 83.698501 113.508126)
		(width 0.15)
		(layer "F.Cu")
		(net 564)
	)
	(segment
		(start 84.630002 113.175)
		(end 84.296876 113.508126)
		(width 0.15)
		(layer "F.Cu")
		(net 564)
	)
	(segment
		(start 80.072 158.45122)
		(end 83.97878 158.45122)
		(width 0.15)
		(layer "F.Cu")
		(net 564)
	)
	(segment
		(start 90.775 113.175)
		(end 84.630002 113.175)
		(width 0.15)
		(layer "F.Cu")
		(net 564)
	)
	(segment
		(start 83.97878 158.45122)
		(end 84.228021 158.201979)
		(width 0.15)
		(layer "F.Cu")
		(net 564)
	)
	(via
		(at 83.698501 113.508126)
		(size 0.5)
		(drill 0.2)
		(layers "F.Cu" "B.Cu")
		(net 564)
	)
	(via
		(at 84.228021 158.201979)
		(size 0.5)
		(drill 0.2)
		(layers "F.Cu" "B.Cu")
		(net 564)
	)
	(segment
		(start 84.06501 155.486444)
		(end 84.06501 149.011461)
		(width 0.15)
		(layer "B.Cu")
		(net 564)
	)
	(segment
		(start 84.47802 155.899454)
		(end 84.06501 155.486444)
		(width 0.15)
		(layer "B.Cu")
		(net 564)
	)
	(segment
		(start 80.904006 113.508126)
		(end 77.66504 116.747092)
		(width 0.15)
		(layer "B.Cu")
		(net 564)
	)
	(segment
		(start 84.228021 158.201979)
		(end 84.47802 157.95198)
		(width 0.15)
		(layer "B.Cu")
		(net 564)
	)
	(segment
		(start 84.47802 157.95198)
		(end 84.47802 155.899454)
		(width 0.15)
		(layer "B.Cu")
		(net 564)
	)
	(segment
		(start 83.698501 113.508126)
		(end 80.904006 113.508126)
		(width 0.15)
		(layer "B.Cu")
		(net 564)
	)
	(segment
		(start 84.06501 149.011461)
		(end 77.66504 142.611491)
		(width 0.15)
		(layer "B.Cu")
		(net 564)
	)
	(segment
		(start 77.66504 116.747092)
		(end 77.66504 142.611491)
		(width 0.15)
		(layer "B.Cu")
		(net 564)
	)
	(segment
		(start 96.29 109.66)
		(end 96.29 109.060998)
		(width 0.15)
		(layer "F.Cu")
		(net 565)
	)
	(segment
		(start 93.193566 108.24)
		(end 92.703526 107.749959)
		(width 0.15)
		(layer "F.Cu")
		(net 565)
	)
	(segment
		(start 80.605041 107.749959)
		(end 78.84 109.515)
		(width 0.15)
		(layer "F.Cu")
		(net 565)
	)
	(segment
		(start 78.84 109.515)
		(end 78.84 109.94)
		(width 0.15)
		(layer "F.Cu")
		(net 565)
	)
	(segment
		(start 69.072 158.45122)
		(end 69.072 157.122)
		(width 0.15)
		(layer "F.Cu")
		(net 565)
	)
	(segment
		(start 95.775 110.175)
		(end 96.29 109.66)
		(width 0.15)
		(layer "F.Cu")
		(net 565)
	)
	(segment
		(start 92.703526 107.749959)
		(end 80.605041 107.749959)
		(width 0.15)
		(layer "F.Cu")
		(net 565)
	)
	(segment
		(start 93.193566 108.24)
		(end 95.469002 108.24)
		(width 0.15)
		(layer "F.Cu")
		(net 565)
	)
	(segment
		(start 96.29 109.060998)
		(end 95.469002 108.24)
		(width 0.15)
		(layer "F.Cu")
		(net 565)
	)
	(via
		(at 78.84 110.165)
		(size 0.5)
		(drill 0.2)
		(layers "F.Cu" "B.Cu")
		(net 565)
	)
	(via
		(at 69.072 157.122)
		(size 0.5)
		(drill 0.2)
		(layers "F.Cu" "B.Cu")
		(net 565)
	)
	(segment
		(start 75.91497 116.018596)
		(end 78.84 113.093566)
		(width 0.15)
		(layer "B.Cu")
		(net 565)
	)
	(segment
		(start 78.84 110.165)
		(end 78.84 113.093566)
		(width 0.15)
		(layer "B.Cu")
		(net 565)
	)
	(segment
		(start 69.09 157.104)
		(end 69.09 155.79)
		(width 0.15)
		(layer "B.Cu")
		(net 565)
	)
	(segment
		(start 75.565 149.315)
		(end 75.565 142.865)
		(width 0.15)
		(layer "B.Cu")
		(net 565)
	)
	(segment
		(start 75.91497 142.51503)
		(end 75.91497 116.018596)
		(width 0.15)
		(layer "B.Cu")
		(net 565)
	)
	(segment
		(start 75.565 142.865)
		(end 75.91497 142.51503)
		(width 0.15)
		(layer "B.Cu")
		(net 565)
	)
	(segment
		(start 69.072 157.122)
		(end 69.09 157.104)
		(width 0.15)
		(layer "B.Cu")
		(net 565)
	)
	(segment
		(start 69.09 155.79)
		(end 75.565 149.315)
		(width 0.15)
		(layer "B.Cu")
		(net 565)
	)
	(segment
		(start 96.775 108.725)
		(end 95.99 107.94)
		(width 0.15)
		(layer "F.Cu")
		(net 566)
	)
	(segment
		(start 69.072 154.34712)
		(end 69.072 153.053)
		(width 0.2)
		(layer "F.Cu")
		(net 566)
	)
	(segment
		(start 93.247132 107.94)
		(end 95.99 107.94)
		(width 0.15)
		(layer "F.Cu")
		(net 566)
	)
	(segment
		(start 80.405051 107.499949)
		(end 92.807083 107.499949)
		(width 0.15)
		(layer "F.Cu")
		(net 566)
	)
	(segment
		(start 69.072 153.053)
		(end 69.075 153.05)
		(width 0.2)
		(layer "F.Cu")
		(net 566)
	)
	(segment
		(start 80.405051 107.499949)
		(end 78.415 109.49)
		(width 0.15)
		(layer "F.Cu")
		(net 566)
	)
	(segment
		(start 93.247132 107.94)
		(end 92.807083 107.499949)
		(width 0.15)
		(layer "F.Cu")
		(net 566)
	)
	(segment
		(start 96.775 109.175)
		(end 96.775 108.725)
		(width 0.15)
		(layer "F.Cu")
		(net 566)
	)
	(via
		(at 69.075 153.05)
		(size 0.5)
		(drill 0.2)
		(layers "F.Cu" "B.Cu")
		(net 566)
	)
	(via
		(at 78.415 109.604804)
		(size 0.5)
		(drill 0.2)
		(layers "F.Cu" "B.Cu")
		(net 566)
	)
	(segment
		(start 69.075 153.05)
		(end 71.455 153.05)
		(width 0.15)
		(layer "B.Cu")
		(net 566)
	)
	(segment
		(start 71.455 153.05)
		(end 75.29 149.215)
		(width 0.15)
		(layer "B.Cu")
		(net 566)
	)
	(segment
		(start 75.29 149.215)
		(end 75.29 142.74)
		(width 0.15)
		(layer "B.Cu")
		(net 566)
	)
	(segment
		(start 75.29 142.74)
		(end 75.66496 142.36504)
		(width 0.15)
		(layer "B.Cu")
		(net 566)
	)
	(segment
		(start 75.66496 142.36504)
		(end 75.66496 115.91504)
		(width 0.15)
		(layer "B.Cu")
		(net 566)
	)
	(segment
		(start 75.66496 115.91504)
		(end 78.415 113.165)
		(width 0.15)
		(layer "B.Cu")
		(net 566)
	)
	(segment
		(start 78.415 109.604804)
		(end 78.415 113.165)
		(width 0.15)
		(layer "B.Cu")
		(net 566)
	)
	(segment
		(start 78.04 66.04)
		(end 78.2 66.2)
		(width 0.15)
		(layer "F.Cu")
		(net 573)
	)
	(segment
		(start 70.042 89.442)
		(end 70.539 88.945)
		(width 0.15)
		(layer "F.Cu")
		(net 573)
	)
	(segment
		(start 76.971 88.945)
		(end 78.459 87.457)
		(width 0.15)
		(layer "F.Cu")
		(net 573)
	)
	(segment
		(start 78.2 67.151)
		(end 78.265 67.216)
		(width 0.15)
		(layer "F.Cu")
		(net 573)
	)
	(segment
		(start 77.296 68.185)
		(end 78.265 67.216)
		(width 0.2)
		(layer "F.Cu")
		(net 573)
	)
	(segment
		(start 76.425294 68.313912)
		(end 77.071088 68.313912)
		(width 0.2)
		(layer "F.Cu")
		(net 573)
	)
	(segment
		(start 70.539 88.945)
		(end 76.971 88.945)
		(width 0.15)
		(layer "F.Cu")
		(net 573)
	)
	(segment
		(start 70.042 90.705143)
		(end 70.042 89.442)
		(width 0.15)
		(layer "F.Cu")
		(net 573)
	)
	(segment
		(start 78.2 66.2)
		(end 78.2 67.151)
		(width 0.15)
		(layer "F.Cu")
		(net 573)
	)
	(segment
		(start 78.459 87.457)
		(end 79.259 87.457)
		(width 0.15)
		(layer "F.Cu")
		(net 573)
	)
	(segment
		(start 70.539 88.945)
		(end 69.944 88.35)
		(width 0.15)
		(layer "F.Cu")
		(net 573)
	)
	(segment
		(start 69.944 88.35)
		(end 69.225 88.35)
		(width 0.15)
		(layer "F.Cu")
		(net 573)
	)
	(segment
		(start 77.2 68.185)
		(end 77.296 68.185)
		(width 0.2)
		(layer "F.Cu")
		(net 573)
	)
	(segment
		(start 77.071088 68.313912)
		(end 77.2 68.185)
		(width 0.2)
		(layer "F.Cu")
		(net 573)
	)
	(segment
		(start 77.75 66.04)
		(end 78.04 66.04)
		(width 0.15)
		(layer "F.Cu")
		(net 573)
	)
	(via
		(at 79.259 87.457)
		(size 0.5)
		(drill 0.2)
		(layers "F.Cu" "B.Cu")
		(net 573)
	)
	(via
		(at 76.425294 68.313912)
		(size 0.5)
		(drill 0.2)
		(layers "F.Cu" "B.Cu")
		(net 573)
	)
	(segment
		(start 79.725 87.225)
		(end 79.491 87.225)
		(width 0.15)
		(layer "B.Cu")
		(net 573)
	)
	(segment
		(start 79.491 87.225)
		(end 79.259 87.457)
		(width 0.15)
		(layer "B.Cu")
		(net 573)
	)
	(segment
		(start 78.049999 69.938617)
		(end 78.049999 86.247999)
		(width 0.15)
		(layer "In5.Cu")
		(net 573)
	)
	(segment
		(start 76.425294 68.313912)
		(end 78.049999 69.938617)
		(width 0.15)
		(layer "In5.Cu")
		(net 573)
	)
	(segment
		(start 78.049999 86.247999)
		(end 79.259 87.457)
		(width 0.15)
		(layer "In5.Cu")
		(net 573)
	)
	(segment
		(start 114.375 76.005)
		(end 110.875 79.505)
		(width 0.2)
		(layer "B.Cu")
		(net 574)
	)
	(segment
		(start 95.25 81.955)
		(end 95.25 90.57)
		(width 0.2)
		(layer "B.Cu")
		(net 574)
	)
	(segment
		(start 114.375 69.663)
		(end 111.661 66.949)
		(width 0.2)
		(layer "B.Cu")
		(net 574)
	)
	(segment
		(start 114.375 69.663)
		(end 114.375 76.005)
		(width 0.2)
		(layer "B.Cu")
		(net 574)
	)
	(segment
		(start 110.875 79.505)
		(end 97.7 79.505)
		(width 0.2)
		(layer "B.Cu")
		(net 574)
	)
	(segment
		(start 97.7 79.505)
		(end 95.25 81.955)
		(width 0.2)
		(layer "B.Cu")
		(net 574)
	)
	(segment
		(start 93.965 68.865)
		(end 95.881 66.949)
		(width 0.15)
		(layer "B.Cu")
		(net 575)
	)
	(segment
		(start 95.881 66.949)
		(end 97.691 66.949)
		(width 0.15)
		(layer "B.Cu")
		(net 575)
	)
	(segment
		(start 93.965 90.59)
		(end 93.965 68.865)
		(width 0.15)
		(layer "B.Cu")
		(net 575)
	)
	(segment
		(start 92.33 162.19)
		(end 91.665 162.19)
		(width 0.15)
		(layer "F.Cu")
		(net 576)
	)
	(segment
		(start 91.49 162.365)
		(end 91.065 162.365)
		(width 0.15)
		(layer "F.Cu")
		(net 576)
	)
	(segment
		(start 92.39 170.56)
		(end 92.39 172.55)
		(width 0.15)
		(layer "F.Cu")
		(net 576)
	)
	(segment
		(start 92.39 172.55)
		(end 91.485 173.455)
		(width 0.15)
		(layer "F.Cu")
		(net 576)
	)
	(segment
		(start 91.485 173.455)
		(end 91.485 177.34)
		(width 0.15)
		(layer "F.Cu")
		(net 576)
	)
	(segment
		(start 91.665 162.19)
		(end 91.49 162.365)
		(width 0.15)
		(layer "F.Cu")
		(net 576)
	)
	(via
		(at 92.33 162.19)
		(size 0.5)
		(drill 0.2)
		(layers "F.Cu" "B.Cu")
		(net 576)
	)
	(via
		(at 92.39 170.56)
		(size 0.5)
		(drill 0.2)
		(layers "F.Cu" "B.Cu")
		(net 576)
	)
	(segment
		(start 92.33 162.19)
		(end 92.33 170.5)
		(width 0.15)
		(layer "In5.Cu")
		(net 576)
	)
	(segment
		(start 92.33 170.5)
		(end 92.39 170.56)
		(width 0.15)
		(layer "In5.Cu")
		(net 576)
	)
	(segment
		(start 90.89 173.42)
		(end 89.8 172.33)
		(width 0.15)
		(layer "F.Cu")
		(net 577)
	)
	(segment
		(start 89.8 172.33)
		(end 89.8 166.72)
		(width 0.15)
		(layer "F.Cu")
		(net 577)
	)
	(segment
		(start 89.8 166.72)
		(end 89.345 166.265)
		(width 0.15)
		(layer "F.Cu")
		(net 577)
	)
	(segment
		(start 90.89 177.155)
		(end 90.89 173.42)
		(width 0.15)
		(layer "F.Cu")
		(net 577)
	)
	(segment
		(start 89.345 166.265)
		(end 88.825 166.265)
		(width 0.15)
		(layer "F.Cu")
		(net 577)
	)
	(segment
		(start 89.37 169.65)
		(end 88.4 168.68)
		(width 0.15)
		(layer "F.Cu")
		(net 578)
	)
	(segment
		(start 89.37 172.32)
		(end 89.37 169.65)
		(width 0.15)
		(layer "F.Cu")
		(net 578)
	)
	(segment
		(start 90.29 173.24)
		(end 89.37 172.32)
		(width 0.15)
		(layer "F.Cu")
		(net 578)
	)
	(segment
		(start 90.29 177.155)
		(end 90.29 173.24)
		(width 0.15)
		(layer "F.Cu")
		(net 578)
	)
	(segment
		(start 88.4 168.68)
		(end 88.4 167.21)
		(width 0.15)
		(layer "F.Cu")
		(net 578)
	)
	(segment
		(start 89.69 173.07)
		(end 89.69 177.155)
		(width 0.15)
		(layer "F.Cu")
		(net 579)
	)
	(segment
		(start 88.96 172.34)
		(end 89.69 173.07)
		(width 0.15)
		(layer "F.Cu")
		(net 579)
	)
	(segment
		(start 87.89 167.2)
		(end 87.89 168.78)
		(width 0.15)
		(layer "F.Cu")
		(net 579)
	)
	(segment
		(start 88.96 169.85)
		(end 88.96 172.34)
		(width 0.15)
		(layer "F.Cu")
		(net 579)
	)
	(segment
		(start 87.89 168.78)
		(end 88.96 169.85)
		(width 0.15)
		(layer "F.Cu")
		(net 579)
	)
	(segment
		(start 87.39 171.2)
		(end 87.39 167.19)
		(width 0.15)
		(layer "F.Cu")
		(net 580)
	)
	(segment
		(start 89.09 177.155)
		(end 89.09 172.9)
		(width 0.15)
		(layer "F.Cu")
		(net 580)
	)
	(segment
		(start 89.09 172.9)
		(end 87.39 171.2)
		(width 0.15)
		(layer "F.Cu")
		(net 580)
	)
	(segment
		(start 88.49 172.73)
		(end 88.49 177.155)
		(width 0.15)
		(layer "F.Cu")
		(net 581)
	)
	(segment
		(start 86.89 171.13)
		(end 88.49 172.73)
		(width 0.15)
		(layer "F.Cu")
		(net 581)
	)
	(segment
		(start 86.89 167.2)
		(end 86.89 171.13)
		(width 0.15)
		(layer "F.Cu")
		(net 581)
	)
	(segment
		(start 86.39 167.2)
		(end 86.39 167.99)
		(width 0.15)
		(layer "F.Cu")
		(net 582)
	)
	(segment
		(start 87.89 172.53)
		(end 87.89 177.155)
		(width 0.15)
		(layer "F.Cu")
		(net 582)
	)
	(segment
		(start 86.39 167.99)
		(end 86.48 168.08)
		(width 0.15)
		(layer "F.Cu")
		(net 582)
	)
	(segment
		(start 86.48 171.12)
		(end 87.89 172.53)
		(width 0.15)
		(layer "F.Cu")
		(net 582)
	)
	(segment
		(start 86.48 168.08)
		(end 86.48 171.12)
		(width 0.15)
		(layer "F.Cu")
		(net 582)
	)
	(segment
		(start 85.89 167.2)
		(end 85.89 167.98)
		(width 0.15)
		(layer "F.Cu")
		(net 583)
	)
	(segment
		(start 86.16 171.22)
		(end 87.29 172.35)
		(width 0.15)
		(layer "F.Cu")
		(net 583)
	)
	(segment
		(start 87.29 172.35)
		(end 87.29 177.155)
		(width 0.15)
		(layer "F.Cu")
		(net 583)
	)
	(segment
		(start 86.16 168.25)
		(end 86.16 171.22)
		(width 0.15)
		(layer "F.Cu")
		(net 583)
	)
	(segment
		(start 85.89 167.98)
		(end 86.16 168.25)
		(width 0.15)
		(layer "F.Cu")
		(net 583)
	)
	(segment
		(start 86.685 172.165)
		(end 86.685 177.155)
		(width 0.15)
		(layer "F.Cu")
		(net 584)
	)
	(segment
		(start 85.39 167.2)
		(end 85.39 167.97)
		(width 0.15)
		(layer "F.Cu")
		(net 584)
	)
	(segment
		(start 85.82 171.3)
		(end 86.685 172.165)
		(width 0.15)
		(layer "F.Cu")
		(net 584)
	)
	(segment
		(start 85.39 167.97)
		(end 85.82 168.4)
		(width 0.15)
		(layer "F.Cu")
		(net 584)
	)
	(segment
		(start 85.82 168.4)
		(end 85.82 171.3)
		(width 0.15)
		(layer "F.Cu")
		(net 584)
	)
	(segment
		(start 107.775 114.175)
		(end 108.285 114.685)
		(width 0.1)
		(layer "F.Cu")
		(net 585)
	)
	(segment
		(start 114.805 114.685)
		(end 118.655 118.535)
		(width 0.1)
		(layer "F.Cu")
		(net 585)
	)
	(segment
		(start 108.285 114.685)
		(end 114.805 114.685)
		(width 0.1)
		(layer "F.Cu")
		(net 585)
	)
	(segment
		(start 118.655 118.535)
		(end 118.655 121.955)
		(width 0.1)
		(layer "F.Cu")
		(net 585)
	)
	(via
		(at 118.655 121.955)
		(size 0.5)
		(drill 0.2)
		(layers "F.Cu" "B.Cu")
		(net 585)
	)
	(via
		(at 116.255 152.665)
		(size 0.5)
		(drill 0.2)
		(layers "F.Cu" "B.Cu")
		(net 585)
	)
	(segment
		(start 117.055 152.665)
		(end 116.255 152.665)
		(width 0.15)
		(layer "B.Cu")
		(net 585)
	)
	(segment
		(start 118.655 121.955)
		(end 120.215 123.515)
		(width 0.1)
		(layer "In5.Cu")
		(net 585)
	)
	(segment
		(start 120.215 126.875)
		(end 118.545 128.545)
		(width 0.1)
		(layer "In5.Cu")
		(net 585)
	)
	(segment
		(start 118.545 128.545)
		(end 115.945 128.545)
		(width 0.1)
		(layer "In5.Cu")
		(net 585)
	)
	(segment
		(start 115.515 151.925)
		(end 116.255 152.665)
		(width 0.1)
		(layer "In5.Cu")
		(net 585)
	)
	(segment
		(start 115.945 128.545)
		(end 115.515 128.975)
		(width 0.1)
		(layer "In5.Cu")
		(net 585)
	)
	(segment
		(start 115.515 128.975)
		(end 115.515 151.925)
		(width 0.1)
		(layer "In5.Cu")
		(net 585)
	)
	(segment
		(start 120.215 123.515)
		(end 120.215 126.875)
		(width 0.1)
		(layer "In5.Cu")
		(net 585)
	)
	(segment
		(start 108.275 116.465)
		(end 108.275 115.815)
		(width 0.1)
		(layer "F.Cu")
		(net 586)
	)
	(segment
		(start 108.425 115.665)
		(end 115.502144 115.665)
		(width 0.1)
		(layer "F.Cu")
		(net 586)
	)
	(segment
		(start 117.995 118.157856)
		(end 117.995 122.175)
		(width 0.1)
		(layer "F.Cu")
		(net 586)
	)
	(segment
		(start 104.535 116.675)
		(end 108.065 116.675)
		(width 0.1)
		(layer "F.Cu")
		(net 586)
	)
	(segment
		(start 108.275 115.815)
		(end 108.425 115.665)
		(width 0.1)
		(layer "F.Cu")
		(net 586)
	)
	(segment
		(start 115.502144 115.665)
		(end 117.995 118.157856)
		(width 0.1)
		(layer "F.Cu")
		(net 586)
	)
	(segment
		(start 103.775 115.175)
		(end 104.295 115.695)
		(width 0.1)
		(layer "F.Cu")
		(net 586)
	)
	(segment
		(start 108.065 116.675)
		(end 108.275 116.465)
		(width 0.1)
		(layer "F.Cu")
		(net 586)
	)
	(segment
		(start 104.295 115.695)
		(end 104.295 116.435)
		(width 0.1)
		(layer "F.Cu")
		(net 586)
	)
	(segment
		(start 104.295 116.435)
		(end 104.535 116.675)
		(width 0.1)
		(layer "F.Cu")
		(net 586)
	)
	(via
		(at 117.995 122.175)
		(size 0.5)
		(drill 0.2)
		(layers "F.Cu" "B.Cu")
		(net 586)
	)
	(via
		(at 116.245 153.595)
		(size 0.5)
		(drill 0.2)
		(layers "F.Cu" "B.Cu")
		(net 586)
	)
	(segment
		(start 117.055 153.665)
		(end 116.315 153.665)
		(width 0.15)
		(layer "B.Cu")
		(net 586)
	)
	(segment
		(start 116.315 153.665)
		(end 116.245 153.595)
		(width 0.15)
		(layer "B.Cu")
		(net 586)
	)
	(segment
		(start 119.975 126.735)
		(end 119.975 123.955)
		(width 0.1)
		(layer "In5.Cu")
		(net 586)
	)
	(segment
		(start 115.275 128.805)
		(end 115.795 128.285)
		(width 0.1)
		(layer "In5.Cu")
		(net 586)
	)
	(segment
		(start 116.245 153.595)
		(end 115.275 152.625)
		(width 0.1)
		(layer "In5.Cu")
		(net 586)
	)
	(segment
		(start 118.195 122.175)
		(end 117.995 122.175)
		(width 0.1)
		(layer "In5.Cu")
		(net 586)
	)
	(segment
		(start 118.425 128.285)
		(end 119.975 126.735)
		(width 0.1)
		(layer "In5.Cu")
		(net 586)
	)
	(segment
		(start 115.795 128.285)
		(end 118.425 128.285)
		(width 0.1)
		(layer "In5.Cu")
		(net 586)
	)
	(segment
		(start 115.275 152.625)
		(end 115.275 128.805)
		(width 0.1)
		(layer "In5.Cu")
		(net 586)
	)
	(segment
		(start 119.975 123.955)
		(end 118.195 122.175)
		(width 0.1)
		(layer "In5.Cu")
		(net 586)
	)
	(segment
		(start 96.775 113.175)
		(end 96.275 112.675)
		(width 0.15)
		(layer "F.Cu")
		(net 589)
	)
	(via blind
		(at 96.275 112.675)
		(size 0.5)
		(drill 0.2)
		(layers "F.Cu" "In2.Cu")
		(net 589)
	)
	(segment
		(start 94.765 108.215)
		(end 82.59 108.215)
		(width 0.15)
		(layer "In2.Cu")
		(net 589)
	)
	(segment
		(start 78.215 99.015)
		(end 74.245 99.015)
		(width 0.15)
		(layer "In2.Cu")
		(net 589)
	)
	(segment
		(start 82.59 108.215)
		(end 79.165 104.79)
		(width 0.15)
		(layer "In2.Cu")
		(net 589)
	)
	(segment
		(start 74.245 99.015)
		(end 72.75 100.51)
		(width 0.15)
		(layer "In2.Cu")
		(net 589)
	)
	(segment
		(start 95.765 109.215)
		(end 94.765 108.215)
		(width 0.15)
		(layer "In2.Cu")
		(net 589)
	)
	(segment
		(start 79.165 104.79)
		(end 79.165 99.965)
		(width 0.15)
		(layer "In2.Cu")
		(net 589)
	)
	(segment
		(start 79.165 99.965)
		(end 78.215 99.015)
		(width 0.15)
		(layer "In2.Cu")
		(net 589)
	)
	(segment
		(start 95.765 112.165)
		(end 95.765 109.215)
		(width 0.15)
		(layer "In2.Cu")
		(net 589)
	)
	(segment
		(start 96.275 112.675)
		(end 95.765 112.165)
		(width 0.15)
		(layer "In2.Cu")
		(net 589)
	)
	(segment
		(start 109.755 110.155)
		(end 109.255 110.655)
		(width 0.15)
		(layer "F.Cu")
		(net 590)
	)
	(via blind
		(at 109.255 110.655)
		(size 0.5)
		(drill 0.2)
		(layers "F.Cu" "In5.Cu")
		(net 590)
	)
	(via
		(at 84.865 107.015)
		(size 0.5)
		(drill 0.2)
		(layers "F.Cu" "B.Cu")
		(net 590)
	)
	(segment
		(start 79.415 99.815)
		(end 79.415 104.64)
		(width 0.15)
		(layer "In2.Cu")
		(net 590)
	)
	(segment
		(start 71.955 98.765)
		(end 78.365 98.765)
		(width 0.15)
		(layer "In2.Cu")
		(net 590)
	)
	(segment
		(start 82.49 107.715)
		(end 84.165 107.715)
		(width 0.15)
		(layer "In2.Cu")
		(net 590)
	)
	(segment
		(start 84.165 107.715)
		(end 84.865 107.015)
		(width 0.15)
		(layer "In2.Cu")
		(net 590)
	)
	(segment
		(start 79.415 104.64)
		(end 82.49 107.715)
		(width 0.15)
		(layer "In2.Cu")
		(net 590)
	)
	(segment
		(start 70.21 100.51)
		(end 71.955 98.765)
		(width 0.15)
		(layer "In2.Cu")
		(net 590)
	)
	(segment
		(start 78.365 98.765)
		(end 79.415 99.815)
		(width 0.15)
		(layer "In2.Cu")
		(net 590)
	)
	(segment
		(start 85.315 107.465)
		(end 107.465 107.465)
		(width 0.15)
		(layer "In5.Cu")
		(net 590)
	)
	(segment
		(start 108.265 109.665)
		(end 108.265 108.265)
		(width 0.15)
		(layer "In5.Cu")
		(net 590)
	)
	(segment
		(start 85.315 107.465)
		(end 84.865 107.015)
		(width 0.15)
		(layer "In5.Cu")
		(net 590)
	)
	(segment
		(start 109.255 110.655)
		(end 108.265 109.665)
		(width 0.15)
		(layer "In5.Cu")
		(net 590)
	)
	(segment
		(start 108.265 108.265)
		(end 107.465 107.465)
		(width 0.15)
		(layer "In5.Cu")
		(net 590)
	)
	(segment
		(start 107.775 108.41843)
		(end 107.769491 108.412921)
		(width 0.15)
		(layer "F.Cu")
		(net 591)
	)
	(segment
		(start 107.775 109.175)
		(end 107.775 108.41843)
		(width 0.15)
		(layer "F.Cu")
		(net 591)
	)
	(via
		(at 84.165 107.015)
		(size 0.5)
		(drill 0.2)
		(layers "F.Cu" "B.Cu")
		(net 591)
	)
	(via
		(at 107.769491 108.412921)
		(size 0.5)
		(drill 0.2)
		(layers "F.Cu" "B.Cu")
		(net 591)
	)
	(segment
		(start 79.665 104.493554)
		(end 82.636446 107.465)
		(width 0.15)
		(layer "In2.Cu")
		(net 591)
	)
	(segment
		(start 78.515 98.515)
		(end 79.665 99.665)
		(width 0.15)
		(layer "In2.Cu")
		(net 591)
	)
	(segment
		(start 79.665 99.665)
		(end 79.665 104.493554)
		(width 0.15)
		(layer "In2.Cu")
		(net 591)
	)
	(segment
		(start 84.165 107.165)
		(end 84.165 107.015)
		(width 0.15)
		(layer "In2.Cu")
		(net 591)
	)
	(segment
		(start 67.67 100.51)
		(end 69.665 98.515)
		(width 0.15)
		(layer "In2.Cu")
		(net 591)
	)
	(segment
		(start 82.636446 107.465)
		(end 83.865 107.465)
		(width 0.15)
		(layer "In2.Cu")
		(net 591)
	)
	(segment
		(start 83.865 107.465)
		(end 84.165 107.165)
		(width 0.15)
		(layer "In2.Cu")
		(net 591)
	)
	(segment
		(start 69.665 98.515)
		(end 78.515 98.515)
		(width 0.15)
		(layer "In2.Cu")
		(net 591)
	)
	(segment
		(start 84.865 107.715)
		(end 84.165 107.015)
		(width 0.15)
		(layer "In5.Cu")
		(net 591)
	)
	(segment
		(start 84.865 107.715)
		(end 107.07157 107.715)
		(width 0.15)
		(layer "In5.Cu")
		(net 591)
	)
	(segment
		(start 107.07157 107.715)
		(end 107.769491 108.412921)
		(width 0.15)
		(layer "In5.Cu")
		(net 591)
	)
	(segment
		(start 96.755 114.175)
		(end 96.255 114.675)
		(width 0.15)
		(layer "F.Cu")
		(net 592)
	)
	(via blind
		(at 96.255 114.675)
		(size 0.5)
		(drill 0.2)
		(layers "F.Cu" "In2.Cu")
		(net 592)
	)
	(via
		(at 94.265 113.665)
		(size 0.5)
		(drill 0.2)
		(layers "F.Cu" "B.Cu")
		(net 592)
	)
	(via
		(at 83.465 107.015)
		(size 0.5)
		(drill 0.2)
		(layers "F.Cu" "B.Cu")
		(net 592)
	)
	(segment
		(start 87.515 108.115)
		(end 89.565 110.165)
		(width 0.15)
		(layer "B.Cu")
		(net 592)
	)
	(segment
		(start 89.565 110.165)
		(end 89.565 113.765)
		(width 0.15)
		(layer "B.Cu")
		(net 592)
	)
	(segment
		(start 89.565 113.765)
		(end 89.965 114.165)
		(width 0.15)
		(layer "B.Cu")
		(net 592)
	)
	(segment
		(start 83.465 107.015)
		(end 84.565 108.115)
		(width 0.15)
		(layer "B.Cu")
		(net 592)
	)
	(segment
		(start 89.965 114.165)
		(end 90.765 114.165)
		(width 0.15)
		(layer "B.Cu")
		(net 592)
	)
	(segment
		(start 84.565 108.115)
		(end 87.515 108.115)
		(width 0.15)
		(layer "B.Cu")
		(net 592)
	)
	(segment
		(start 91.265 113.665)
		(end 94.265 113.665)
		(width 0.15)
		(layer "B.Cu")
		(net 592)
	)
	(segment
		(start 90.765 114.165)
		(end 91.265 113.665)
		(width 0.15)
		(layer "B.Cu")
		(net 592)
	)
	(segment
		(start 96.255 114.675)
		(end 95.765 115.165)
		(width 0.15)
		(layer "In2.Cu")
		(net 592)
	)
	(segment
		(start 95.765 115.165)
		(end 94.865 115.165)
		(width 0.15)
		(layer "In2.Cu")
		(net 592)
	)
	(segment
		(start 94.865 115.165)
		(end 94.265 114.565)
		(width 0.15)
		(layer "In2.Cu")
		(net 592)
	)
	(segment
		(start 79.915 104.39)
		(end 82.54 107.015)
		(width 0.15)
		(layer "In2.Cu")
		(net 592)
	)
	(segment
		(start 82.54 107.015)
		(end 83.465 107.015)
		(width 0.15)
		(layer "In2.Cu")
		(net 592)
	)
	(segment
		(start 65.13 100.51)
		(end 67.37501 98.26499)
		(width 0.15)
		(layer "In2.Cu")
		(net 592)
	)
	(segment
		(start 78.66499 98.26499)
		(end 79.915 99.515)
		(width 0.15)
		(layer "In2.Cu")
		(net 592)
	)
	(segment
		(start 94.265 114.565)
		(end 94.265 113.665)
		(width 0.15)
		(layer "In2.Cu")
		(net 592)
	)
	(segment
		(start 79.915 99.515)
		(end 79.915 104.39)
		(width 0.15)
		(layer "In2.Cu")
		(net 592)
	)
	(segment
		(start 67.37501 98.26499)
		(end 78.66499 98.26499)
		(width 0.15)
		(layer "In2.Cu")
		(net 592)
	)
	(segment
		(start 140.7025 91.55)
		(end 140.865 91.7125)
		(width 0.1)
		(layer "F.Cu")
		(net 597)
	)
	(segment
		(start 132.85 90.8875)
		(end 132.85 90.1125)
		(width 0.1)
		(layer "F.Cu")
		(net 597)
	)
	(segment
		(start 140.8275 99.05)
		(end 140.865 99.0125)
		(width 0.1)
		(layer "F.Cu")
		(net 597)
	)
	(segment
		(start 140.865 99.0125)
		(end 140.865 99.6975)
		(width 0.1)
		(layer "F.Cu")
		(net 597)
	)
	(segment
		(start 139.0125 99.05)
		(end 140.8275 99.05)
		(width 0.1)
		(layer "F.Cu")
		(net 597)
	)
	(segment
		(start 139.0125 91.55)
		(end 140.7025 91.55)
		(width 0.1)
		(layer "F.Cu")
		(net 597)
	)
	(segment
		(start 132.85 99.7125)
		(end 132.85 101.3275)
		(width 0.1)
		(layer "F.Cu")
		(net 597)
	)
	(segment
		(start 140.865 91.7125)
		(end 140.865 92.3975)
		(width 0.1)
		(layer "F.Cu")
		(net 597)
	)
	(segment
		(start 132.85 101.3275)
		(end 132.1225 101.3275)
		(width 0.1)
		(layer "F.Cu")
		(net 597)
	)
	(segment
		(start 140.865 99.6975)
		(end 140.85 99.7125)
		(width 0.1)
		(layer "F.Cu")
		(net 597)
	)
	(segment
		(start 140.865 92.3975)
		(end 140.85 92.4125)
		(width 0.1)
		(layer "F.Cu")
		(net 597)
	)
	(segment
		(start 132.1225 101.3275)
		(end 132.075 101.375)
		(width 0.1)
		(layer "F.Cu")
		(net 597)
	)
	(via
		(at 132.075 101.375)
		(size 0.5)
		(drill 0.2)
		(layers "F.Cu" "B.Cu")
		(net 597)
	)
	(via
		(at 132.85 90.1125)
		(size 0.5)
		(drill 0.2)
		(layers "F.Cu" "B.Cu")
		(net 597)
	)
	(via
		(at 140.85 99.7125)
		(size 0.5)
		(drill 0.2)
		(layers "F.Cu" "B.Cu")
		(net 597)
	)
	(via
		(at 140.85 92.4125)
		(size 0.5)
		(drill 0.2)
		(layers "F.Cu" "B.Cu")
		(net 597)
	)
	(segment
		(start 132.865 90.8125)
		(end 132.865 90.1275)
		(width 0.1)
		(layer "B.Cu")
		(net 597)
	)
	(segment
		(start 140.25 92.4125)
		(end 140.85 92.4125)
		(width 0.2)
		(layer "B.Cu")
		(net 597)
	)
	(segment
		(start 140.25 92.4125)
		(end 139.75 92.4125)
		(width 0.2)
		(layer "B.Cu")
		(net 597)
	)
	(segment
		(start 139.55 99.2125)
		(end 140.05 99.7125)
		(width 0.2)
		(layer "B.Cu")
		(net 597)
	)
	(segment
		(start 132.85 90.1125)
		(end 135.85 90.1125)
		(width 0.2)
		(layer "B.Cu")
		(net 597)
	)
	(segment
		(start 132.865 90.1275)
		(end 132.85 90.1125)
		(width 0.1)
		(layer "B.Cu")
		(net 597)
	)
	(segment
		(start 132.7375 99.7125)
		(end 132.075 100.375)
		(width 0.2)
		(layer "B.Cu")
		(net 597)
	)
	(segment
		(start 135.85 90.1125)
		(end 138.15 92.4125)
		(width 0.2)
		(layer "B.Cu")
		(net 597)
	)
	(segment
		(start 138.15 92.4125)
		(end 140.25 92.4125)
		(width 0.2)
		(layer "B.Cu")
		(net 597)
	)
	(segment
		(start 132.7375 99.7125)
		(end 140.05 99.7125)
		(width 0.2)
		(layer "B.Cu")
		(net 597)
	)
	(segment
		(start 132.075 100.375)
		(end 132.075 101.375)
		(width 0.2)
		(layer "B.Cu")
		(net 597)
	)
	(segment
		(start 139.55 92.6125)
		(end 139.55 99.2125)
		(width 0.2)
		(layer "B.Cu")
		(net 597)
	)
	(segment
		(start 139.75 92.4125)
		(end 139.55 92.6125)
		(width 0.2)
		(layer "B.Cu")
		(net 597)
	)
	(segment
		(start 140.05 99.7125)
		(end 140.85 99.7125)
		(width 0.2)
		(layer "B.Cu")
		(net 597)
	)
	(segment
		(start 103.775 112.175)
		(end 104.275 112.675)
		(width 0.15)
		(layer "F.Cu")
		(net 624)
	)
	(segment
		(start 130.29 103.875)
		(end 130.39 103.775)
		(width 0.15)
		(layer "F.Cu")
		(net 624)
	)
	(segment
		(start 117.775 103.875)
		(end 130.29 103.875)
		(width 0.15)
		(layer "F.Cu")
		(net 624)
	)
	(via blind
		(at 104.275 112.675)
		(size 0.5)
		(drill 0.2)
		(layers "F.Cu" "In5.Cu")
		(net 624)
	)
	(via
		(at 117.775 103.875)
		(size 0.5)
		(drill 0.2)
		(layers "F.Cu" "B.Cu")
		(net 624)
	)
	(segment
		(start 106.575 112.175)
		(end 107.475 111.275)
		(width 0.15)
		(layer "In5.Cu")
		(net 624)
	)
	(segment
		(start 116.375 111.275)
		(end 117.775 109.875)
		(width 0.15)
		(layer "In5.Cu")
		(net 624)
	)
	(segment
		(start 117.775 109.875)
		(end 117.775 103.875)
		(width 0.15)
		(layer "In5.Cu")
		(net 624)
	)
	(segment
		(start 104.275 112.675)
		(end 104.775 112.175)
		(width 0.15)
		(layer "In5.Cu")
		(net 624)
	)
	(segment
		(start 107.475 111.275)
		(end 116.375 111.275)
		(width 0.15)
		(layer "In5.Cu")
		(net 624)
	)
	(segment
		(start 104.775 112.175)
		(end 106.575 112.175)
		(width 0.15)
		(layer "In5.Cu")
		(net 624)
	)
	(segment
		(start 129.875 104.775)
		(end 130.4 104.775)
		(width 0.15)
		(layer "F.Cu")
		(net 626)
	)
	(segment
		(start 104.775 112.175)
		(end 105.275 112.675)
		(width 0.15)
		(layer "F.Cu")
		(net 626)
	)
	(segment
		(start 118.275 104.475)
		(end 129.575 104.475)
		(width 0.15)
		(layer "F.Cu")
		(net 626)
	)
	(segment
		(start 129.575 104.475)
		(end 129.875 104.775)
		(width 0.15)
		(layer "F.Cu")
		(net 626)
	)
	(via
		(at 118.275 104.475)
		(size 0.5)
		(drill 0.2)
		(layers "F.Cu" "B.Cu")
		(net 626)
	)
	(via blind
		(at 105.275 112.675)
		(size 0.5)
		(drill 0.2)
		(layers "F.Cu" "In5.Cu")
		(net 626)
	)
	(segment
		(start 107.675 111.575)
		(end 116.575 111.575)
		(width 0.15)
		(layer "In5.Cu")
		(net 626)
	)
	(segment
		(start 116.575 111.575)
		(end 118.275 109.875)
		(width 0.15)
		(layer "In5.Cu")
		(net 626)
	)
	(segment
		(start 118.275 109.875)
		(end 118.275 104.475)
		(width 0.15)
		(layer "In5.Cu")
		(net 626)
	)
	(segment
		(start 105.275 112.675)
		(end 106.575 112.675)
		(width 0.15)
		(layer "In5.Cu")
		(net 626)
	)
	(segment
		(start 106.575 112.675)
		(end 107.675 111.575)
		(width 0.15)
		(layer "In5.Cu")
		(net 626)
	)
	(segment
		(start 124.955 113.84)
		(end 124.925 113.81)
		(width 0.15)
		(layer "F.Cu")
		(net 651)
	)
	(segment
		(start 124.955 115.935)
		(end 124.955 113.84)
		(width 0.15)
		(layer "F.Cu")
		(net 651)
	)
	(segment
		(start 124.785 132.685)
		(end 124.785 129.97)
		(width 0.15)
		(layer "F.Cu")
		(net 656)
	)
	(segment
		(start 110.474 167.16)
		(end 110.474 177.329)
		(width 0.15)
		(layer "F.Cu")
		(net 694)
	)
	(zone
		(net 1)
		(net_name "GND")
		(layer "F.Cu")
		(hatch edge 0.508)
		(connect_pads yes
			(clearance 0.15)
		)
		(min_thickness 0.1)
		(filled_areas_thickness no)
		(fill yes
			(thermal_gap 0.508)
			(thermal_bridge_width 0.508)
		)
		(polygon
			(pts
				(xy 83.165 68.515) (xy 78.469 68.505) (xy 78.45 62.005) (xy 73.15 62.005) (xy 73.15 64.765) (xy 71.05 64.765)
				(xy 71.05 58.905) (xy 93.89 58.905) (xy 93.89 62.965) (xy 89.465 62.965) (xy 89.465 68.365) (xy 84.765 68.39)
				(xy 84.79 63.14) (xy 84.79 61.415) (xy 81.14 61.415) (xy 81.14 67.49) (xy 83.165 67.515)
			)
		)
	)
	(zone
		(net 1)
		(net_name "GND")
		(layer "F.Cu")
		(hatch edge 0.508)
		(connect_pads yes
			(clearance 0.1)
		)
		(min_thickness 0.1)
		(filled_areas_thickness no)
		(fill yes
			(thermal_gap 0.2)
			(thermal_bridge_width 0.2)
		)
		(polygon
			(pts
				(xy 92.24 73.065017) (xy 92.237291 77.675) (xy 92.245 77.675) (xy 92.245 107.125) (xy 86.819 107.127)
				(xy 86.819 103.527) (xy 84.195 103.525) (xy 83.345 102.675) (xy 83.345 102.125) (xy 86.674 102.125)
				(xy 86.674 98.625) (xy 86.819 98.625) (xy 86.819 96.175) (xy 84.195 96.175) (xy 83.345 95.325) (xy 83.345 94.775)
				(xy 85.995 94.775) (xy 85.995 91.275) (xy 86.819 91.275) (xy 86.819 88.825) (xy 84.195 88.825) (xy 83.345 87.975)
				(xy 83.345 87.425) (xy 85.995 87.425) (xy 85.995 83.925) (xy 86.819 83.925) (xy 86.819 81.475) (xy 84.195 81.475)
				(xy 83.279 80.592) (xy 83.279 80.062) (xy 85.995 80.075) (xy 85.980459 76.567) (xy 86.817771 76.555)
				(xy 86.82023 74.073488) (xy 84.175 74.059976) (xy 83.2 73.137) (xy 83.2 72.505) (xy 85.9745 72.505)
				(xy 85.95 70.205) (xy 89.85 70.205) (xy 91.465 70.205) (xy 91.465 73.065)
			)
		)
		(polygon
			(pts
				(xy 87.104 104.125) (xy 87.119 106.175) (xy 91.969 106.177) (xy 91.969 104.127)
			)
		)
		(polygon
			(pts
				(xy 89.995 102.625) (xy 89.995 103.675) (xy 91.995 103.675) (xy 91.995 102.625)
			)
		)
		(polygon
			(pts
				(xy 87.295 102.625) (xy 87.295 103.675) (xy 88.195 103.675) (xy 88.195 102.625)
			)
		)
		(polygon
			(pts
				(xy 87.169 96.777) (xy 87.169 99.077) (xy 91.995 99.075) (xy 91.995 96.775)
			)
		)
		(polygon
			(pts
				(xy 89.995 95.275) (xy 89.995 96.325) (xy 91.995 96.325) (xy 91.995 95.275)
			)
		)
		(polygon
			(pts
				(xy 87.295 95.275) (xy 87.295 96.325) (xy 88.195 96.325) (xy 88.195 95.275)
			)
		)
		(polygon
			(pts
				(xy 87.169 89.425) (xy 87.169 91.375) (xy 91.995 91.375) (xy 91.995 89.425)
			)
		)
		(polygon
			(pts
				(xy 89.995 87.925) (xy 89.995 88.975) (xy 91.995 88.975) (xy 91.995 87.925)
			)
		)
		(polygon
			(pts
				(xy 87.295 87.925) (xy 87.295 88.975) (xy 88.195 88.975) (xy 88.195 87.925)
			)
		)
		(polygon
			(pts
				(xy 87.269 82.027) (xy 87.269 83.975) (xy 91.969 83.977) (xy 91.969 82.027)
			)
		)
		(polygon
			(pts
				(xy 89.995 80.575) (xy 89.995 81.625) (xy 91.995 81.625) (xy 91.995 80.575)
			)
		)
		(polygon
			(pts
				(xy 87.295 80.575) (xy 87.295 81.625) (xy 88.195 81.625) (xy 88.195 80.575)
			)
		)
		(polygon
			(pts
				(xy 87.166 74.57175) (xy 87.167789 75.455) (xy 88.052025 76.051999) (xy 88.05 76.555) (xy 91.975 76.575)
				(xy 91.972 74.577)
			)
		)
		(polygon
			(pts
				(xy 87.3 73.175) (xy 87.3 74.225) (xy 88.2 74.225) (xy 88.2 73.175)
			)
		)
		(polygon
			(pts
				(xy 90 73.44) (xy 90 74.225) (xy 92 74.225) (xy 92 73.465)
			)
		)
	)
	(zone
		(net 5)
		(net_name "VCC1V8")
		(layer "F.Cu")
		(hatch edge 0.508)
		(priority 3)
		(connect_pads yes
			(clearance 0.1)
		)
		(min_thickness 0.1)
		(filled_areas_thickness no)
		(fill yes
			(thermal_gap 0.2)
			(thermal_bridge_width 0.2)
		)
		(polygon
			(pts
				(xy 82.309 92.277) (xy 79.099 92.277) (xy 79.089 89.287) (xy 82.289 89.297)
			)
		)
	)
	(zone
		(net 3)
		(net_name "VCC1V35")
		(layer "F.Cu")
		(hatch edge 0.508)
		(priority 3)
		(connect_pads yes
			(clearance 0.1)
		)
		(min_thickness 0.1)
		(filled_areas_thickness no)
		(fill yes
			(thermal_gap 0.2)
			(thermal_bridge_width 0.2)
		)
		(polygon
			(pts
				(xy 82.089 85.597) (xy 78.879 85.597) (xy 78.869 82.607) (xy 82.069 82.617)
			)
		)
	)
	(zone
		(net 6)
		(net_name "VCC1V0")
		(layer "F.Cu")
		(hatch edge 0.508)
		(priority 3)
		(connect_pads yes
			(clearance 0.1)
		)
		(min_thickness 0.1)
		(filled_areas_thickness no)
		(fill yes
			(thermal_gap 0.2)
			(thermal_bridge_width 0.2)
		)
		(polygon
			(pts
				(xy 82.069 82.027) (xy 78.469 82.027) (xy 78.469156 86.107) (xy 74.469156 86.11325) (xy 74.46775 77.60075)
				(xy 78.439 77.607) (xy 78.439039 79.54507) (xy 82.049 79.557)
			)
		)
	)
	(zone
		(net 339)
		(net_name "VCC1V2")
		(layer "F.Cu")
		(hatch edge 0.508)
		(priority 3)
		(connect_pads yes
			(clearance 0.1)
		)
		(min_thickness 0.1)
		(filled_areas_thickness no)
		(fill yes
			(thermal_gap 0.2)
			(thermal_bridge_width 0.2)
		)
		(polygon
			(pts
				(xy 81.929 75.205) (xy 79.2 75.205) (xy 79.2 72.505) (xy 81.95 72.505)
			)
		)
	)
	(zone
		(net 59)
		(net_name "P12V_AUX")
		(layer "F.Cu")
		(hatch edge 0.508)
		(connect_pads yes
			(clearance 0.1)
		)
		(min_thickness 0.1)
		(filled_areas_thickness no)
		(fill yes
			(thermal_gap 0.508)
			(thermal_bridge_width 0.508)
		)
		(polygon
			(pts
				(xy 93.89 72.865) (xy 91.615 72.865) (xy 91.615 63.115) (xy 93.89 63.115)
			)
		)
	)
	(zone
		(net 4)
		(net_name "VCC5V0")
		(layer "F.Cu")
		(hatch edge 0.508)
		(connect_pads yes
			(clearance 0.1)
		)
		(min_thickness 0.1)
		(filled_areas_thickness no)
		(fill yes
			(thermal_gap 0.508)
			(thermal_bridge_width 0.508)
		)
		(polygon
			(pts
				(xy 79.2 75.405) (xy 82.15 75.405) (xy 82.15 74.655) (xy 86.67 74.65) (xy 86.67 75.05) (xy 85.87 75.05)
				(xy 85.72 75.2) (xy 85.72 76.55) (xy 85.72 77.2) (xy 79.2 77.205)
			)
		)
	)
	(zone
		(net 291)
		(net_name "Net-(U16-SW)")
		(layer "F.Cu")
		(hatch edge 0.508)
		(connect_pads yes
			(clearance 0.1)
		)
		(min_thickness 0.1)
		(filled_areas_thickness no)
		(fill yes
			(thermal_gap 0.508)
			(thermal_bridge_width 0.508)
		)
		(polygon
			(pts
				(xy 83.07 72.505) (xy 83.07 73.2) (xy 84.07 74.2) (xy 86.67 74.2) (xy 86.67 74.5) (xy 82.17 74.5)
				(xy 82.17 72.505)
			)
		)
	)
	(zone
		(net 60)
		(net_name "Net-(C101-Pad2)")
		(layer "F.Cu")
		(hatch edge 0.508)
		(connect_pads yes
			(clearance 0.1)
		)
		(min_thickness 0.1)
		(filled_areas_thickness no)
		(fill yes
			(thermal_gap 0.508)
			(thermal_bridge_width 0.508)
		)
		(polygon
			(pts
				(xy 85.77 70.2) (xy 85.77 72.4) (xy 79.2 72.407) (xy 79.2 70.205)
			)
		)
	)
	(zone
		(net 276)
		(net_name "Net-(C81-Pad2)")
		(layer "F.Cu")
		(hatch edge 0.508)
		(connect_pads yes
			(clearance 0.1)
		)
		(min_thickness 0.1)
		(filled_areas_thickness no)
		(fill yes
			(thermal_gap 0.508)
			(thermal_bridge_width 0.508)
		)
		(polygon
			(pts
				(xy 85.795 77.625) (xy 85.795 79.825) (xy 78.829 79.807) (xy 78.829 77.607)
			)
		)
	)
	(zone
		(net 289)
		(net_name "Net-(U12-SW)")
		(layer "F.Cu")
		(hatch edge 0.508)
		(connect_pads yes
			(clearance 0.1)
		)
		(min_thickness 0.1)
		(filled_areas_thickness no)
		(fill yes
			(thermal_gap 0.508)
			(thermal_bridge_width 0.508)
		)
		(polygon
			(pts
				(xy 83.095 79.975) (xy 83.095 80.625) (xy 84.095 81.625) (xy 86.695 81.625) (xy 86.695 81.925) (xy 82.195 81.925)
				(xy 82.195 79.975)
			)
		)
	)
	(zone
		(net 4)
		(net_name "VCC5V0")
		(layer "F.Cu")
		(hatch edge 0.508)
		(connect_pads yes
			(clearance 0.1)
		)
		(min_thickness 0.1)
		(filled_areas_thickness no)
		(fill yes
			(thermal_gap 0.508)
			(thermal_bridge_width 0.508)
		)
		(polygon
			(pts
				(xy 82.369 82.127) (xy 86.619 82.127) (xy 86.619 82.427) (xy 85.895 82.427) (xy 85.745 82.625) (xy 85.745 83.975)
				(xy 85.745 84.625) (xy 82.369 84.627)
			)
		)
	)
	(zone
		(net 104)
		(net_name "/Power supply/VCC12V")
		(layer "F.Cu")
		(hatch edge 0.508)
		(priority 1)
		(connect_pads yes
			(clearance 0.15)
		)
		(min_thickness 0.254)
		(filled_areas_thickness no)
		(fill yes
			(thermal_gap 0.508)
			(thermal_bridge_width 0.508)
		)
		(polygon
			(pts
				(xy 84.565 63.165) (xy 84.615 68.49) (xy 89.64 68.49) (xy 89.64 63.115) (xy 91.465 63.115) (xy 91.465 70.065)
				(xy 83.44 70.065) (xy 83.44 66.34) (xy 82.715 65.715) (xy 81.315 65.715) (xy 81.315 64.765) (xy 82.715 64.765)
				(xy 83.34 64.065) (xy 83.315 63.165)
			)
		)
	)
	(zone
		(net 4)
		(net_name "VCC5V0")
		(layer "F.Cu")
		(hatch edge 0.508)
		(connect_pads yes
			(clearance 0.1)
		)
		(min_thickness 0.1)
		(filled_areas_thickness no)
		(fill yes
			(thermal_gap 0.508)
			(thermal_bridge_width 0.508)
		)
		(polygon
			(pts
				(xy 82.195 104.225) (xy 86.695 104.175) (xy 86.695 104.575) (xy 85.895 104.575) (xy 85.745 104.725)
				(xy 85.745 106.075) (xy 85.745 106.615) (xy 82.195 106.615)
			)
		)
	)
	(zone
		(net 290)
		(net_name "Net-(U13-SW)")
		(layer "F.Cu")
		(hatch edge 0.508)
		(connect_pads yes
			(clearance 0.1)
		)
		(min_thickness 0.1)
		(filled_areas_thickness no)
		(fill yes
			(thermal_gap 0.508)
			(thermal_bridge_width 0.508)
		)
		(polygon
			(pts
				(xy 83.105 87.385) (xy 83.105 88.035) (xy 84.105 89.035) (xy 86.705 89.035) (xy 86.705 89.335) (xy 82.205 89.335)
				(xy 82.205 87.385)
			)
		)
	)
	(zone
		(net 277)
		(net_name "Net-(C82-Pad2)")
		(layer "F.Cu")
		(hatch edge 0.508)
		(connect_pads yes
			(clearance 0.1)
		)
		(min_thickness 0.1)
		(filled_areas_thickness no)
		(fill yes
			(thermal_gap 0.508)
			(thermal_bridge_width 0.508)
		)
		(polygon
			(pts
				(xy 85.805 85.035) (xy 85.805 87.235) (xy 78.799 87.227) (xy 78.799 85.027)
			)
		)
	)
	(zone
		(net 288)
		(net_name "Net-(U11-SW)")
		(layer "F.Cu")
		(hatch edge 0.508)
		(connect_pads yes
			(clearance 0.1)
		)
		(min_thickness 0.1)
		(filled_areas_thickness no)
		(fill yes
			(thermal_gap 0.508)
			(thermal_bridge_width 0.508)
		)
		(polygon
			(pts
				(xy 83.095 94.725) (xy 83.095 95.375) (xy 84.095 96.375) (xy 86.695 96.375) (xy 86.695 96.675) (xy 82.195 96.675)
				(xy 82.195 94.725)
			)
		)
	)
	(zone
		(net 4)
		(net_name "VCC5V0")
		(layer "F.Cu")
		(hatch edge 0.508)
		(connect_pads yes
			(clearance 0.1)
		)
		(min_thickness 0.1)
		(filled_areas_thickness no)
		(fill yes
			(thermal_gap 0.508)
			(thermal_bridge_width 0.508)
		)
		(polygon
			(pts
				(xy 82.195 96.875) (xy 86.695 96.825) (xy 86.695 97.225) (xy 85.895 97.225) (xy 85.745 97.375) (xy 85.745 98.725)
				(xy 85.745 99.375) (xy 82.195 99.375)
			)
		)
	)
	(zone
		(net 275)
		(net_name "Net-(C80-Pad2)")
		(layer "F.Cu")
		(hatch edge 0.508)
		(connect_pads yes
			(clearance 0.1)
		)
		(min_thickness 0.1)
		(filled_areas_thickness no)
		(fill yes
			(thermal_gap 0.508)
			(thermal_bridge_width 0.508)
		)
		(polygon
			(pts
				(xy 85.795 92.375) (xy 85.795 94.575) (xy 79.079 94.587) (xy 79.079 92.387)
			)
		)
	)
	(zone
		(net 285)
		(net_name "Net-(U10-SW)")
		(layer "F.Cu")
		(hatch edge 0.508)
		(connect_pads yes
			(clearance 0.1)
		)
		(min_thickness 0.1)
		(filled_areas_thickness no)
		(fill yes
			(thermal_gap 0.508)
			(thermal_bridge_width 0.508)
		)
		(polygon
			(pts
				(xy 83.095 102.075) (xy 83.095 102.725) (xy 84.095 103.725) (xy 86.695 103.725) (xy 86.695 104.025)
				(xy 82.195 104.025) (xy 82.195 102.075)
			)
		)
	)
	(zone
		(net 274)
		(net_name "Net-(C79-Pad2)")
		(layer "F.Cu")
		(hatch edge 0.508)
		(connect_pads yes
			(clearance 0.1)
		)
		(min_thickness 0.1)
		(filled_areas_thickness no)
		(fill yes
			(thermal_gap 0.508)
			(thermal_bridge_width 0.508)
		)
		(polygon
			(pts
				(xy 86.469 99.677) (xy 86.469 101.877) (xy 82.175 101.875) (xy 82.175 99.675)
			)
		)
	)
	(zone
		(net 4)
		(net_name "VCC5V0")
		(layer "F.Cu")
		(hatch edge 0.508)
		(connect_pads yes
			(clearance 0.1)
		)
		(min_thickness 0.1)
		(filled_areas_thickness no)
		(fill yes
			(thermal_gap 0.508)
			(thermal_bridge_width 0.508)
		)
		(polygon
			(pts
				(xy 82.205 89.535) (xy 86.705 89.485) (xy 86.705 89.885) (xy 85.905 89.885) (xy 85.755 90.035) (xy 85.755 91.385)
				(xy 85.755 92.035) (xy 82.205 92.035)
			)
		)
	)
	(zone
		(net 114)
		(net_name "Net-(C72-Pad2)")
		(layer "F.Cu")
		(hatch edge 0.508)
		(connect_pads yes
			(clearance 0.15)
		)
		(min_thickness 0.1)
		(filled_areas_thickness no)
		(fill yes
			(thermal_gap 0.508)
			(thermal_bridge_width 0.508)
		)
		(polygon
			(pts
				(xy 73.25 68.755) (xy 83.165 68.755) (xy 83.165 69.955) (xy 78.05 69.955) (xy 78 77.355) (xy 73.2 77.355)
			)
		)
	)
	(zone
		(net 8)
		(net_name "Net-(D3-C)")
		(layer "F.Cu")
		(hatch edge 0.508)
		(connect_pads yes
			(clearance 0.15)
		)
		(min_thickness 0.1)
		(filled_areas_thickness no)
		(fill yes
			(thermal_gap 0.508)
			(thermal_bridge_width 0.508)
		)
		(polygon
			(pts
				(xy 65.65 60.915) (xy 70.8 60.915) (xy 70.8 65.065) (xy 78.3 65.065) (xy 78.26 68.035) (xy 68.45 68.055)
				(xy 68.400417 73.905) (xy 65.6 73.905)
			)
		)
	)
	(zone
		(net 0)
		(net_name "")
		(layers "F.Cu" "B.Cu" "In2.Cu" "In3.Cu" "In5.Cu" "In6.Cu")
		(hatch edge 0.508)
		(connect_pads
			(clearance 0)
		)
		(min_thickness 0.1)
		(filled_areas_thickness no)
		(keepout
			(tracks not_allowed)
			(vias allowed)
			(pads allowed)
			(copperpour not_allowed)
			(footprints allowed)
		)
		(placement
			(enabled no)
			(sheetname "")
		)
		(fill
			(thermal_gap 0.508)
			(thermal_bridge_width 0.508)
		)
		(polygon
			(pts
				(xy 150.1 179.305) (xy 147.35 179.305) (xy 147.35 72.705) (xy 145.38 72.705) (xy 145.38 58.905)
				(xy 150.100008 58.905)
			)
		)
	)
	(zone
		(net 0)
		(net_name "")
		(layers "F.Cu" "B.Cu" "In2.Cu" "In3.Cu" "In5.Cu" "In6.Cu")
		(hatch edge 0.508)
		(connect_pads
			(clearance 0)
		)
		(min_thickness 0.1)
		(filled_areas_thickness no)
		(keepout
			(tracks not_allowed)
			(vias allowed)
			(pads allowed)
			(copperpour not_allowed)
			(footprints allowed)
		)
		(placement
			(enabled no)
			(sheetname "")
		)
		(fill
			(thermal_gap 0.508)
			(thermal_bridge_width 0.508)
		)
		(polygon
			(pts
				(xy 65.33 72.705) (xy 62.85 72.705) (xy 62.85 179.305) (xy 60.1 179.305) (xy 60.1 58.905) (xy 65.33 58.905)
			)
		)
	)
	(zone
		(net 1)
		(net_name "GND")
		(layer "B.Cu")
		(hatch full 0.508)
		(priority 1)
		(connect_pads yes
			(clearance 0.2)
		)
		(min_thickness 0.1)
		(filled_areas_thickness no)
		(fill yes
			(thermal_gap 0.508)
			(thermal_bridge_width 0.508)
		)
		(polygon
			(pts
				(xy 94.7 101) (xy 93.2 101) (xy 93.2 94.6) (xy 94.7 94.6)
			)
		)
	)
	(zone
		(net 5)
		(net_name "VCC1V8")
		(layer "B.Cu")
		(hatch full 0.508)
		(priority 1)
		(connect_pads yes
			(clearance 0.2)
		)
		(min_thickness 0.1)
		(filled_areas_thickness no)
		(fill yes
			(thermal_gap 0.508)
			(thermal_bridge_width 0.508)
		)
		(polygon
			(pts
				(xy 92.6 101.4) (xy 93.3 101.4) (xy 93.3 103.3) (xy 90.9 103.3) (xy 90.9 96.3) (xy 92.6 96.3)
			)
		)
	)
	(zone
		(net 1)
		(net_name "GND")
		(layer "B.Cu")
		(hatch full 0.508)
		(priority 1)
		(connect_pads yes
			(clearance 0.2)
		)
		(min_thickness 0.1)
		(filled_areas_thickness no)
		(fill yes
			(thermal_gap 0.508)
			(thermal_bridge_width 0.508)
		)
		(polygon
			(pts
				(xy 119.6 126) (xy 115 126) (xy 115 123.2) (xy 119.6 123.2)
			)
		)
	)
	(zone
		(net 339)
		(net_name "VCC1V2")
		(layer "B.Cu")
		(hatch full 0.508)
		(priority 1)
		(connect_pads yes
			(clearance 0.2)
		)
		(min_thickness 0.1)
		(filled_areas_thickness no)
		(fill yes
			(thermal_gap 0.508)
			(thermal_bridge_width 0.508)
		)
		(polygon
			(pts
				(xy 119.6 127.8) (xy 114.9 127.8) (xy 114.9 126.5) (xy 119.6 126.5)
			)
		)
	)
	(zone
		(net 1)
		(net_name "GND")
		(layer "B.Cu")
		(hatch full 0.508)
		(priority 1)
		(connect_pads yes
			(clearance 0.2)
		)
		(min_thickness 0.1)
		(filled_areas_thickness no)
		(fill yes
			(thermal_gap 0.508)
			(thermal_bridge_width 0.508)
		)
		(polygon
			(pts
				(xy 115.9 107.2) (xy 112.8 107.2) (xy 112.8 96.6) (xy 115.9 96.6)
			)
		)
	)
	(zone
		(net 2)
		(net_name "VCC3V3")
		(layer "B.Cu")
		(hatch full 0.508)
		(priority 1)
		(connect_pads yes
			(clearance 0.2)
		)
		(min_thickness 0.1)
		(filled_areas_thickness no)
		(fill yes
			(thermal_gap 0.508)
			(thermal_bridge_width 0.508)
		)
		(polygon
			(pts
				(xy 112.3 107.2) (xy 109.8 107.2) (xy 109.8 96.7) (xy 112.3 96.7)
			)
		)
	)
	(zone
		(net 1)
		(net_name "GND")
		(layer "B.Cu")
		(hatch full 0.508)
		(priority 1)
		(connect_pads yes
			(clearance 0.2)
		)
		(min_thickness 0.1)
		(filled_areas_thickness no)
		(fill yes
			(thermal_gap 0.508)
			(thermal_bridge_width 0.508)
		)
		(polygon
			(pts
				(xy 90.3 153.9) (xy 91.5 153.9) (xy 91.5 155.9) (xy 88.4 155.9) (xy 88.4 147.2) (xy 90.3 147.2)
			)
		)
	)
	(zone
		(net 3)
		(net_name "VCC1V35")
		(layer "B.Cu")
		(hatch full 0.508)
		(priority 1)
		(connect_pads yes
			(clearance 0.2)
		)
		(min_thickness 0.1)
		(filled_areas_thickness no)
		(fill yes
			(thermal_gap 0.508)
			(thermal_bridge_width 0.508)
		)
		(polygon
			(pts
				(xy 93.9 153.5) (xy 90.8 153.5) (xy 90.8 147.3) (xy 93.9 147.3)
			)
		)
	)
	(zone
		(net 2)
		(net_name "VCC3V3")
		(layer "B.Cu")
		(hatch full 0.508)
		(priority 1)
		(connect_pads yes
			(clearance 0.2)
		)
		(min_thickness 0.1)
		(filled_areas_thickness no)
		(fill yes
			(thermal_gap 0.508)
			(thermal_bridge_width 0.508)
		)
		(polygon
			(pts
				(xy 93.6 133.3) (xy 83.4 133.3) (xy 83.4 130.8) (xy 93.6 130.8)
			)
		)
	)
	(zone
		(net 1)
		(net_name "GND")
		(layer "B.Cu")
		(hatch full 0.508)
		(priority 1)
		(connect_pads yes
			(clearance 0.2)
		)
		(min_thickness 0.1)
		(filled_areas_thickness no)
		(fill yes
			(thermal_gap 0.508)
			(thermal_bridge_width 0.508)
		)
		(polygon
			(pts
				(xy 93.6 137.5) (xy 83.3 137.5) (xy 83.3 133.8) (xy 93.6 133.8)
			)
		)
	)
	(zone
		(net 1)
		(net_name "GND")
		(layer "B.Cu")
		(hatch full 0.508)
		(priority 1)
		(connect_pads yes
			(clearance 0.2)
		)
		(min_thickness 0.1)
		(filled_areas_thickness no)
		(fill yes
			(thermal_gap 0.508)
			(thermal_bridge_width 0.508)
		)
		(polygon
			(pts
				(xy 117.4 139.7) (xy 114.7 139.7) (xy 114.7 129.3) (xy 117.4 129.3)
			)
		)
	)
	(zone
		(net 2)
		(net_name "VCC3V3")
		(layer "B.Cu")
		(hatch full 0.508)
		(priority 1)
		(connect_pads yes
			(clearance 0.2)
		)
		(min_thickness 0.1)
		(filled_areas_thickness no)
		(fill yes
			(thermal_gap 0.508)
			(thermal_bridge_width 0.508)
		)
		(polygon
			(pts
				(xy 114.2 139.7) (xy 112.1 139.7) (xy 112.1 129.3) (xy 114.2 129.3)
			)
		)
	)
	(zone
		(net 1)
		(net_name "GND")
		(layer "B.Cu")
		(hatch full 0.508)
		(priority 1)
		(connect_pads yes
			(clearance 0.2)
		)
		(min_thickness 0.1)
		(filled_areas_thickness no)
		(fill yes
			(thermal_gap 0.508)
			(thermal_bridge_width 0.508)
		)
		(polygon
			(pts
				(xy 98.7 104.6) (xy 104.8 104.6) (xy 104.819 108.947) (xy 96.619 108.947) (xy 96.6 101.5) (xy 98.7 101.5)
			)
		)
	)
	(zone
		(net 6)
		(net_name "VCC1V0")
		(layer "B.Cu")
		(hatch full 0.508)
		(priority 1)
		(connect_pads yes
			(clearance 0.2)
		)
		(min_thickness 0.1)
		(filled_areas_thickness no)
		(fill yes
			(thermal_gap 0.508)
			(thermal_bridge_width 0.508)
		)
		(polygon
			(pts
				(xy 95.979 109.097) (xy 93.779 109.097) (xy 93.8 101.5) (xy 96 101.5)
			)
		)
	)
	(zone
		(net 1)
		(net_name "GND")
		(layer "In1.Cu")
		(hatch none 0.508)
		(connect_pads yes
			(clearance 0.15)
		)
		(min_thickness 0.1)
		(filled_areas_thickness no)
		(fill yes
			(thermal_gap 0.508)
			(thermal_bridge_width 0.508)
		)
		(polygon
			(pts
				(xy 150.1 179.305) (xy 60.1 179.305) (xy 60.1 58.905) (xy 150.1 58.905)
			)
		)
	)
	(zone
		(net 3)
		(net_name "VCC1V35")
		(layer "In3.Cu")
		(hatch full 0.508)
		(priority 3)
		(connect_pads yes
			(clearance 0.2)
		)
		(min_thickness 0.1)
		(filled_areas_thickness no)
		(fill yes
			(thermal_gap 0.508)
			(thermal_bridge_width 0.508)
		)
		(polygon
			(pts
				(xy 86.542999 89.676984) (xy 78.889 89.657) (xy 78.890722 82.499557) (xy 82.359 82.497) (xy 82.369026 86.161021)
				(xy 90.529 86.197) (xy 90.479 125.287) (xy 105.695 125.255) (xy 105.7125 162.85) (xy 86.8375 162.9)
			)
		)
	)
	(zone
		(net 6)
		(net_name "VCC1V0")
		(layer "In3.Cu")
		(hatch full 0.508)
		(priority 2)
		(connect_pads yes
			(clearance 0.15)
		)
		(min_thickness 0.1)
		(filled_areas_thickness no)
		(fill yes
			(thermal_gap 0.508)
			(thermal_bridge_width 0.508)
		)
		(polygon
			(pts
				(xy 93.8 101.5) (xy 94.6 101.5) (xy 94.6 108.3) (xy 93.8 108.3) (xy 93.809206 118.678124) (xy 106.37 118.755)
				(xy 106.37 125.255) (xy 90.645 125.255) (xy 90.660478 108.56453) (xy 90.670755 86.033809) (xy 74.527246 85.980191)
				(xy 74.5 77.605) (xy 93.8 77.605)
			)
		)
	)
	(zone
		(net 59)
		(net_name "P12V_AUX")
		(layer "In3.Cu")
		(hatch full 0.508)
		(priority 1)
		(connect_pads yes
			(clearance 0.15)
		)
		(min_thickness 0.1)
		(filled_areas_thickness no)
		(fill yes
			(thermal_gap 0.508)
			(thermal_bridge_width 0.508)
		)
		(polygon
			(pts
				(xy 93.965 72.865) (xy 91.615 72.865) (xy 91.615 70.58) (xy 70.945 70.58) (xy 70.945 82.205) (xy 65.445 87.38)
				(xy 65.445 166.955) (xy 75.545 166.955) (xy 75.545 175.98) (xy 73.345 175.98) (xy 73.345 169.255)
				(xy 63.02 169.255) (xy 63.02 82.83) (xy 65.22 82.83) (xy 68.095 79.955) (xy 68.095 66.58) (xy 91.615 66.59)
				(xy 91.615 63.115) (xy 93.99 63.115)
			)
		)
	)
	(zone
		(net 2)
		(net_name "VCC3V3")
		(layer "In3.Cu")
		(hatch none 0.508)
		(connect_pads yes
			(clearance 0.15)
		)
		(min_thickness 0.1)
		(filled_areas_thickness no)
		(fill yes
			(thermal_gap 0.508)
			(thermal_bridge_width 0.508)
		)
		(polygon
			(pts
				(xy 147.37 175.955) (xy 62.92 175.93) (xy 62.895 58.905) (xy 147.37 58.905)
			)
		)
	)
	(zone
		(net 1)
		(net_name "GND")
		(layer "In4.Cu")
		(hatch full 0.508)
		(connect_pads yes
			(clearance 0.15)
		)
		(min_thickness 0.1)
		(filled_areas_thickness no)
		(fill yes
			(thermal_gap 0.508)
			(thermal_bridge_width 0.508)
		)
		(polygon
			(pts
				(xy 150.1 179.305) (xy 60.1 179.305) (xy 60.1 58.905) (xy 150.1 58.905)
			)
		)
	)
	(zone
		(net 5)
		(net_name "VCC1V8")
		(layer "In6.Cu")
		(hatch full 0.508)
		(priority 2)
		(connect_pads yes
			(clearance 0.15)
		)
		(min_thickness 0.1)
		(filled_areas_thickness no)
		(fill yes
			(thermal_gap 0.508)
			(thermal_bridge_width 0.508)
		)
		(polygon
			(pts
				(xy 93.4 118.9125) (xy 94.77 118.78) (xy 94.77 118.68) (xy 105.695 118.705) (xy 105.695 122.505)
				(xy 94.77 122.48) (xy 94.77 122.455) (xy 90.34 122.465) (xy 89.93 122.94) (xy 89.93 123.11) (xy 89.94 124.24)
				(xy 89.42 124.24) (xy 88.59 123.41) (xy 88.59 122.915) (xy 88.6 122.33375) (xy 88.6 97.26625) (xy 79.129 97.267)
				(xy 79.1035 89.7255) (xy 94.5945 89.7085) (xy 94.6 101.3) (xy 93.5 101.3)
			)
		)
	)
	(zone
		(net 339)
		(net_name "VCC1V2")
		(layer "In6.Cu")
		(hatch none 0.508)
		(priority 3)
		(connect_pads yes
			(clearance 0.1)
		)
		(min_thickness 0.1)
		(filled_areas_thickness no)
		(fill yes
			(thermal_gap 0.2)
			(thermal_bridge_width 0.2)
		)
		(polygon
			(pts
				(xy 94.999 92.177) (xy 86.299 92.177) (xy 86.299 75.397) (xy 78.669 75.397) (xy 78.669 69.947) (xy 94.999 69.947)
			)
		)
	)
	(zone
		(net 143)
		(net_name "/DDR3/DDR3_VTT")
		(layer "In6.Cu")
		(hatch full 0.508)
		(priority 1)
		(connect_pads yes
			(clearance 0.2)
		)
		(min_thickness 0.1)
		(filled_areas_thickness no)
		(fill yes
			(thermal_gap 0.508)
			(thermal_bridge_width 0.508)
		)
		(polygon
			(pts
				(xy 106.3 144.4) (xy 106.3 156.9) (xy 101 156.9) (xy 101 163) (xy 97.9 163) (xy 97.9 156.9) (xy 94.15 156.9)
				(xy 94.1 144.4)
			)
		)
	)
	(zone
		(net 4)
		(net_name "VCC5V0")
		(layer "In6.Cu")
		(hatch none 0.508)
		(priority 1)
		(connect_pads yes
			(clearance 0.15)
		)
		(min_thickness 0.1)
		(filled_areas_thickness no)
		(fill yes
			(thermal_gap 0.508)
			(thermal_bridge_width 0.508)
		)
		(polygon
			(pts
				(xy 88.37 108.33) (xy 71.645 108.33) (xy 71.609 98.087) (xy 67.419 98.107) (xy 67.429 87.997) (xy 71.645 88.0425)
				(xy 71.645 67.755) (xy 88.37 67.755)
			)
		)
	)
	(zone
		(net 2)
		(net_name "VCC3V3")
		(layer "In6.Cu")
		(hatch none 0.508)
		(connect_pads yes
			(clearance 0.15)
		)
		(min_thickness 0.1)
		(filled_areas_thickness no)
		(fill yes
			(thermal_gap 0.508)
			(thermal_bridge_width 0.508)
		)
		(polygon
			(pts
				(xy 147.37 175.93) (xy 62.92 175.905) (xy 62.895 58.88) (xy 147.37 58.88)
			)
		)
	)
	(zone
		(net 339)
		(net_name "VCC1V2")
		(layer "In6.Cu")
		(hatch full 0.508)
		(priority 3)
		(connect_pads yes
			(clearance 0.15)
		)
		(min_thickness 0.1)
		(filled_areas_thickness no)
		(fill yes
			(thermal_gap 0.508)
			(thermal_bridge_width 0.508)
		)
		(polygon
			(pts
				(xy 108.22 111.779977) (xy 108.245 111.78) (xy 108.245 124.8) (xy 118.7 124.8) (xy 118.7 127.7)
				(xy 90.395 127.705) (xy 90.395 121.155) (xy 93.195 121.155) (xy 93.195 122.58) (xy 105.645 122.58)
				(xy 105.645 118.705) (xy 94.745 118.6925) (xy 94.745 87.555) (xy 108.22 87.53)
			)
		)
	)
)
